# ODB++ job r4006-b0001-02_r01_odb.tgz
### matrix/matrix

STEP {
    COL=1
    NAME=PCB
}


LAYER {
    ROW=1
    CONTEXT=BOARD
    TYPE=COMPONENT
    NAME=COMP_+_TOP
    POLARITY=POSITIVE
    START_NAME=
    END_NAME=
    OLD_NAME=
    ADD_TYPE=
    COLOR=0
}

LAYER {
    ROW=2
    CONTEXT=BOARD
    TYPE=SILK_SCREEN
    NAME=SST
    POLARITY=POSITIVE
    START_NAME=
    END_NAME=
    OLD_NAME=
    ADD_TYPE=
    COLOR=608585
}

LAYER {
    ROW=3
    CONTEXT=BOARD
    TYPE=SOLDER_PASTE
    NAME=SPT
    POLARITY=POSITIVE
    START_NAME=
    END_NAME=
    OLD_NAME=
    ADD_TYPE=
    COLOR=608585
}

LAYER {
    ROW=4
    CONTEXT=BOARD
    TYPE=SOLDER_MASK
    NAME=SMT
    POLARITY=POSITIVE
    START_NAME=
    END_NAME=
    OLD_NAME=
    ADD_TYPE=
    COLOR=608585
}

LAYER {
    ROW=5
    CONTEXT=BOARD
    TYPE=SIGNAL
    NAME=TOP
    POLARITY=POSITIVE
    START_NAME=
    END_NAME=
    OLD_NAME=
    ADD_TYPE=
    COLOR=608585
}

LAYER {
    ROW=6
    CONTEXT=BOARD
    TYPE=POWER_GROUND
    NAME=L02_GND1
    POLARITY=NEGATIVE
    START_NAME=
    END_NAME=
    OLD_NAME=
    ADD_TYPE=
    COLOR=608585
}

LAYER {
    ROW=7
    CONTEXT=BOARD
    TYPE=SIGNAL
    NAME=L03_SIG1
    POLARITY=POSITIVE
    START_NAME=
    END_NAME=
    OLD_NAME=
    ADD_TYPE=
    COLOR=608585
}

LAYER {
    ROW=8
    CONTEXT=BOARD
    TYPE=POWER_GROUND
    NAME=L04_GND2
    POLARITY=NEGATIVE
    START_NAME=
    END_NAME=
    OLD_NAME=
    ADD_TYPE=
    COLOR=608585
}

LAYER {
    ROW=9
    CONTEXT=BOARD
    TYPE=POWER_GROUND
    NAME=L05_VCC1
    POLARITY=NEGATIVE
    START_NAME=
    END_NAME=
    OLD_NAME=
    ADD_TYPE=
    COLOR=608585
}

LAYER {
    ROW=10
    CONTEXT=BOARD
    TYPE=POWER_GROUND
    NAME=L06_VCC2
    POLARITY=NEGATIVE
    START_NAME=
    END_NAME=
    OLD_NAME=
    ADD_TYPE=
    COLOR=608585
}

LAYER {
    ROW=11
    CONTEXT=BOARD
    TYPE=POWER_GROUND
    NAME=L07_GND3
    POLARITY=NEGATIVE
    START_NAME=
    END_NAME=
    OLD_NAME=
    ADD_TYPE=
    COLOR=608585
}

LAYER {
    ROW=12
    CONTEXT=BOARD
    TYPE=SIGNAL
    NAME=L08_SIG2
    POLARITY=POSITIVE
    START_NAME=
    END_NAME=
    OLD_NAME=
    ADD_TYPE=
    COLOR=608585
}

LAYER {
    ROW=13
    CONTEXT=BOARD
    TYPE=POWER_GROUND
    NAME=L09_GND4
    POLARITY=NEGATIVE
    START_NAME=
    END_NAME=
    OLD_NAME=
    ADD_TYPE=
    COLOR=608585
}

LAYER {
    ROW=14
    CONTEXT=BOARD
    TYPE=SIGNAL
    NAME=BOTTOM
    POLARITY=POSITIVE
    START_NAME=
    END_NAME=
    OLD_NAME=
    ADD_TYPE=
    COLOR=608585
}

LAYER {
    ROW=15
    CONTEXT=BOARD
    TYPE=SOLDER_MASK
    NAME=SMB
    POLARITY=POSITIVE
    START_NAME=
    END_NAME=
    OLD_NAME=
    ADD_TYPE=
    COLOR=608585
}

LAYER {
    ROW=16
    CONTEXT=BOARD
    TYPE=SOLDER_PASTE
    NAME=SPB
    POLARITY=POSITIVE
    START_NAME=
    END_NAME=
    OLD_NAME=
    ADD_TYPE=
    COLOR=608585
}

LAYER {
    ROW=17
    CONTEXT=BOARD
    TYPE=SILK_SCREEN
    NAME=SSB
    POLARITY=POSITIVE
    START_NAME=
    END_NAME=
    OLD_NAME=
    ADD_TYPE=
    COLOR=608585
}

LAYER {
    ROW=18
    CONTEXT=BOARD
    TYPE=ROUT
    NAME=ROUT
    POLARITY=POSITIVE
    START_NAME=
    END_NAME=
    OLD_NAME=
    ADD_TYPE=
    COLOR=608585
}

LAYER {
    ROW=19
    CONTEXT=BOARD
    TYPE=COMPONENT
    NAME=COMP_+_BOT
    POLARITY=POSITIVE
    START_NAME=
    END_NAME=
    OLD_NAME=
    ADD_TYPE=
    COLOR=0
}

LAYER {
    ROW=20
    CONTEXT=MISC
    TYPE=DOCUMENT
    NAME=ASM
    POLARITY=POSITIVE
    START_NAME=
    END_NAME=
    OLD_NAME=
    ADD_TYPE=
    COLOR=608585
}

LAYER {
    ROW=21
    CONTEXT=MISC
    TYPE=DOCUMENT
    NAME=FAB
    POLARITY=POSITIVE
    START_NAME=
    END_NAME=
    OLD_NAME=
    ADD_TYPE=
    COLOR=608585
}

LAYER {
    ROW=22
    CONTEXT=MISC
    TYPE=DOCUMENT
    NAME=BD_1-7
    POLARITY=POSITIVE
    START_NAME=
    END_NAME=
    OLD_NAME=
    ADD_TYPE=
    COLOR=608585
}

LAYER {
    ROW=23
    CONTEXT=MISC
    TYPE=DOCUMENT
    NAME=BD_10-9
    POLARITY=POSITIVE
    START_NAME=
    END_NAME=
    OLD_NAME=
    ADD_TYPE=
    COLOR=608585
}

LAYER {
    ROW=24
    CONTEXT=MISC
    TYPE=DOCUMENT
    NAME=OTL
    POLARITY=POSITIVE
    START_NAME=
    END_NAME=
    OLD_NAME=
    ADD_TYPE=
    COLOR=608585
}

LAYER {
    ROW=25
    CONTEXT=MISC
    TYPE=DOCUMENT
    NAME=TAS
    POLARITY=POSITIVE
    START_NAME=
    END_NAME=
    OLD_NAME=
    ADD_TYPE=
    COLOR=608585
}

LAYER {
    ROW=26
    CONTEXT=MISC
    TYPE=DOCUMENT
    NAME=BAS
    POLARITY=POSITIVE
    START_NAME=
    END_NAME=
    OLD_NAME=
    ADD_TYPE=
    COLOR=608585
}

LAYER {
    ROW=27
    CONTEXT=MISC
    TYPE=DOCUMENT
    NAME=SQA_AREAS
    POLARITY=POSITIVE
    START_NAME=
    END_NAME=
    OLD_NAME=
    ADD_TYPE=
    COLOR=608585
}

LAYER {
    ROW=28
    CONTEXT=MISC
    TYPE=DOCUMENT
    NAME=DRC_ROUTE
    POLARITY=POSITIVE
    START_NAME=
    END_NAME=
    OLD_NAME=
    ADD_TYPE=
    COLOR=608585
}

LAYER {
    ROW=29
    CONTEXT=MISC
    TYPE=DOCUMENT
    NAME=DRC_COMP_TOP
    POLARITY=POSITIVE
    START_NAME=
    END_NAME=
    OLD_NAME=
    ADD_TYPE=
    COLOR=608585
}

LAYER {
    ROW=30
    CONTEXT=MISC
    TYPE=DOCUMENT
    NAME=DRC_COMP_BOTTOM
    POLARITY=POSITIVE
    START_NAME=
    END_NAME=
    OLD_NAME=
    ADD_TYPE=
    COLOR=608585
}

LAYER {
    ROW=31
    CONTEXT=MISC
    TYPE=DOCUMENT
    NAME=DRC_TP_TOP
    POLARITY=POSITIVE
    START_NAME=
    END_NAME=
    OLD_NAME=
    ADD_TYPE=
    COLOR=608585
}

LAYER {
    ROW=32
    CONTEXT=MISC
    TYPE=DOCUMENT
    NAME=DRC_TP_BOTTOM
    POLARITY=POSITIVE
    START_NAME=
    END_NAME=
    OLD_NAME=
    ADD_TYPE=
    COLOR=608585
}

LAYER {
    ROW=33
    CONTEXT=BOARD
    TYPE=DRILL
    NAME=DRILL
    POLARITY=POSITIVE
    START_NAME=
    END_NAME=
    OLD_NAME=
    ADD_TYPE=
    COLOR=608585
}

LAYER {
    ROW=34
    CONTEXT=BOARD
    TYPE=DRILL
    NAME=BACKDRILL_L09_GND4_BOTTOM
    POLARITY=POSITIVE
    START_NAME=L09_GND4
    END_NAME=BOTTOM
    OLD_NAME=
    ADD_TYPE=
    COLOR=608585
}

LAYER {
    ROW=35
    CONTEXT=BOARD
    TYPE=DRILL
    NAME=BACKDRILL_TOP_L07_GND3
    POLARITY=POSITIVE
    START_NAME=TOP
    END_NAME=L07_GND3
    OLD_NAME=
    ADD_TYPE=
    COLOR=608585
}

### misc/info
JOB_NAME=r4006-b0001-02_r01_odb
ODB_VERSION_MAJOR=7
ODB_VERSION_MINOR=0
ODB_SOURCE=Cadence Allegro extract file
CREATION_DATE=20220225.181531
SAVE_DATE=20220225.181531
SAVE_APP=ODB++ Viewer 9.1.1
SAVE_USER=

### misc/attrlist
.customer = 
.design_center = 
.comment = 
.data_source = 
.technology = 
.global_camtek_aoiset = 
.drc_route_keepin_lyr = drc_route
.drc_comp_keepin_lyr = drc_comp
.drc_tp_keepin_lyr = drc_tp
.drc_route_keepout_lyr = drc_route
.drc_comp_keepout_lyr = drc_comp
.drc_pad_keepout_lyr = drc_route
.drc_via_keepout_lyr = drc_route
.drc_trace_keepout_lyr = drc_route
.drc_plane_keepout_lyr = drc_route
.drc_comp_height_lyr = drc_comp
.drc_tp_keepout_lyr = drc_tp
.variant_list = 
.primary_side = top
.design_origin_x = 0
.design_origin_y = 0
.board_thickness = 0.0618

### steps/pcb/stephdr
X_DATUM=0
Y_DATUM=0
X_ORIGIN=0
Y_ORIGIN=0

TOP_ACTIVE=0
BOTTOM_ACTIVE=0
RIGHT_ACTIVE=0
LEFT_ACTIVE=0
ONLINE_DRC_NAME=
ONLINE_DRC_MODE=DISABLED
ONLINE_DRC_STAT=RED
ONLINE_DRC_TIME=0
ONLINE_DRC_BEEP_VOL=2
ONLINE_DRC_BEEP_TONE=500
ONLINE_NET_MODE=DISABLED
ONLINE_NET_STAT=RED
ONLINE_NET_TIME=0
ONLINE_NET_BEEP_VOL=2
ONLINE_NET_BEEP_TONE=1000
AFFECTING_BOM=
AFFECTING_BOM_CHANGED=0

### steps/pcb/attrlist
.out_drill_full = no
.out_drill_optional = no
.out_rout_optional = no
.array_with_rotation = no
.eco = 
.design_center = 
.comment = 
.data_source = 
.out_name = 
.assembly_proc_top = 
.assembly_proc_bottom = 
.all_eda_layers = 
.fab_drc = 
.hdi_drc = 
.merge_processes = 
.neutralization_info = 
.neutralization_ss_layers = 
.current_variant = 
.smt_direction_top = left2right
.smt_direction_bottom = right2left
.fs_direction_top = left2right
.fs_direction_bottom = right2left
.axi_direction = left2right
.viacap_layer = none
.out_drill_order = 0
.out_rout_order = 0

### steps/pcb/layers/backdrill_l09_gnd4_bottom/attrlist
.out_mirror = no
.lpol_done = no
.cu_base = no
.comment = 
.inp_file = 
.eda_layers = 
.layer_class = 
.ecmp_layer_tech = none
.out_angle = 0.0
.out_polarity = positive
.layer_hdi_type = core
.hdi_assembly_tech = none
.drill_layer_direction = top2bottom
.out_x_scale = 1
.out_y_scale = 1
.out_comp = 0
.et_adjacency = 20
.layer_dielectric = 0.0001
.copper_weight = 1

### steps/pcb/layers/backdrill_top_l07_gnd3/attrlist
.out_mirror = no
.lpol_done = no
.cu_base = no
.comment = 
.inp_file = 
.eda_layers = 
.layer_class = 
.ecmp_layer_tech = none
.out_angle = 0.0
.out_polarity = positive
.layer_hdi_type = core
.hdi_assembly_tech = none
.drill_layer_direction = top2bottom
.out_x_scale = 1
.out_y_scale = 1
.out_comp = 0
.et_adjacency = 20
.layer_dielectric = 0.0001
.copper_weight = 1

### steps/pcb/layers/bottom/attrlist
.out_mirror = no
.lpol_done = no
.cu_base = no
.comment = 
.inp_file = 
.eda_layers = "ETCH:BOTTOM"&"PIN:BOTTOM"&"VIA CLASS:BOTTOM"&"MANUFACTURING:BOTTOM"&"MANUFACTURING:CELESTICA_LEGEND"
.layer_class = 
.ecmp_layer_tech = none
.out_angle = 0.0
.out_polarity = positive
.layer_hdi_type = core
.hdi_assembly_tech = none
.drill_layer_direction = top2bottom
.out_x_scale = 1
.out_y_scale = 1
.out_comp = 0
.et_adjacency = 20
.layer_dielectric = 0
.copper_weight = 1

### steps/pcb/layers/comp_+_bot/attrlist
.out_mirror = no
.lpol_done = no
.cu_base = no
.comment = 
.inp_file = 
.eda_layers = "package_geometry:assembly_bottom"
.layer_class = 
.ecmp_layer_tech = none
.out_angle = 0.0
.out_polarity = positive
.layer_hdi_type = core
.hdi_assembly_tech = none
.drill_layer_direction = top2bottom
.out_x_scale = 1
.out_y_scale = 1
.out_comp = 0
.et_adjacency = 20
.layer_dielectric = 0.0001
.copper_weight = 1

### steps/pcb/layers/comp_+_top/attrlist
.out_mirror = no
.lpol_done = no
.cu_base = no
.comment = 
.inp_file = 
.eda_layers = "package_geometry:assembly_top"
.layer_class = 
.ecmp_layer_tech = none
.out_angle = 0.0
.out_polarity = positive
.layer_hdi_type = core
.hdi_assembly_tech = none
.drill_layer_direction = top2bottom
.out_x_scale = 1
.out_y_scale = 1
.out_comp = 0
.et_adjacency = 20
.layer_dielectric = 0.0001
.copper_weight = 1

### steps/pcb/layers/drill/attrlist
.out_mirror = no
.lpol_done = no
.cu_base = no
.comment = 
.inp_file = 
.eda_layers = 
.layer_class = 
.ecmp_layer_tech = none
.out_angle = 0.0
.out_polarity = positive
.layer_hdi_type = core
.hdi_assembly_tech = none
.drill_layer_direction = top2bottom
.out_x_scale = 1
.out_y_scale = 1
.out_comp = 0
.et_adjacency = 20
.layer_dielectric = 0.0001
.copper_weight = 1

### steps/pcb/layers/l02_gnd1/attrlist
.out_mirror = no
.lpol_done = no
.cu_base = no
.comment = 
.inp_file = 
.eda_layers = "ETCH:L02_GND1"&"PIN:L02_GND1"&"VIA CLASS:L02_GND1"&"MANUFACTURING:L02_GND1"&"MANUFACTURING:CELESTICA_LEGEND"
.layer_class = 
.ecmp_layer_tech = none
.out_angle = 0.0
.out_polarity = positive
.layer_hdi_type = core
.hdi_assembly_tech = none
.drill_layer_direction = top2bottom
.out_x_scale = 1
.out_y_scale = 1
.out_comp = 0
.et_adjacency = 20
.layer_dielectric = 0.005
.copper_weight = 1

### steps/pcb/layers/l03_sig1/attrlist
.out_mirror = no
.lpol_done = no
.cu_base = no
.comment = 
.inp_file = 
.eda_layers = "ETCH:L03_SIG1"&"PIN:L03_SIG1"&"VIA CLASS:L03_SIG1"&"MANUFACTURING:L03_SIG1"&"MANUFACTURING:CELESTICA_LEGEND"
.layer_class = 
.ecmp_layer_tech = none
.out_angle = 0.0
.out_polarity = positive
.layer_hdi_type = core
.hdi_assembly_tech = none
.drill_layer_direction = top2bottom
.out_x_scale = 1
.out_y_scale = 1
.out_comp = 0
.et_adjacency = 20
.layer_dielectric = 0.005
.copper_weight = 1

### steps/pcb/layers/l04_gnd2/attrlist
.out_mirror = no
.lpol_done = no
.cu_base = no
.comment = 
.inp_file = 
.eda_layers = "ETCH:L04_GND2"&"PIN:L04_GND2"&"VIA CLASS:L04_GND2"&"MANUFACTURING:L04_GND2"&"MANUFACTURING:CELESTICA_LEGEND"
.layer_class = 
.ecmp_layer_tech = none
.out_angle = 0.0
.out_polarity = positive
.layer_hdi_type = core
.hdi_assembly_tech = none
.drill_layer_direction = top2bottom
.out_x_scale = 1
.out_y_scale = 1
.out_comp = 0
.et_adjacency = 20
.layer_dielectric = 0.005
.copper_weight = 1

### steps/pcb/layers/l05_vcc1/attrlist
.out_mirror = no
.lpol_done = no
.cu_base = no
.comment = 
.inp_file = 
.eda_layers = "ETCH:L05_VCC1"&"PIN:L05_VCC1"&"VIA CLASS:L05_VCC1"&"MANUFACTURING:L05_VCC1"&"MANUFACTURING:CELESTICA_LEGEND"
.layer_class = 
.ecmp_layer_tech = none
.out_angle = 0.0
.out_polarity = positive
.layer_hdi_type = core
.hdi_assembly_tech = none
.drill_layer_direction = top2bottom
.out_x_scale = 1
.out_y_scale = 1
.out_comp = 0
.et_adjacency = 20
.layer_dielectric = 0.014
.copper_weight = 1

### steps/pcb/layers/l06_vcc2/attrlist
.out_mirror = no
.lpol_done = no
.cu_base = no
.comment = 
.inp_file = 
.eda_layers = "ETCH:L06_VCC2"&"PIN:L06_VCC2"&"VIA CLASS:L06_VCC2"&"MANUFACTURING:L06_VCC2"&"MANUFACTURING:CELESTICA_LEGEND"
.layer_class = 
.ecmp_layer_tech = none
.out_angle = 0.0
.out_polarity = positive
.layer_hdi_type = core
.hdi_assembly_tech = none
.drill_layer_direction = top2bottom
.out_x_scale = 1
.out_y_scale = 1
.out_comp = 0
.et_adjacency = 20
.layer_dielectric = 0.005
.copper_weight = 1

### steps/pcb/layers/l07_gnd3/attrlist
.out_mirror = no
.lpol_done = no
.cu_base = no
.comment = 
.inp_file = 
.eda_layers = "ETCH:L07_GND3"&"PIN:L07_GND3"&"VIA CLASS:L07_GND3"&"MANUFACTURING:L07_GND3"&"MANUFACTURING:CELESTICA_LEGEND"
.layer_class = 
.ecmp_layer_tech = none
.out_angle = 0.0
.out_polarity = positive
.layer_hdi_type = core
.hdi_assembly_tech = none
.drill_layer_direction = top2bottom
.out_x_scale = 1
.out_y_scale = 1
.out_comp = 0
.et_adjacency = 20
.layer_dielectric = 0.005
.copper_weight = 1

### steps/pcb/layers/l08_sig2/attrlist
.out_mirror = no
.lpol_done = no
.cu_base = no
.comment = 
.inp_file = 
.eda_layers = "ETCH:L08_SIG2"&"PIN:L08_SIG2"&"VIA CLASS:L08_SIG2"&"MANUFACTURING:L08_SIG2"&"MANUFACTURING:CELESTICA_LEGEND"
.layer_class = 
.ecmp_layer_tech = none
.out_angle = 0.0
.out_polarity = positive
.layer_hdi_type = core
.hdi_assembly_tech = none
.drill_layer_direction = top2bottom
.out_x_scale = 1
.out_y_scale = 1
.out_comp = 0
.et_adjacency = 20
.layer_dielectric = 0.005
.copper_weight = 1

### steps/pcb/layers/l09_gnd4/attrlist
.out_mirror = no
.lpol_done = no
.cu_base = no
.comment = 
.inp_file = 
.eda_layers = "ETCH:L09_GND4"&"PIN:L09_GND4"&"VIA CLASS:L09_GND4"&"MANUFACTURING:L09_GND4"&"MANUFACTURING:CELESTICA_LEGEND"
.layer_class = 
.ecmp_layer_tech = none
.out_angle = 0.0
.out_polarity = positive
.layer_hdi_type = core
.hdi_assembly_tech = none
.drill_layer_direction = top2bottom
.out_x_scale = 1
.out_y_scale = 1
.out_comp = 0
.et_adjacency = 20
.layer_dielectric = 0.003
.copper_weight = 1

### steps/pcb/layers/rout/attrlist
.out_mirror = no
.lpol_done = no
.cu_base = no
.comment = 
.inp_file = 
.eda_layers = "BOARD GEOMETRY:OUTLINE"
.layer_class = 
.ecmp_layer_tech = none
.out_angle = 0.0
.out_polarity = positive
.layer_hdi_type = core
.hdi_assembly_tech = none
.drill_layer_direction = top2bottom
.out_x_scale = 1
.out_y_scale = 1
.out_comp = 0
.et_adjacency = 20
.layer_dielectric = 0
.copper_weight = 1

### steps/pcb/layers/smb/attrlist
.out_mirror = no
.lpol_done = no
.cu_base = no
.comment = 
.inp_file = 
.eda_layers = "PACKAGE GEOMETRY:SOLDERMASK_BOTTOM"&"BOARD GEOMETRY:SOLDERMASK_BOTTOM"&"BOARD GEOMETRY:OUTLINE"&"PIN:SOLDERMASK_BOTTOM"&"VIA CLASS:SOLDERMASK_BOTTOM"&"MANUFACTURING:CELESTICA_LEGEND"
.layer_class = 
.ecmp_layer_tech = none
.out_angle = 0.0
.out_polarity = positive
.layer_hdi_type = core
.hdi_assembly_tech = none
.drill_layer_direction = top2bottom
.out_x_scale = 1
.out_y_scale = 1
.out_comp = 0
.et_adjacency = 20
.layer_dielectric = 0
.copper_weight = 1

### steps/pcb/layers/smt/attrlist
.out_mirror = no
.lpol_done = no
.cu_base = no
.comment = 
.inp_file = 
.eda_layers = "PACKAGE GEOMETRY:SOLDERMASK_TOP"&"BOARD GEOMETRY:SOLDERMASK_TOP"&"BOARD GEOMETRY:OUTLINE"&"PIN:SOLDERMASK_TOP"&"VIA CLASS:SOLDERMASK_TOP"&"MANUFACTURING:CELESTICA_LEGEND"
.layer_class = 
.ecmp_layer_tech = none
.out_angle = 0.0
.out_polarity = positive
.layer_hdi_type = core
.hdi_assembly_tech = none
.drill_layer_direction = top2bottom
.out_x_scale = 1
.out_y_scale = 1
.out_comp = 0
.et_adjacency = 20
.layer_dielectric = 0
.copper_weight = 1

### steps/pcb/layers/spb/attrlist
.out_mirror = no
.lpol_done = no
.cu_base = no
.comment = 
.inp_file = 
.eda_layers = "PACKAGE GEOMETRY:SOLDERPASTE_BOTTOM"&"PACKAGE GEOMETRY:PASTEMASK_BOTTOM"&"PIN:PASTEMASK_BOTTOM"&"VIA CLASS:PASTEMASK_BOTTOM"&"MANUFACTURING:CELESTICA_LEGEND"&"MANUFACTURING:SOLDERPASTE_BOTTOM"
.layer_class = 
.ecmp_layer_tech = none
.out_angle = 0.0
.out_polarity = positive
.layer_hdi_type = core
.hdi_assembly_tech = none
.drill_layer_direction = top2bottom
.out_x_scale = 1
.out_y_scale = 1
.out_comp = 0
.et_adjacency = 20
.layer_dielectric = 0
.copper_weight = 1

### steps/pcb/layers/spt/attrlist
.out_mirror = no
.lpol_done = no
.cu_base = no
.comment = 
.inp_file = 
.eda_layers = "PACKAGE GEOMETRY:SOLDERPASTE_TOP"&"PACKAGE GEOMETRY:PASTEMASK_TOP"&"PIN:PASTEMASK_TOP"&"VIA CLASS:PASTEMASK_TOP"&"MANUFACTURING:CELESTICA_LEGEND"&"MANUFACTURING:SOLDERPASTE_TOP"
.layer_class = 
.ecmp_layer_tech = none
.out_angle = 0.0
.out_polarity = positive
.layer_hdi_type = core
.hdi_assembly_tech = none
.drill_layer_direction = top2bottom
.out_x_scale = 1
.out_y_scale = 1
.out_comp = 0
.et_adjacency = 20
.layer_dielectric = 0
.copper_weight = 1

### steps/pcb/layers/ssb/attrlist
.out_mirror = no
.lpol_done = no
.cu_base = no
.comment = 
.inp_file = 
.eda_layers = "PACKAGE GEOMETRY:SILKSCREEN_BOTTOM"&"BOARD GEOMETRY:SILKSCREEN_BOTTOM"&"REF DES:SILKSCREEN_BOTTOM"&"MANUFACTURING:CELESTICA_LEGEND"
.layer_class = 
.ecmp_layer_tech = none
.out_angle = 0.0
.out_polarity = positive
.layer_hdi_type = core
.hdi_assembly_tech = none
.drill_layer_direction = top2bottom
.out_x_scale = 1
.out_y_scale = 1
.out_comp = 0
.et_adjacency = 20
.layer_dielectric = 0
.copper_weight = 1

### steps/pcb/layers/sst/attrlist
.out_mirror = no
.lpol_done = no
.cu_base = no
.comment = 
.inp_file = 
.eda_layers = "PACKAGE GEOMETRY:SILKSCREEN_TOP"&"BOARD GEOMETRY:SILKSCREEN_TOP"&"REF DES:SILKSCREEN_TOP"&"MANUFACTURING:CELESTICA_LEGEND"
.layer_class = 
.ecmp_layer_tech = none
.out_angle = 0.0
.out_polarity = positive
.layer_hdi_type = core
.hdi_assembly_tech = none
.drill_layer_direction = top2bottom
.out_x_scale = 1
.out_y_scale = 1
.out_comp = 0
.et_adjacency = 20
.layer_dielectric = 0
.copper_weight = 1

### steps/pcb/layers/top/attrlist
.out_mirror = no
.lpol_done = no
.cu_base = no
.comment = 
.inp_file = 
.eda_layers = "ETCH:TOP"&"PIN:TOP"&"VIA CLASS:TOP"&"MANUFACTURING:TOP"&"MANUFACTURING:CELESTICA_LEGEND"
.layer_class = 
.ecmp_layer_tech = none
.out_angle = 0.0
.out_polarity = positive
.layer_hdi_type = core
.hdi_assembly_tech = none
.drill_layer_direction = top2bottom
.out_x_scale = 1
.out_y_scale = 1
.out_comp = 0
.et_adjacency = 20
.layer_dielectric = 0.003
.copper_weight = 1

### steps/pcb/profile
#
#Num Features
#
F 1

#
#Units
#
U INCH

#
#Layer features
#
S P 0
OB 6.58071003937 2.84646003937 I
OS 6.57211003937 2.84646003937
OC 6.552430019685 2.826769980315 6.57211496063 2.826775098425 N
OS 6.552430019685 2.414369980315
OC 6.57211003937 2.39468996063 6.57211003937 2.414369980315 N
OS 6.58071003937 2.39468996063
OC 6.60038996063 2.375 6.580705019685 2.375005019685 Y
OS 6.60038996063 0.54133996063
OC 6.561019980315 0.501969980315 6.561019980315 0.54133996063 Y
OS 3.161419980315 0.501969980315
OC 3.12205 0.4626 3.161419980315 0.4626 N
OS 3.12205 0.01968996063
OS 3.10236003937 0
OS 2.30708996063 0
OS 2.2874 0.01968996063
OS 2.2874 0.29331003937
OC 2.2126 0.29331003937 2.25 0.29331003937 N
OS 2.2126 0.01968996063
OS 2.19291003937 0
OS 1.79133996063 0
OS 1.77165 0.01968996063
OS 1.77165 0.430119980315
OC 1.62795 0.430119980315 1.6998 0.430119980315 N
OS 1.62795 0.21653996063
OC 1.588580019685 0.177169980315 1.588580019685 0.21653996063 Y
OS 1.35236003937 0.177169980315
OC 1.31298996063 0.21653996063 1.352359940945 0.21653996063 Y
OS 1.31298996063 0.4626
OC 1.273619980315 0.501969980315 1.273619980315 0.4626 N
OS 0.629919980315 0.501969980315
OC 0.59055 0.4626 0.629919980315 0.4626 N
OS 0.59055 0.21653996063
OC 0.551180019685 0.177169980315 0.551180019685 0.21653996063 Y
OS 0.039369980315 0.177169980315
OC 0 0.21653996063 0.039369980315 0.21653996063 Y
OS 0 4.33661003937
OC 0.039369980315 4.375980019685 0.039369980315 4.33661003937 Y
OS 6.561019980315 4.375980019685
OC 6.60038996063 4.33661003937 6.561019980315 4.33661003937 Y
OS 6.60038996063 2.86613996063
OC 6.58071003937 2.84646003937 6.58071003937 2.86613996063 Y
OE
SE

### steps/pcb/eda/data
# 25 Feb 2022 06:15 PM
#
HDR Cadence Allegro extract file
LYR drill backdrill_l09_gnd4_bottom backdrill_top_l07_gnd3 top smt spt smb spb bottom l03_sig1 l08_sig2 l02_gnd1 l04_gnd2 l05_vcc1 l06_vcc2 l07_gnd3 l09_gnd4 
#
#
#Net attribute names
#
#@0 .critical_net
#@1 .diff_pair
#@2 .electrical_class
#@3 .testpoint_count
#
#
#Net attribute text strings
#
#&0 FT_USB
#&1 CONN_MICRO_USB
#&2 PCIE_REFCLK
#&3 OSC_200M_CLK
#&4 OSC_125M_CLK
#&5 FPGA_OUT_MAC_PPS_IN1
#&6 FPGA_OUT_MAC_PPS_IN0
#&7 FPGA_IN_MAC_PPS_OUT
#&8 MAC_USB
#&9 CPU-RX-PCIE-MGT3-TX
#&10 CPU_RX_PCIE_MGT3_TX
#&11 CPU-RX-PCIE-MGT2-TX
#&12 CPU_RX_PCIE_MGT2_TX
#&13 CPU-RX-PCIE-MGT1-TX
#&14 CPU_RX_PCIE_MGT1_TX
#&15 CPU-RX-PCIE-MGT0-TX
#&16 CPU_RX_PCIE_MGT0_TX
#&17 CPU-TX-PCIE-MGT-3-RX
#&18 CPU_TX_PCIE_MGT_3_RX
#&19 CPU-TX-PCIE-MGT-2-RX
#&20 CPU_TX_PCIE_MGT_2_RX
#&21 CPU-TX-PCIE-MGT-1-RX
#&22 CPU_TX_PCIE_MGT_1_RX
#&23 CPU-TX-PCIE-MGT-0-RX
#&24 CPU_TX_PCIE_MGT_0_RX
#
# NET 0
NET $NONE$ 
SNT TOP T 2 0
FID C 4 4006
FID C 5 1923
FID C 3 8782
SNT TOP T 3 0
FID C 4 4005
FID C 5 1922
FID C 3 8781
SNT TOP T 13 35
FID C 4 4008
FID C 5 1925
FID C 3 8784
SNT TOP T 13 39
FID C 4 4021
FID C 5 1938
FID C 3 8797
SNT TOP T 13 40
FID C 4 4020
FID C 5 1937
FID C 3 8796
SNT TOP T 13 42
FID C 4 4019
FID C 5 1936
FID C 3 8795
SNT TOP T 13 43
FID C 4 4018
FID C 5 1935
FID C 3 8794
SNT TOP T 13 44
FID C 4 4017
FID C 5 1934
FID C 3 8793
SNT TOP T 13 45
FID C 4 4016
FID C 5 1933
FID C 3 8792
SNT TOP T 13 52
FID C 4 4015
FID C 5 1932
FID C 3 8791
SNT TOP T 13 53
FID C 4 4014
FID C 5 1931
FID C 3 8790
SNT TOP T 13 54
FID C 4 4013
FID C 5 1930
FID C 3 8789
SNT TOP T 13 56
FID C 4 4012
FID C 5 1929
FID C 3 8788
SNT TOP T 13 57
FID C 4 4011
FID C 5 1928
FID C 3 8787
SNT TOP T 13 58
FID C 4 4010
FID C 5 1927
FID C 3 8786
SNT TOP T 13 59
FID C 4 4009
FID C 5 1926
FID C 3 8785
SNT TOP T 115 7
FID C 4 4007
FID C 5 1924
FID C 3 8783
SNT TOP T 116 7
FID C 4 3984
FID C 5 1901
FID C 3 8760
SNT TOP T 117 7
FID C 4 3983
FID C 5 1900
FID C 3 8759
SNT TOP T 118 7
FID C 4 3985
FID C 5 1902
FID C 3 8761
SNT TOP T 120 25
FID C 4 4004
FID C 5 1921
FID C 3 8780
SNT TOP T 120 26
FID C 4 4003
FID C 5 1920
FID C 3 8779
SNT TOP T 120 27
FID C 4 4002
FID C 5 1919
FID C 3 8778
SNT TOP T 121 0
FID H 0 84
FID C 4 4072
FID C 6 3158
FID C 3 9181
FID C 8 7051
FID L 11 1574
FID L 12 1574
FID L 13 2351
FID L 14 2350
FID L 15 1574
FID L 16 1574
SNT TOP T 122 0
FID H 0 82
FID C 4 4073
FID C 6 3159
FID C 3 9182
FID C 8 7052
FID L 11 1575
FID L 12 1575
FID L 13 2352
FID L 14 2351
FID L 15 1575
FID L 16 1575
SNT TOP T 123 0
FID H 0 81
FID C 4 4074
FID C 6 3160
FID C 3 9183
FID C 8 7053
FID L 11 1576
FID L 12 1576
FID L 13 2353
FID L 14 2352
FID L 15 1576
FID L 16 1576
SNT TOP T 124 0
FID H 0 83
FID C 4 4075
FID C 6 3161
FID C 3 9184
FID C 8 7054
FID L 11 1577
FID L 12 1577
FID L 13 2354
FID L 14 2353
FID L 15 1577
FID L 16 1577
SNT TOP T 129 8
FID H 0 77
FID C 4 4076
FID C 6 3162
FID C 3 9185
FID C 8 7055
FID L 11 1578
FID L 12 1578
FID L 13 2355
FID L 14 2354
FID L 15 1578
FID L 16 1578
SNT TOP T 130 8
FID H 0 93
FID C 4 4077
FID C 6 3163
FID C 3 9186
FID C 8 7056
FID L 11 1579
FID L 12 1579
FID L 13 2356
FID L 14 2355
FID L 15 1579
FID L 16 1579
SNT TOP T 131 8
FID H 0 59
FID C 4 4078
FID C 6 3164
FID C 3 9187
FID C 8 7057
FID L 11 1580
FID L 12 1580
FID L 13 2357
FID L 14 2356
FID L 15 1580
FID L 16 1580
SNT TOP T 132 8
FID H 0 68
FID C 4 4079
FID C 6 3165
FID C 3 9188
FID C 8 7058
FID L 11 1581
FID L 12 1581
FID L 13 2358
FID L 14 2357
FID L 15 1581
FID L 16 1581
SNT TOP T 143 6
FID H 0 100
FID C 4 4080
FID C 6 3166
FID C 3 9189
FID C 8 7059
FID L 11 1582
FID L 12 1582
FID L 13 2359
FID L 14 2358
FID L 15 1582
FID L 16 1582
SNT TOP T 143 7
FID H 0 101
FID C 4 4081
FID C 6 3167
FID C 3 9190
FID C 8 7060
FID L 11 1583
FID L 12 1583
FID L 13 2360
FID L 14 2359
FID L 15 1583
FID L 16 1583
SNT TOP T 149 0
FID C 4 4001
FID C 5 1918
FID C 3 8777
SNT TOP T 149 6
FID C 4 4000
FID C 5 1917
FID C 3 8776
SNT TOP T 149 7
FID C 4 3999
FID C 5 1916
FID C 3 8775
SNT TOP T 149 11
FID C 4 3998
FID C 5 1915
FID C 3 8774
SNT TOP T 149 12
FID C 4 3997
FID C 5 1914
FID C 3 8773
SNT TOP T 149 20
FID C 4 3996
FID C 5 1913
FID C 3 8772
SNT TOP T 149 21
FID C 4 3995
FID C 5 1912
FID C 3 8771
SNT TOP T 149 22
FID C 4 3994
FID C 5 1911
FID C 3 8770
SNT TOP T 149 23
FID C 4 3993
FID C 5 1910
FID C 3 8769
SNT TOP T 165 1
FID C 4 3981
FID C 5 1898
FID C 3 8757
SNT TOP T 166 1
FID C 4 3982
FID C 5 1899
FID C 3 8758
SNT TOP T 169 9
FID C 4 3992
FID C 5 1909
FID C 3 8768
SNT TOP T 169 10
FID C 4 3991
FID C 5 1908
FID C 3 8767
SNT TOP T 169 11
FID C 4 3990
FID C 5 1907
FID C 3 8766
SNT TOP T 169 12
FID C 4 3989
FID C 5 1906
FID C 3 8765
SNT TOP T 169 13
FID C 4 3988
FID C 5 1905
FID C 3 8764
SNT TOP T 169 15
FID C 4 3987
FID C 5 1904
FID C 3 8763
SNT TOP T 169 17
FID C 4 3986
FID C 5 1903
FID C 3 8762
SNT TOP T 170 0
FID C 4 162
FID C 5 144
FID C 3 473
SNT TOP T 170 14
FID C 4 123
FID C 5 105
FID C 3 358
SNT TOP T 170 15
FID C 4 121
FID C 5 103
FID C 3 356
SNT TOP T 170 18
FID C 4 86
FID C 5 68
FID C 3 259
SNT TOP T 170 22
FID C 4 192
FID C 5 174
FID C 3 557
SNT TOP T 170 24
FID C 4 196
FID C 5 178
FID C 3 569
SNT TOP T 170 25
FID C 4 132
FID C 5 114
FID C 3 385
SNT TOP T 170 27
FID C 4 90
FID C 5 72
FID C 3 271
SNT TOP T 170 31
FID C 4 215
FID C 5 197
FID C 3 626
SNT TOP T 170 32
FID C 4 214
FID C 5 196
FID C 3 623
SNT TOP T 170 35
FID C 4 178
FID C 5 160
FID C 3 515
SNT TOP T 170 37
FID C 4 98
FID C 5 80
FID C 3 295
SNT TOP T 170 40
FID C 4 80
FID C 5 62
FID C 3 243
SNT TOP T 170 44
FID C 4 189
FID C 5 171
FID C 3 548
SNT TOP T 170 54
FID C 4 191
FID C 5 173
FID C 3 554
SNT TOP T 170 55
FID C 4 188
FID C 5 170
FID C 3 545
SNT TOP T 170 58
FID C 4 109
FID C 5 91
FID C 3 328
SNT TOP T 170 63
FID C 4 77
FID C 5 59
FID C 3 234
SNT TOP T 170 64
FID C 4 201
FID C 5 183
FID C 3 584
SNT TOP T 170 65
FID C 4 200
FID C 5 182
FID C 3 581
SNT TOP T 170 66
FID C 4 164
FID C 5 146
FID C 3 477
SNT TOP T 170 67
FID C 4 167
FID C 5 149
FID C 3 486
SNT TOP T 170 80
FID C 4 119
FID C 5 101
FID C 3 354
SNT TOP T 170 81
FID C 4 118
FID C 5 100
FID C 3 353
SNT TOP T 170 82
FID C 4 70
FID C 5 52
FID C 3 213
SNT TOP T 170 83
FID C 4 69
FID C 5 51
FID C 3 212
SNT TOP T 170 89
FID C 4 169
FID C 5 151
FID C 3 492
SNT TOP T 170 106
FID C 4 72
FID C 5 54
FID C 3 217
SNT TOP T 170 107
FID C 4 94
FID C 5 76
FID C 3 281
SNT TOP T 170 110
FID C 4 171
FID C 5 153
FID C 3 498
SNT TOP T 170 111
FID C 4 175
FID C 5 157
FID C 3 508
SNT TOP T 170 125
FID C 4 113
FID C 5 95
FID C 3 338
SNT TOP T 170 129
FID C 4 96
FID C 5 78
FID C 3 287
SNT TOP T 170 132
FID C 4 173
FID C 5 155
FID C 3 502
SNT TOP T 170 133
FID C 4 177
FID C 5 159
FID C 3 512
SNT TOP T 170 134
FID C 4 185
FID C 5 167
FID C 3 536
SNT TOP T 170 145
FID C 4 124
FID C 5 106
FID C 3 361
SNT TOP T 170 147
FID C 4 114
FID C 5 96
FID C 3 341
SNT TOP T 170 148
FID C 4 107
FID C 5 89
FID C 3 320
SNT TOP T 170 149
FID C 4 78
FID C 5 60
FID C 3 237
SNT TOP T 170 154
FID C 4 180
FID C 5 162
FID C 3 521
SNT TOP T 170 156
FID C 4 187
FID C 5 169
FID C 3 542
SNT TOP T 170 157
FID C 4 125
FID C 5 107
FID C 3 364
SNT TOP T 170 168
FID C 4 66
FID C 5 48
FID C 3 205
SNT TOP T 170 172
FID C 4 92
FID C 5 74
FID C 3 275
SNT TOP T 170 173
FID C 4 89
FID C 5 71
FID C 3 266
SNT TOP T 170 174
FID C 4 68
FID C 5 50
FID C 3 211
SNT TOP T 170 176
FID C 4 183
FID C 5 165
FID C 3 530
SNT TOP T 170 177
FID C 4 194
FID C 5 176
FID C 3 563
SNT TOP T 170 178
FID C 4 133
FID C 5 115
FID C 3 388
SNT TOP T 170 179
FID C 4 137
FID C 5 119
FID C 3 400
SNT TOP T 170 191
FID C 4 106
FID C 5 88
FID C 3 317
SNT TOP T 170 192
FID C 4 211
FID C 5 193
FID C 3 612
SNT TOP T 170 193
FID C 4 111
FID C 5 93
FID C 3 332
SNT TOP T 170 199
FID C 4 195
FID C 5 177
FID C 3 566
SNT TOP T 170 200
FID C 4 135
FID C 5 117
FID C 3 394
SNT TOP T 170 201
FID C 4 139
FID C 5 121
FID C 3 406
SNT TOP T 170 202
FID C 4 129
FID C 5 111
FID C 3 375
SNT TOP T 170 214
FID C 4 212
FID C 5 194
FID C 3 615
SNT TOP T 170 215
FID C 4 116
FID C 5 98
FID C 3 347
SNT TOP T 170 220
FID C 4 190
FID C 5 172
FID C 3 551
SNT TOP T 170 221
FID C 4 197
FID C 5 179
FID C 3 572
SNT TOP T 170 223
FID C 4 140
FID C 5 122
FID C 3 407
SNT TOP T 170 224
FID C 4 130
FID C 5 112
FID C 3 377
SNT TOP T 170 225
FID C 4 154
FID C 5 136
FID C 3 449
SNT TOP T 170 235
FID C 4 128
FID C 5 110
FID C 3 371
SNT TOP T 170 240
FID C 4 131
FID C 5 113
FID C 3 382
SNT TOP T 170 242
FID C 4 193
FID C 5 175
FID C 3 560
SNT TOP T 170 243
FID C 4 199
FID C 5 181
FID C 3 578
SNT TOP T 170 244
FID C 4 143
FID C 5 125
FID C 3 416
SNT TOP T 170 245
FID C 4 141
FID C 5 123
FID C 3 410
SNT TOP T 170 247
FID C 4 156
FID C 5 138
FID C 3 455
SNT TOP T 170 258
FID C 4 209
FID C 5 191
FID C 3 608
SNT TOP T 170 259
FID C 4 73
FID C 5 55
FID C 3 222
SNT TOP T 170 260
FID C 4 71
FID C 5 53
FID C 3 216
SNT TOP T 170 264
FID C 4 147
FID C 5 129
FID C 3 430
SNT TOP T 170 266
FID C 4 145
FID C 5 127
FID C 3 422
SNT TOP T 170 267
FID C 4 157
FID C 5 139
FID C 3 458
SNT TOP T 170 268
FID C 4 158
FID C 5 140
FID C 3 461
SNT TOP T 170 269
FID C 4 127
FID C 5 109
FID C 3 370
SNT TOP T 170 279
FID C 4 210
FID C 5 192
FID C 3 611
SNT TOP T 170 281
FID C 4 83
FID C 5 65
FID C 3 252
SNT TOP T 170 282
FID C 4 75
FID C 5 57
FID C 3 226
SNT TOP T 170 283
FID C 4 74
FID C 5 56
FID C 3 223
SNT TOP T 170 286
FID C 4 149
FID C 5 131
FID C 3 436
SNT TOP T 170 287
FID C 4 151
FID C 5 133
FID C 3 442
SNT TOP T 170 288
FID C 4 153
FID C 5 135
FID C 3 448
SNT TOP T 170 302
FID C 4 165
FID C 5 147
FID C 3 480
SNT TOP T 170 305
FID C 4 88
FID C 5 70
FID C 3 265
SNT TOP T 170 310
FID C 4 159
FID C 5 141
FID C 3 464
SNT TOP T 170 311
FID C 4 160
FID C 5 142
FID C 3 467
SNT TOP T 170 320
FID C 4 104
FID C 5 86
FID C 3 313
SNT TOP T 170 321
FID C 4 103
FID C 5 85
FID C 3 310
SNT TOP T 170 346
FID C 4 101
FID C 5 83
FID C 3 304
SNT TOP T 170 348
FID C 4 182
FID C 5 164
FID C 3 525
SNT TOP T 170 353
FID C 4 170
FID C 5 152
FID C 3 495
SNT TOP T 170 354
FID C 4 172
FID C 5 154
FID C 3 499
SNT TOP T 170 357
FID C 4 155
FID C 5 137
FID C 3 454
SNT TOP T 170 367
FID C 4 102
FID C 5 84
FID C 3 305
SNT TOP T 170 368
FID C 4 105
FID C 5 87
FID C 3 316
SNT TOP T 170 369
FID C 4 100
FID C 5 82
FID C 3 301
SNT TOP T 170 370
FID C 4 179
FID C 5 161
FID C 3 516
SNT TOP T 170 374
FID C 4 163
FID C 5 145
FID C 3 476
SNT TOP T 170 376
FID C 4 67
FID C 5 49
FID C 3 206
SNT TOP T 170 378
FID C 4 144
FID C 5 126
FID C 3 421
SNT TOP T 170 379
FID C 4 35
FID C 5 23
FID C 3 107
SNT TOP T 170 387
FID C 4 79
FID C 5 61
FID C 3 238
SNT TOP T 170 388
FID C 4 76
FID C 5 58
FID C 3 231
SNT TOP T 170 391
FID C 4 99
FID C 5 81
FID C 3 298
SNT TOP T 170 393
FID C 4 115
FID C 5 97
FID C 3 344
SNT TOP T 170 394
FID C 4 112
FID C 5 94
FID C 3 337
SNT TOP T 170 396
FID C 4 161
FID C 5 143
FID C 3 472
SNT TOP T 170 397
FID C 4 168
FID C 5 150
FID C 3 489
SNT TOP T 170 398
FID C 4 186
FID C 5 168
FID C 3 537
SNT TOP T 170 400
FID C 4 142
FID C 5 124
FID C 3 415
SNT TOP T 170 401
FID C 4 152
FID C 5 134
FID C 3 445
SNT TOP T 170 402
FID C 4 126
FID C 5 108
FID C 3 367
SNT TOP T 170 410
FID C 4 207
FID C 5 189
FID C 3 602
SNT TOP T 170 412
FID C 4 91
FID C 5 73
FID C 3 274
SNT TOP T 170 413
FID C 4 87
FID C 5 69
FID C 3 262
SNT TOP T 170 415
FID C 4 203
FID C 5 185
FID C 3 588
SNT TOP T 170 416
FID C 4 110
FID C 5 92
FID C 3 331
SNT TOP T 170 419
FID C 4 166
FID C 5 148
FID C 3 483
SNT TOP T 170 420
FID C 4 184
FID C 5 166
FID C 3 531
SNT TOP T 170 421
FID C 4 138
FID C 5 120
FID C 3 401
SNT TOP T 170 422
FID C 4 150
FID C 5 132
FID C 3 439
SNT TOP T 170 424
FID C 4 97
FID C 5 79
FID C 3 290
SNT TOP T 170 431
FID C 4 204
FID C 5 186
FID C 3 593
SNT TOP T 170 434
FID C 4 85
FID C 5 67
FID C 3 256
SNT TOP T 170 435
FID C 4 208
FID C 5 190
FID C 3 605
SNT TOP T 170 436
FID C 4 206
FID C 5 188
FID C 3 599
SNT TOP T 170 437
FID C 4 202
FID C 5 184
FID C 3 585
SNT TOP T 170 439
FID C 4 108
FID C 5 90
FID C 3 325
SNT TOP T 170 441
FID C 4 176
FID C 5 158
FID C 3 511
SNT TOP T 170 443
FID C 4 136
FID C 5 118
FID C 3 395
SNT TOP T 170 444
FID C 4 146
FID C 5 128
FID C 3 427
SNT TOP T 170 445
FID C 4 148
FID C 5 130
FID C 3 431
SNT TOP T 170 446
FID C 4 95
FID C 5 77
FID C 3 284
SNT TOP T 170 454
FID C 4 84
FID C 5 66
FID C 3 253
SNT TOP T 170 455
FID C 4 81
FID C 5 63
FID C 3 244
SNT TOP T 170 456
FID C 4 82
FID C 5 64
FID C 3 247
SNT TOP T 170 460
FID C 4 213
FID C 5 195
FID C 3 620
SNT TOP T 170 461
FID C 4 117
FID C 5 99
FID C 3 352
SNT TOP T 170 463
FID C 4 174
FID C 5 156
FID C 3 505
SNT TOP T 170 464
FID C 4 198
FID C 5 180
FID C 3 575
SNT TOP T 170 465
FID C 4 134
FID C 5 116
FID C 3 391
SNT TOP T 170 467
FID C 4 93
FID C 5 75
FID C 3 280
SNT TOP T 170 474
FID C 4 181
FID C 5 163
FID C 3 522
SNT TOP T 170 478
FID C 4 65
FID C 5 47
FID C 3 200
SNT TOP T 170 480
FID C 4 205
FID C 5 187
FID C 3 596
SNT TOP T 170 482
FID C 4 122
FID C 5 104
FID C 3 357
SNT TOP T 170 483
FID C 4 120
FID C 5 102
FID C 3 355
SNT TOP T 179 6
FID C 4 3978
FID C 5 1895
FID C 3 8754
SNT TOP T 179 7
FID C 4 3979
FID C 5 1896
FID C 3 8755
SNT TOP T 183 4
FID C 4 2262
FID C 5 1345
FID C 3 5602
SNT TOP T 594 3
FID C 4 1997
FID C 5 1200
FID C 3 5090
SNT TOP T 595 3
FID C 4 1998
FID C 5 1201
FID C 3 5091
SNT TOP T 597 0
FID C 4 3980
FID C 5 1897
FID C 3 8756
SNT TOP T 599 0
FID C 4 3975
FID C 5 1892
FID C 3 8751
SNT TOP T 599 2
FID C 4 3974
FID C 5 1891
FID C 3 8750
SNT TOP T 600 0
FID C 4 3977
FID C 5 1894
FID C 3 8753
SNT TOP T 600 2
FID C 4 3976
FID C 5 1893
FID C 3 8752
SNT TOP T 602 5
FID C 4 2259
FID C 5 1342
FID C 3 5599
SNT TOP T 602 6
FID C 4 2260
FID C 5 1343
FID C 3 5600
SNT TOP T 602 7
FID C 4 2261
FID C 5 1344
FID C 3 5601
SNT TOP T 603 3
FID C 4 3969
FID C 5 1890
FID C 3 8745
SNT TOP T 605 18
FID C 6 3107
FID C 8 6976
SNT TOP T 605 31
FID C 6 3106
FID C 8 6975
SNT TOP T 605 40
FID C 4 3973
FID C 3 8749
SNT TOP T 605 42
FID C 4 3970
FID C 3 8746
SNT TOP T 605 43
FID C 4 3972
FID C 3 8748
SNT TOP T 605 61
FID C 4 3971
FID C 3 8747
SNT TOP T 606 0
FID C 6 3155
FID C 8 7048
FID C 4 4071
FID C 3 9180
SNT TOP T 607 0
FID C 4 4069
FID C 3 9178
FID C 6 3156
FID C 8 7049
SNT TOP T 608 0
FID C 4 4070
FID C 3 9179
FID C 6 3157
FID C 8 7050
SNT TOP B 107 6
FID C 6 451
FID C 7 148
FID C 8 1265
SNT TOP B 442 3
FID C 6 1563
FID C 7 556
FID C 8 4003
SNT TOP B 443 3
FID C 6 1562
FID C 7 555
FID C 8 4002
SNT TOP B 445 0
SNT TOP B 446 0
SNT TOP B 447 0
SNT VIA
FID C 6 3110
FID C 8 6979
SNT VIA
FID H 0 1083
FID C 4 4022
FID C 6 3108
FID C 3 8798
FID C 8 6977
FID L 11 1572
FID L 12 1572
FID L 13 2349
FID L 14 2348
FID L 15 1572
FID L 16 1572
SNT VIA
FID H 0 1975
FID C 3 484
FID C 8 177
FID L 11 123
FID L 12 123
FID L 13 123
FID L 14 123
FID L 15 123
FID L 16 123
SNT VIA
FID H 0 1976
FID C 3 490
FID C 8 179
FID L 11 125
FID L 12 125
FID L 13 125
FID L 14 125
FID L 15 125
FID L 16 125
SNT VIA
FID H 0 1977
FID C 3 218
FID C 8 91
FID L 11 37
FID L 12 37
FID L 13 37
FID L 14 37
FID L 15 37
FID L 16 37
SNT VIA
FID H 0 1978
FID C 3 496
FID C 8 181
FID L 11 127
FID L 12 127
FID L 13 127
FID L 14 127
FID L 15 127
FID L 16 127
SNT VIA
FID H 0 1979
FID C 3 506
FID C 8 184
FID L 11 130
FID L 12 130
FID L 13 130
FID L 14 130
FID L 15 130
FID L 16 130
SNT VIA
FID H 0 1980
FID C 3 339
FID C 8 131
FID L 11 77
FID L 12 77
FID L 13 77
FID L 14 77
FID L 15 77
FID L 16 77
SNT VIA
FID H 0 1981
FID C 3 534
FID C 8 193
FID L 11 139
FID L 12 139
FID L 13 139
FID L 14 139
FID L 15 139
FID L 16 139
SNT VIA
FID H 0 1982
FID C 3 359
FID C 8 136
FID L 11 82
FID L 12 82
FID L 13 82
FID L 14 82
FID L 15 82
FID L 16 82
SNT VIA
FID H 0 1983
FID C 3 342
FID C 8 132
FID L 11 78
FID L 12 78
FID L 13 78
FID L 14 78
FID L 15 78
FID L 16 78
SNT VIA
FID H 0 1984
FID C 3 321
FID C 8 125
FID L 11 71
FID L 12 71
FID L 13 71
FID L 14 71
FID L 15 71
FID L 16 71
SNT VIA
FID H 0 1985
FID C 3 235
FID C 8 97
FID L 11 43
FID L 12 43
FID L 13 43
FID L 14 43
FID L 15 43
FID L 16 43
SNT VIA
FID H 0 1986
FID C 3 519
FID C 8 188
FID L 11 134
FID L 12 134
FID L 13 134
FID L 14 134
FID L 15 134
FID L 16 134
SNT VIA
FID H 0 1987
FID C 3 540
FID C 8 195
FID L 11 141
FID L 12 141
FID L 13 141
FID L 14 141
FID L 15 141
FID L 16 141
SNT VIA
FID H 0 1988
FID C 3 362
FID C 8 137
FID L 11 83
FID L 12 83
FID L 13 83
FID L 14 83
FID L 15 83
FID L 16 83
SNT VIA
FID H 0 1989
FID C 3 203
FID C 8 87
FID L 11 33
FID L 12 33
FID L 13 33
FID L 14 33
FID L 15 33
FID L 16 33
SNT VIA
FID H 0 1990
FID C 3 276
FID C 8 110
FID L 11 56
FID L 12 56
FID L 13 56
FID L 14 56
FID L 15 56
FID L 16 56
SNT VIA
FID H 0 1991
FID C 3 209
FID C 8 89
FID L 11 35
FID L 12 35
FID L 13 35
FID L 14 35
FID L 15 35
FID L 16 35
SNT VIA
FID H 0 1992
FID C 3 528
FID C 8 191
FID L 11 137
FID L 12 137
FID L 13 137
FID L 14 137
FID L 15 137
FID L 16 137
SNT VIA
FID H 0 1993
FID C 3 561
FID C 8 202
FID L 11 148
FID L 12 148
FID L 13 148
FID L 14 148
FID L 15 148
FID L 16 148
SNT VIA
FID H 0 1994
FID C 3 386
FID C 8 145
FID L 11 91
FID L 12 91
FID L 13 91
FID L 14 91
FID L 15 91
FID L 16 91
SNT VIA
FID H 0 1995
FID C 3 398
FID C 8 149
FID L 11 95
FID L 12 95
FID L 13 95
FID L 14 95
FID L 15 95
FID L 16 95
SNT VIA
FID H 0 1996
FID C 3 318
FID C 8 124
FID L 11 70
FID L 12 70
FID L 13 70
FID L 14 70
FID L 15 70
FID L 16 70
SNT VIA
FID H 0 1997
FID C 3 613
FID C 8 219
FID L 11 165
FID L 12 165
FID L 13 165
FID L 14 165
FID L 15 165
FID L 16 165
SNT VIA
FID H 0 1998
FID C 3 333
FID C 8 129
FID L 11 75
FID L 12 75
FID L 13 75
FID L 14 75
FID L 15 75
FID L 16 75
SNT VIA
FID H 0 1999
FID C 3 564
FID C 8 203
FID L 11 149
FID L 12 149
FID L 13 149
FID L 14 149
FID L 15 149
FID L 16 149
SNT VIA
FID H 0 2000
FID C 3 392
FID C 8 147
FID L 11 93
FID L 12 93
FID L 13 93
FID L 14 93
FID L 15 93
FID L 16 93
SNT VIA
FID H 0 2001
FID C 3 404
FID C 8 151
FID L 11 97
FID L 12 97
FID L 13 97
FID L 14 97
FID L 15 97
FID L 16 97
SNT VIA
FID H 0 2002
FID C 3 374
FID C 8 141
FID L 11 87
FID L 12 87
FID L 13 87
FID L 14 87
FID L 15 87
FID L 16 87
SNT VIA
FID H 0 2003
FID C 3 616
FID C 8 220
FID L 11 166
FID L 12 166
FID L 13 166
FID L 14 166
FID L 15 166
FID L 16 166
SNT VIA
FID H 0 2004
FID C 3 348
FID C 8 134
FID L 11 80
FID L 12 80
FID L 13 80
FID L 14 80
FID L 15 80
FID L 16 80
SNT VIA
FID H 0 2005
FID C 3 549
FID C 8 198
FID L 11 144
FID L 12 144
FID L 13 144
FID L 14 144
FID L 15 144
FID L 16 144
SNT VIA
FID H 0 2006
FID C 3 570
FID C 8 205
FID L 11 151
FID L 12 151
FID L 13 151
FID L 14 151
FID L 15 151
FID L 16 151
SNT VIA
FID H 0 2007
FID C 3 408
FID C 8 152
FID L 11 98
FID L 12 98
FID L 13 98
FID L 14 98
FID L 15 98
FID L 16 98
SNT VIA
FID H 0 2008
FID C 3 378
FID C 8 142
FID L 11 88
FID L 12 88
FID L 13 88
FID L 14 88
FID L 15 88
FID L 16 88
SNT VIA
FID H 0 2009
FID C 3 372
FID C 8 140
FID L 11 86
FID L 12 86
FID L 13 86
FID L 14 86
FID L 15 86
FID L 16 86
SNT VIA
FID H 0 2010
FID C 3 380
FID C 8 143
FID L 11 89
FID L 12 89
FID L 13 89
FID L 14 89
FID L 15 89
FID L 16 89
SNT VIA
FID H 0 2011
FID C 3 558
FID C 8 201
FID L 11 147
FID L 12 147
FID L 13 147
FID L 14 147
FID L 15 147
FID L 16 147
SNT VIA
FID H 0 2012
FID C 3 576
FID C 8 207
FID L 11 153
FID L 12 153
FID L 13 153
FID L 14 153
FID L 15 153
FID L 16 153
SNT VIA
FID H 0 2013
FID C 3 417
FID C 8 155
FID L 11 101
FID L 12 101
FID L 13 101
FID L 14 101
FID L 15 101
FID L 16 101
SNT VIA
FID H 0 2014
FID C 3 411
FID C 8 153
FID L 11 99
FID L 12 99
FID L 13 99
FID L 14 99
FID L 15 99
FID L 16 99
SNT VIA
FID H 0 2015
FID C 3 606
FID C 8 217
FID L 11 163
FID L 12 163
FID L 13 163
FID L 14 163
FID L 15 163
FID L 16 163
SNT VIA
FID H 0 2016
FID C 3 220
FID C 8 92
FID L 11 38
FID L 12 38
FID L 13 38
FID L 14 38
FID L 15 38
FID L 16 38
SNT VIA
FID H 0 2017
FID C 3 214
FID C 8 90
FID L 11 36
FID L 12 36
FID L 13 36
FID L 14 36
FID L 15 36
FID L 16 36
SNT VIA
FID H 0 2018
FID C 3 428
FID C 8 159
FID L 11 105
FID L 12 105
FID L 13 105
FID L 14 105
FID L 15 105
FID L 16 105
SNT VIA
FID H 0 2019
FID C 3 423
FID C 8 157
FID L 11 103
FID L 12 103
FID L 13 103
FID L 14 103
FID L 15 103
FID L 16 103
SNT VIA
FID H 0 2020
FID C 3 368
FID C 8 139
FID L 11 85
FID L 12 85
FID L 13 85
FID L 14 85
FID L 15 85
FID L 16 85
SNT VIA
FID H 0 2021
FID C 3 609
FID C 8 218
FID L 11 164
FID L 12 164
FID L 13 164
FID L 14 164
FID L 15 164
FID L 16 164
SNT VIA
FID H 0 2022
FID C 3 250
FID C 8 102
FID L 11 48
FID L 12 48
FID L 13 48
FID L 14 48
FID L 15 48
FID L 16 48
SNT VIA
FID H 0 2023
FID C 3 227
FID C 8 94
FID L 11 40
FID L 12 40
FID L 13 40
FID L 14 40
FID L 15 40
FID L 16 40
SNT VIA
FID H 0 2024
FID C 3 224
FID C 8 93
FID L 11 39
FID L 12 39
FID L 13 39
FID L 14 39
FID L 15 39
FID L 16 39
SNT VIA
FID H 0 2025
FID C 3 434
FID C 8 161
FID L 11 107
FID L 12 107
FID L 13 107
FID L 14 107
FID L 15 107
FID L 16 107
SNT VIA
FID H 0 2026
FID C 3 440
FID C 8 163
FID L 11 109
FID L 12 109
FID L 13 109
FID L 14 109
FID L 15 109
FID L 16 109
SNT VIA
FID H 0 2027
FID C 3 446
FID C 8 165
FID L 11 111
FID L 12 111
FID L 13 111
FID L 14 111
FID L 15 111
FID L 16 111
SNT VIA
FID H 0 2028
FID C 3 478
FID C 8 175
FID L 11 121
FID L 12 121
FID L 13 121
FID L 14 121
FID L 15 121
FID L 16 121
SNT VIA
FID H 0 2029
FID C 3 263
FID C 8 106
FID L 11 52
FID L 12 52
FID L 13 52
FID L 14 52
FID L 15 52
FID L 16 52
SNT VIA
FID H 0 2030
FID C 3 311
FID C 8 122
FID L 11 68
FID L 12 68
FID L 13 68
FID L 14 68
FID L 15 68
FID L 16 68
SNT VIA
FID H 0 2031
FID C 3 308
FID C 8 121
FID L 11 67
FID L 12 67
FID L 13 67
FID L 14 67
FID L 15 67
FID L 16 67
SNT VIA
FID H 0 2032
FID C 3 302
FID C 8 119
FID L 11 65
FID L 12 65
FID L 13 65
FID L 14 65
FID L 15 65
FID L 16 65
SNT VIA
FID H 0 2033
FID C 3 526
FID C 8 190
FID L 11 136
FID L 12 136
FID L 13 136
FID L 14 136
FID L 15 136
FID L 16 136
SNT VIA
FID H 0 2034
FID C 3 493
FID C 8 180
FID L 11 126
FID L 12 126
FID L 13 126
FID L 14 126
FID L 15 126
FID L 16 126
SNT VIA
FID H 0 2035
FID C 3 500
FID C 8 182
FID L 11 128
FID L 12 128
FID L 13 128
FID L 14 128
FID L 15 128
FID L 16 128
SNT VIA
FID H 0 2036
FID C 3 452
FID C 8 167
FID L 11 113
FID L 12 113
FID L 13 113
FID L 14 113
FID L 15 113
FID L 16 113
SNT VIA
FID H 0 2037
FID C 3 306
FID C 8 120
FID L 11 66
FID L 12 66
FID L 13 66
FID L 14 66
FID L 15 66
FID L 16 66
SNT VIA
FID H 0 2038
FID C 3 314
FID C 8 123
FID L 11 69
FID L 12 69
FID L 13 69
FID L 14 69
FID L 15 69
FID L 16 69
SNT VIA
FID H 0 2039
FID C 3 299
FID C 8 118
FID L 11 64
FID L 12 64
FID L 13 64
FID L 14 64
FID L 15 64
FID L 16 64
SNT VIA
FID H 0 2040
FID C 3 517
FID C 8 187
FID L 11 133
FID L 12 133
FID L 13 133
FID L 14 133
FID L 15 133
FID L 16 133
SNT VIA
FID H 0 2041
FID C 3 474
FID C 8 174
FID L 11 120
FID L 12 120
FID L 13 120
FID L 14 120
FID L 15 120
FID L 16 120
SNT VIA
FID H 0 2042
FID C 3 207
FID C 8 88
FID L 11 34
FID L 12 34
FID L 13 34
FID L 14 34
FID L 15 34
FID L 16 34
SNT VIA
FID H 0 2043
FID C 3 419
FID C 8 156
FID L 11 102
FID L 12 102
FID L 13 102
FID L 14 102
FID L 15 102
FID L 16 102
SNT VIA
FID H 0 2044
FID C 3 239
FID C 8 98
FID L 11 44
FID L 12 44
FID L 13 44
FID L 14 44
FID L 15 44
FID L 16 44
SNT VIA
FID H 0 2045
FID C 3 229
FID C 8 95
FID L 11 41
FID L 12 41
FID L 13 41
FID L 14 41
FID L 15 41
FID L 16 41
SNT VIA
FID H 0 2046
FID C 3 296
FID C 8 117
FID L 11 63
FID L 12 63
FID L 13 63
FID L 14 63
FID L 15 63
FID L 16 63
SNT VIA
FID H 0 2047
FID C 3 345
FID C 8 133
FID L 11 79
FID L 12 79
FID L 13 79
FID L 14 79
FID L 15 79
FID L 16 79
SNT VIA
FID H 0 2048
FID C 3 335
FID C 8 130
FID L 11 76
FID L 12 76
FID L 13 76
FID L 14 76
FID L 15 76
FID L 16 76
SNT VIA
FID H 0 2049
FID C 3 471
FID C 8 173
FID L 11 119
FID L 12 119
FID L 13 119
FID L 14 119
FID L 15 119
FID L 16 119
SNT VIA
FID H 0 2050
FID C 3 488
FID C 8 178
FID L 11 124
FID L 12 124
FID L 13 124
FID L 14 124
FID L 15 124
FID L 16 124
SNT VIA
FID H 0 2051
FID C 3 538
FID C 8 194
FID L 11 140
FID L 12 140
FID L 13 140
FID L 14 140
FID L 15 140
FID L 16 140
SNT VIA
FID H 0 2052
FID C 3 413
FID C 8 154
FID L 11 100
FID L 12 100
FID L 13 100
FID L 14 100
FID L 15 100
FID L 16 100
SNT VIA
FID H 0 2053
FID C 3 443
FID C 8 164
FID L 11 110
FID L 12 110
FID L 13 110
FID L 14 110
FID L 15 110
FID L 16 110
SNT VIA
FID H 0 2054
FID C 3 365
FID C 8 138
FID L 11 84
FID L 12 84
FID L 13 84
FID L 14 84
FID L 15 84
FID L 16 84
SNT VIA
FID H 0 2055
FID C 3 600
FID C 8 215
FID L 11 161
FID L 12 161
FID L 13 161
FID L 14 161
FID L 15 161
FID L 16 161
SNT VIA
FID H 0 2056
FID C 3 272
FID C 8 109
FID L 11 55
FID L 12 55
FID L 13 55
FID L 14 55
FID L 15 55
FID L 16 55
SNT VIA
FID H 0 2057
FID C 3 260
FID C 8 105
FID L 11 51
FID L 12 51
FID L 13 51
FID L 14 51
FID L 15 51
FID L 16 51
SNT VIA
FID H 0 2058
FID C 3 589
FID C 8 211
FID L 11 157
FID L 12 157
FID L 13 157
FID L 14 157
FID L 15 157
FID L 16 157
SNT VIA
FID H 0 2059
FID C 3 329
FID C 8 128
FID L 11 74
FID L 12 74
FID L 13 74
FID L 14 74
FID L 15 74
FID L 16 74
SNT VIA
FID H 0 2060
FID C 3 481
FID C 8 176
FID L 11 122
FID L 12 122
FID L 13 122
FID L 14 122
FID L 15 122
FID L 16 122
SNT VIA
FID H 0 2061
FID C 3 532
FID C 8 192
FID L 11 138
FID L 12 138
FID L 13 138
FID L 14 138
FID L 15 138
FID L 16 138
SNT VIA
FID H 0 2062
FID C 3 402
FID C 8 150
FID L 11 96
FID L 12 96
FID L 13 96
FID L 14 96
FID L 15 96
FID L 16 96
SNT VIA
FID H 0 2063
FID C 3 437
FID C 8 162
FID L 11 108
FID L 12 108
FID L 13 108
FID L 14 108
FID L 15 108
FID L 16 108
SNT VIA
FID H 0 2064
FID C 3 291
FID C 8 115
FID L 11 61
FID L 12 61
FID L 13 61
FID L 14 61
FID L 15 61
FID L 16 61
SNT VIA
FID H 0 2065
FID C 3 591
FID C 8 212
FID L 11 158
FID L 12 158
FID L 13 158
FID L 14 158
FID L 15 158
FID L 16 158
SNT VIA
FID H 0 2066
FID C 3 257
FID C 8 104
FID L 11 50
FID L 12 50
FID L 13 50
FID L 14 50
FID L 15 50
FID L 16 50
SNT VIA
FID H 0 2067
FID C 3 603
FID C 8 216
FID L 11 162
FID L 12 162
FID L 13 162
FID L 14 162
FID L 15 162
FID L 16 162
SNT VIA
FID H 0 2068
FID C 3 597
FID C 8 214
FID L 11 160
FID L 12 160
FID L 13 160
FID L 14 160
FID L 15 160
FID L 16 160
SNT VIA
FID H 0 2069
FID C 3 586
FID C 8 210
FID L 11 156
FID L 12 156
FID L 13 156
FID L 14 156
FID L 15 156
FID L 16 156
SNT VIA
FID H 0 2070
FID C 3 323
FID C 8 126
FID L 11 72
FID L 12 72
FID L 13 72
FID L 14 72
FID L 15 72
FID L 16 72
SNT VIA
FID H 0 2071
FID C 3 509
FID C 8 185
FID L 11 131
FID L 12 131
FID L 13 131
FID L 14 131
FID L 15 131
FID L 16 131
SNT VIA
FID H 0 2072
FID C 3 396
FID C 8 148
FID L 11 94
FID L 12 94
FID L 13 94
FID L 14 94
FID L 15 94
FID L 16 94
SNT VIA
FID H 0 2073
FID C 3 425
FID C 8 158
FID L 11 104
FID L 12 104
FID L 13 104
FID L 14 104
FID L 15 104
FID L 16 104
SNT VIA
FID H 0 2074
FID C 3 432
FID C 8 160
FID L 11 106
FID L 12 106
FID L 13 106
FID L 14 106
FID L 15 106
FID L 16 106
SNT VIA
FID H 0 2075
FID C 3 285
FID C 8 113
FID L 11 59
FID L 12 59
FID L 13 59
FID L 14 59
FID L 15 59
FID L 16 59
SNT VIA
FID H 0 2076
FID C 3 254
FID C 8 103
FID L 11 49
FID L 12 49
FID L 13 49
FID L 14 49
FID L 15 49
FID L 16 49
SNT VIA
FID H 0 2077
FID C 3 245
FID C 8 100
FID L 11 46
FID L 12 46
FID L 13 46
FID L 14 46
FID L 15 46
FID L 16 46
SNT VIA
FID H 0 2078
FID C 3 248
FID C 8 101
FID L 11 47
FID L 12 47
FID L 13 47
FID L 14 47
FID L 15 47
FID L 16 47
SNT VIA
FID H 0 2079
FID C 3 618
FID C 8 221
FID L 11 167
FID L 12 167
FID L 13 167
FID L 14 167
FID L 15 167
FID L 16 167
SNT VIA
FID H 0 2080
FID C 3 350
FID C 8 135
FID L 11 81
FID L 12 81
FID L 13 81
FID L 14 81
FID L 15 81
FID L 16 81
SNT VIA
FID H 0 2081
FID C 3 503
FID C 8 183
FID L 11 129
FID L 12 129
FID L 13 129
FID L 14 129
FID L 15 129
FID L 16 129
SNT VIA
FID H 0 2082
FID C 3 573
FID C 8 206
FID L 11 152
FID L 12 152
FID L 13 152
FID L 14 152
FID L 15 152
FID L 16 152
SNT VIA
FID H 0 2083
FID C 3 389
FID C 8 146
FID L 11 92
FID L 12 92
FID L 13 92
FID L 14 92
FID L 15 92
FID L 16 92
SNT VIA
FID H 0 2084
FID C 3 278
FID C 8 111
FID L 11 57
FID L 12 57
FID L 13 57
FID L 14 57
FID L 15 57
FID L 16 57
SNT VIA
FID H 0 2085
FID C 3 523
FID C 8 189
FID L 11 135
FID L 12 135
FID L 13 135
FID L 14 135
FID L 15 135
FID L 16 135
SNT VIA
FID H 0 2086
FID C 3 201
FID C 8 86
FID L 11 32
FID L 12 32
FID L 13 32
FID L 14 32
FID L 15 32
FID L 16 32
SNT VIA
FID H 0 2087
FID C 3 594
FID C 8 213
FID L 11 159
FID L 12 159
FID L 13 159
FID L 14 159
FID L 15 159
FID L 16 159
SNT VIA
FID H 0 2088
FID C 3 555
FID C 8 200
FID L 11 146
FID L 12 146
FID L 13 146
FID L 14 146
FID L 15 146
FID L 16 146
SNT VIA
FID H 0 2089
FID C 3 567
FID C 8 204
FID L 11 150
FID L 12 150
FID L 13 150
FID L 14 150
FID L 15 150
FID L 16 150
SNT VIA
FID H 0 2090
FID C 3 383
FID C 8 144
FID L 11 90
FID L 12 90
FID L 13 90
FID L 14 90
FID L 15 90
FID L 16 90
SNT VIA
FID H 0 2091
FID C 3 269
FID C 8 108
FID L 11 54
FID L 12 54
FID L 13 54
FID L 14 54
FID L 15 54
FID L 16 54
SNT VIA
FID H 0 2092
FID C 3 624
FID C 8 223
FID L 11 169
FID L 12 169
FID L 13 169
FID L 14 169
FID L 15 169
FID L 16 169
SNT VIA
FID H 0 2093
FID C 3 621
FID C 8 222
FID L 11 168
FID L 12 168
FID L 13 168
FID L 14 168
FID L 15 168
FID L 16 168
SNT VIA
FID H 0 2094
FID C 3 513
FID C 8 186
FID L 11 132
FID L 12 132
FID L 13 132
FID L 14 132
FID L 15 132
FID L 16 132
SNT VIA
FID H 0 2095
FID C 3 293
FID C 8 116
FID L 11 62
FID L 12 62
FID L 13 62
FID L 14 62
FID L 15 62
FID L 16 62
SNT VIA
FID H 0 2096
FID C 3 241
FID C 8 99
FID L 11 45
FID L 12 45
FID L 13 45
FID L 14 45
FID L 15 45
FID L 16 45
SNT VIA
FID H 0 2097
FID C 3 546
FID C 8 197
FID L 11 143
FID L 12 143
FID L 13 143
FID L 14 143
FID L 15 143
FID L 16 143
SNT VIA
FID H 0 2098
FID C 3 552
FID C 8 199
FID L 11 145
FID L 12 145
FID L 13 145
FID L 14 145
FID L 15 145
FID L 16 145
SNT VIA
FID H 0 2099
FID C 3 543
FID C 8 196
FID L 11 142
FID L 12 142
FID L 13 142
FID L 14 142
FID L 15 142
FID L 16 142
SNT VIA
FID H 0 2100
FID C 3 326
FID C 8 127
FID L 11 73
FID L 12 73
FID L 13 73
FID L 14 73
FID L 15 73
FID L 16 73
SNT VIA
FID H 0 2101
FID C 3 232
FID C 8 96
FID L 11 42
FID L 12 42
FID L 13 42
FID L 14 42
FID L 15 42
FID L 16 42
SNT VIA
FID H 0 2102
FID C 3 582
FID C 8 209
FID L 11 155
FID L 12 155
FID L 13 155
FID L 14 155
FID L 15 155
FID L 16 155
SNT VIA
FID H 0 2103
FID C 3 579
FID C 8 208
FID L 11 154
FID L 12 154
FID L 13 154
FID L 14 154
FID L 15 154
FID L 16 154
SNT VIA
FID H 0 2216
FID C 6 46
FID C 3 267
FID C 8 107
FID L 11 53
FID L 12 53
FID L 13 53
FID L 14 53
FID L 15 53
FID L 16 53
SNT VIA
FID H 0 2222
FID C 4 4023
FID C 6 3109
FID C 3 8799
FID C 8 6978
FID L 11 1573
FID L 12 1573
FID L 13 2350
FID L 14 2349
FID L 15 1573
FID L 16 1573
SNT VIA
FID H 0 2333
FID C 3 282
FID C 8 112
FID L 11 58
FID L 12 58
FID L 13 58
FID L 14 58
FID L 15 58
FID L 16 58
SNT VIA
FID H 0 2334
FID C 3 450
FID C 8 166
FID L 11 112
FID L 12 112
FID L 13 112
FID L 14 112
FID L 15 112
FID L 16 112
SNT VIA
FID H 0 2335
FID C 3 456
FID C 8 168
FID L 11 114
FID L 12 114
FID L 13 114
FID L 14 114
FID L 15 114
FID L 16 114
SNT VIA
FID H 0 2336
FID C 3 462
FID C 8 170
FID L 11 116
FID L 12 116
FID L 13 116
FID L 14 116
FID L 15 116
FID L 16 116
SNT VIA
FID H 0 2337
FID C 3 465
FID C 8 171
FID L 11 117
FID L 12 117
FID L 13 117
FID L 14 117
FID L 15 117
FID L 16 117
SNT VIA
FID H 0 2338
FID C 3 468
FID C 8 172
FID L 11 118
FID L 12 118
FID L 13 118
FID L 14 118
FID L 15 118
FID L 16 118
SNT VIA
FID H 0 2339
FID C 3 106
FID C 8 23
FID L 11 16
FID L 12 16
FID L 13 16
FID L 14 16
FID L 15 16
FID L 16 16
SNT VIA
FID H 0 2572
FID C 6 47
FID C 3 289
FID C 8 114
FID L 11 60
FID L 12 60
FID L 13 60
FID L 14 60
FID L 15 60
FID L 16 60
SNT VIA
FID H 0 2573
FID C 6 48
FID C 3 460
FID C 8 169
FID L 11 115
FID L 12 115
FID L 13 115
FID L 14 115
FID L 15 115
FID L 16 115
# NET 1
NET XP3R3V_FPGA 
SNT TOP T 0 10
FID C 4 1475
FID C 5 878
FID C 3 3838
SNT TOP T 0 11
FID C 4 1436
FID C 5 862
FID C 3 3774
SNT TOP T 2 4
FID C 4 1325
FID C 5 793
FID C 3 3537
SNT TOP T 3 4
FID C 4 1329
FID C 5 794
FID C 3 3542
SNT TOP T 4 15
FID C 4 1480
FID C 5 881
FID C 3 3846
SNT TOP T 5 15
FID C 4 1466
FID C 5 875
FID C 3 3824
SNT TOP T 6 15
FID C 4 1427
FID C 5 858
FID C 3 3760
SNT TOP T 7 7
FID C 4 1556
FID C 5 916
FID C 3 3997
SNT TOP T 10 0
FID C 4 1442
FID C 5 866
FID C 3 3785
SNT TOP T 12 1
FID C 4 1344
FID C 5 800
FID C 3 3575
SNT TOP T 57 0
FID H 0 184
FID C 6 835
FID C 3 3571
FID C 8 2429
FID L 11 810
FID L 12 810
FID L 13 793
FID L 15 810
FID L 16 810
SNT TOP T 110 1
FID C 4 1545
FID C 5 910
FID C 3 3976
SNT TOP T 111 1
FID C 4 1534
FID C 5 905
FID C 3 3956
SNT TOP T 112 1
FID C 4 1554
FID C 5 915
FID C 3 3993
SNT TOP T 113 1
FID C 4 1515
FID C 5 898
FID C 3 3926
SNT TOP T 114 1
FID C 4 1528
FID C 5 902
FID C 3 3946
SNT TOP T 119 6
FID C 4 1372
FID C 5 820
FID C 3 3637
SNT TOP T 119 7
FID C 4 1371
FID C 5 819
FID C 3 3636
SNT TOP T 119 8
FID C 4 1370
FID C 5 818
FID C 3 3635
SNT TOP T 119 9
FID C 4 1369
FID C 5 817
FID C 3 3634
SNT TOP T 119 10
FID C 4 1368
FID C 5 816
FID C 3 3633
SNT TOP T 119 11
FID C 4 1367
FID C 5 815
FID C 3 3632
SNT TOP T 120 2
FID C 4 1456
FID C 5 870
FID C 3 3810
SNT TOP T 125 7
FID C 4 1524
FID C 5 900
FID C 3 3942
SNT TOP T 126 7
FID C 4 1536
FID C 5 906
FID C 3 3960
SNT TOP T 127 7
FID C 4 1547
FID C 5 911
FID C 3 3979
SNT TOP T 128 7
FID C 4 1567
FID C 5 921
FID C 3 4016
SNT TOP T 133 3
FID C 4 1562
FID C 5 919
FID C 3 4006
SNT TOP T 152 0
FID C 4 1503
FID C 5 890
FID C 3 3902
SNT TOP T 155 1
FID C 4 1465
FID C 5 874
FID C 3 3823
SNT TOP T 168 7
FID C 4 1333
FID C 5 795
FID C 3 3547
SNT TOP T 170 16
FID C 4 1362
FID C 5 811
FID C 3 3618
SNT TOP T 170 38
FID C 4 1404
FID C 5 843
FID C 3 3706
SNT TOP T 170 57
FID C 4 1403
FID C 5 842
FID C 3 3704
SNT TOP T 170 79
FID C 4 1363
FID C 5 812
FID C 3 3621
SNT TOP T 170 108
FID C 4 1405
FID C 5 844
FID C 3 3708
SNT TOP T 170 127
FID C 4 1359
FID C 5 808
FID C 3 3609
SNT TOP T 170 146
FID C 4 1361
FID C 5 810
FID C 3 3615
SNT TOP T 170 165
FID C 4 1364
FID C 5 813
FID C 3 3624
SNT TOP T 170 175
FID C 4 1406
FID C 5 845
FID C 3 3710
SNT TOP T 170 194
FID C 4 1407
FID C 5 846
FID C 3 3712
SNT TOP T 170 213
FID C 4 1398
FID C 5 837
FID C 3 3694
SNT TOP T 170 232
FID C 4 1365
FID C 5 814
FID C 3 3627
SNT TOP T 170 261
FID C 4 1408
FID C 5 847
FID C 3 3714
SNT TOP T 170 280
FID C 4 1399
FID C 5 838
FID C 3 3696
SNT TOP T 170 299
FID C 4 1360
FID C 5 809
FID C 3 3612
SNT TOP T 170 328
FID C 4 1409
FID C 5 848
FID C 3 3716
SNT TOP T 170 347
FID C 4 1400
FID C 5 839
FID C 3 3698
SNT TOP T 170 366
FID C 4 1401
FID C 5 840
FID C 3 3700
SNT TOP T 170 385
FID C 4 1396
FID C 5 835
FID C 3 3690
SNT TOP T 170 395
FID C 4 1410
FID C 5 849
FID C 3 3718
SNT TOP T 170 414
FID C 4 1411
FID C 5 850
FID C 3 3720
SNT TOP T 170 433
FID C 4 1402
FID C 5 841
FID C 3 3702
SNT TOP T 170 452
FID C 4 1397
FID C 5 836
FID C 3 3692
SNT TOP T 170 471
FID C 4 1356
FID C 5 806
FID C 3 3601
SNT TOP T 170 481
FID C 4 1412
FID C 5 851
FID C 3 3722
SNT TOP T 174 0
FID C 4 1395
FID C 5 834
FID C 3 3688
SNT TOP T 175 0
FID C 4 1336
FID C 5 797
FID C 3 3554
SNT TOP T 179 11
FID C 4 1355
FID C 5 805
FID C 3 3599
SNT TOP T 183 7
FID C 4 1570
FID C 5 923
FID C 3 4022
SNT TOP T 186 7
FID C 4 1514
FID C 5 897
FID C 3 3925
SNT TOP T 188 7
FID C 4 1432
FID C 5 860
FID C 3 3770
SNT TOP T 198 1
FID C 4 1498
FID C 5 889
FID C 3 3889
SNT TOP T 199 0
FID C 4 1490
FID C 5 886
FID C 3 3870
SNT TOP T 204 0
FID C 4 1496
FID C 5 888
FID C 3 3886
SNT TOP T 218 0
FID C 4 1338
FID C 5 798
FID C 3 3556
SNT TOP T 219 0
FID C 4 1357
FID C 5 807
FID C 3 3605
SNT TOP T 225 1
FID C 4 1471
FID C 5 877
FID C 3 3833
SNT TOP T 243 0
FID C 4 1484
FID C 5 883
FID C 3 3854
SNT TOP T 244 0
FID C 4 1486
FID C 5 884
FID C 3 3857
SNT TOP T 245 0
FID C 4 1477
FID C 5 880
FID C 3 3840
SNT TOP T 246 0
FID C 4 1476
FID C 5 879
FID C 3 3839
SNT TOP T 247 1
FID C 4 1373
FID C 5 821
FID C 3 3638
SNT TOP T 251 0
FID C 4 1377
FID C 5 823
FID C 3 3647
SNT TOP T 252 0
FID C 4 1376
FID C 5 822
FID C 3 3645
SNT TOP T 253 0
FID C 4 1378
FID C 5 824
FID C 3 3649
SNT TOP T 254 0
FID C 4 1382
FID C 5 828
FID C 3 3656
SNT TOP T 255 0
FID C 4 1383
FID C 5 829
FID C 3 3658
SNT TOP T 302 0
FID C 4 1573
FID C 5 925
FID C 3 4028
SNT TOP T 303 0
FID C 4 1316
FID C 5 791
FID C 3 3526
SNT TOP T 306 0
FID C 4 1530
FID C 5 903
FID C 3 3949
SNT TOP T 307 0
FID C 4 1532
FID C 5 904
FID C 3 3952
SNT TOP T 308 0
FID C 4 1541
FID C 5 908
FID C 3 3969
SNT TOP T 309 0
FID C 4 1544
FID C 5 909
FID C 3 3973
SNT TOP T 310 0
FID C 4 1552
FID C 5 914
FID C 3 3990
SNT TOP T 311 0
FID C 4 1551
FID C 5 913
FID C 3 3987
SNT TOP T 333 0
FID C 4 1560
FID C 5 918
FID C 3 4003
SNT TOP T 334 0
FID C 4 1559
FID C 5 917
FID C 3 4002
SNT TOP T 341 0
FID C 4 1522
FID C 5 899
FID C 3 3936
SNT TOP T 342 0
FID C 4 1512
FID C 5 895
FID C 3 3914
SNT TOP T 343 0
FID C 4 1513
FID C 5 896
FID C 3 3916
SNT TOP T 344 0
FID C 4 1511
FID C 5 894
FID C 3 3913
SNT TOP T 347 0
FID C 4 1321
FID C 5 792
FID C 3 3531
SNT TOP T 351 0
FID C 4 1505
FID C 5 892
FID C 3 3904
SNT TOP T 352 0
FID C 4 1506
FID C 5 893
FID C 3 3906
SNT TOP T 360 0
FID C 4 1351
FID C 5 804
FID C 3 3591
SNT TOP T 361 0
FID C 4 1391
FID C 5 833
FID C 3 3683
SNT TOP T 362 0
FID C 4 1348
FID C 5 802
FID C 3 3586
SNT TOP T 370 0
FID C 4 1349
FID C 5 803
FID C 3 3587
SNT TOP T 371 0
FID C 4 1417
FID C 5 854
FID C 3 3735
SNT TOP T 373 0
FID C 4 1418
FID C 5 855
FID C 3 3737
SNT TOP T 378 0
FID C 4 1420
FID C 5 856
FID C 3 3739
SNT TOP T 386 0
FID C 4 1459
FID C 5 871
FID C 3 3814
SNT TOP T 395 0
FID C 4 1429
FID C 5 859
FID C 3 3766
SNT TOP T 405 0
FID C 4 1380
FID C 5 826
FID C 3 3653
SNT TOP T 406 0
FID C 4 1381
FID C 5 827
FID C 3 3655
SNT TOP T 411 0
FID C 4 1441
FID C 5 865
FID C 3 3782
SNT TOP T 412 0
FID C 4 1439
FID C 5 864
FID C 3 3779
SNT TOP T 413 0
FID C 4 1438
FID C 5 863
FID C 3 3777
SNT TOP T 414 0
FID C 4 1572
FID C 5 924
FID C 3 4026
SNT TOP T 417 0
FID C 4 1451
FID C 5 868
FID C 3 3794
SNT TOP T 420 0
FID C 4 1454
FID C 5 869
FID C 3 3805
SNT TOP T 423 0
FID C 4 1379
FID C 5 825
FID C 3 3651
SNT TOP T 425 0
FID C 4 1345
FID C 5 801
FID C 3 3576
SNT TOP T 499 0
FID C 4 1386
FID C 5 832
FID C 3 3678
SNT TOP T 501 0
FID C 4 1385
FID C 5 831
FID C 3 3677
SNT TOP T 516 0
FID C 4 1491
FID C 5 887
FID C 3 3873
SNT TOP T 522 0
FID C 4 1467
FID C 5 876
FID C 3 3825
SNT TOP T 526 0
FID C 4 1525
FID C 5 901
FID C 3 3943
SNT TOP T 527 0
FID C 4 1537
FID C 5 907
FID C 3 3961
SNT TOP T 528 0
FID C 4 1548
FID C 5 912
FID C 3 3980
SNT TOP T 536 0
FID C 4 1564
FID C 5 920
FID C 3 4010
SNT TOP T 544 0
FID C 4 1569
FID C 5 922
FID C 3 4021
SNT TOP T 546 1
FID C 4 1504
FID C 5 891
FID C 3 3903
SNT TOP T 548 0
FID C 4 1481
FID C 5 882
FID C 3 3847
SNT TOP T 562 0
FID C 4 1384
FID C 5 830
FID C 3 3676
SNT TOP T 565 0
FID C 4 1461
FID C 5 872
FID C 3 3816
SNT TOP T 574 0
FID C 4 1335
FID C 5 796
FID C 3 3551
SNT TOP T 576 0
FID C 4 1464
FID C 5 873
FID C 3 3822
SNT TOP T 582 0
FID C 4 1426
FID C 5 857
FID C 3 3759
SNT TOP T 585 1
FID C 4 1433
FID C 5 861
FID C 3 3771
SNT TOP T 587 0
FID C 4 1448
FID C 5 867
FID C 3 3791
SNT TOP T 592 0
FID C 4 1343
FID C 5 799
FID C 3 3574
SNT TOP T 597 4
FID C 4 1489
FID C 5 885
FID C 3 3866
SNT TOP T 598 4
FID C 4 1414
FID C 5 852
FID C 3 3731
SNT TOP T 598 5
FID C 4 1416
FID C 5 853
FID C 3 3733
SNT TOP B 17 0
FID C 6 860
FID C 7 243
FID C 8 2490
SNT TOP B 28 0
FID C 6 857
FID C 7 241
FID C 8 2479
SNT TOP B 35 0
FID C 6 888
FID C 7 262
FID C 8 2567
SNT TOP B 48 0
FID C 6 889
FID C 7 263
FID C 8 2569
SNT TOP B 49 0
FID C 6 890
FID C 7 264
FID C 8 2570
SNT TOP B 50 0
FID C 6 852
FID C 7 236
FID C 8 2464
SNT TOP B 51 0
FID C 6 851
FID C 7 235
FID C 8 2463
SNT TOP B 54 0
FID C 6 892
FID C 7 266
FID C 8 2575
SNT TOP B 55 0
FID C 6 881
FID C 7 255
FID C 8 2558
SNT TOP B 56 0
FID C 6 882
FID C 7 256
FID C 8 2559
SNT TOP B 57 0
FID C 6 893
FID C 7 267
FID C 8 2576
SNT TOP B 58 0
FID C 6 854
FID C 7 238
FID C 8 2471
SNT TOP B 59 0
FID C 6 858
FID C 7 242
FID C 8 2487
SNT TOP B 63 0
FID C 6 878
FID C 7 252
FID C 8 2553
SNT TOP B 64 0
FID C 6 880
FID C 7 254
FID C 8 2556
SNT TOP B 65 0
FID C 6 849
FID C 7 234
FID C 8 2455
SNT TOP B 72 0
FID C 6 884
FID C 7 258
FID C 8 2561
SNT TOP B 73 0
FID C 6 862
FID C 7 245
FID C 8 2497
SNT TOP B 74 0
FID C 6 879
FID C 7 253
FID C 8 2555
SNT TOP B 75 0
FID C 6 885
FID C 7 259
FID C 8 2562
SNT TOP B 79 0
FID C 6 896
FID C 7 270
FID C 8 2580
SNT TOP B 80 0
FID C 6 894
FID C 7 268
FID C 8 2578
SNT TOP B 81 0
FID C 6 886
FID C 7 260
FID C 8 2563
SNT TOP B 84 0
FID C 6 856
FID C 7 240
FID C 8 2477
SNT TOP B 86 0
FID C 6 855
FID C 7 239
FID C 8 2474
SNT TOP B 90 0
FID C 6 897
FID C 7 271
FID C 8 2584
SNT TOP B 94 0
FID C 6 898
FID C 7 272
FID C 8 2585
SNT TOP B 99 0
FID C 6 891
FID C 7 265
FID C 8 2571
SNT TOP B 101 0
FID C 6 895
FID C 7 269
FID C 8 2579
SNT TOP B 108 7
FID C 6 986
FID C 7 302
FID C 8 2739
SNT TOP B 129 0
FID C 6 958
FID C 7 295
FID C 8 2690
SNT TOP B 130 0
FID C 6 823
FID C 7 224
FID C 8 2412
SNT TOP B 131 1
FID C 6 908
FID C 7 275
FID C 8 2601
SNT TOP B 166 1
FID C 6 804
FID C 7 214
FID C 8 2381
SNT TOP B 175 0
FID C 6 861
FID C 7 244
FID C 8 2496
SNT TOP B 184 0
FID C 6 1006
FID C 7 309
FID C 8 2779
SNT TOP B 187 0
FID C 6 984
FID C 7 300
FID C 8 2736
SNT TOP B 189 0
FID C 6 1027
FID C 7 317
FID C 8 2811
SNT TOP B 191 0
FID C 6 990
FID C 7 304
FID C 8 2748
SNT TOP B 193 0
FID C 6 991
FID C 7 305
FID C 8 2750
SNT TOP B 195 0
FID C 6 988
FID C 7 303
FID C 8 2745
SNT TOP B 201 0
FID C 6 995
FID C 7 306
FID C 8 2763
SNT TOP B 202 0
FID C 6 996
FID C 7 307
FID C 8 2765
SNT TOP B 204 0
FID C 6 1024
FID C 7 315
FID C 8 2805
SNT TOP B 205 0
FID C 6 999
FID C 7 308
FID C 8 2771
SNT TOP B 209 0
FID C 6 1008
FID C 7 310
FID C 8 2782
SNT TOP B 222 0
FID C 6 1025
FID C 7 316
FID C 8 2806
SNT TOP B 229 0
FID C 6 843
FID C 7 231
FID C 8 2445
SNT TOP B 230 1
FID C 6 902
FID C 7 273
FID C 8 2591
SNT TOP B 231 0
FID C 6 845
FID C 7 232
FID C 8 2447
SNT TOP B 232 0
FID C 6 871
FID C 7 249
FID C 8 2545
SNT TOP B 237 0
FID C 6 841
FID C 7 230
FID C 8 2441
SNT TOP B 238 0
FID C 6 840
FID C 7 229
FID C 8 2439
SNT TOP B 242 0
FID C 6 978
FID C 7 297
FID C 8 2723
SNT TOP B 245 0
FID C 6 965
FID C 7 296
FID C 8 2707
SNT TOP B 253 0
FID C 6 904
FID C 7 274
FID C 8 2593
SNT TOP B 256 0
FID C 6 833
FID C 7 228
FID C 8 2426
SNT TOP B 258 1
FID C 6 870
FID C 7 248
FID C 8 2543
SNT TOP B 260 0
FID C 6 873
FID C 7 250
FID C 8 2547
SNT TOP B 265 0
FID C 6 811
FID C 7 218
FID C 8 2390
SNT TOP B 268 0
FID C 6 805
FID C 7 215
FID C 8 2382
SNT TOP B 269 0
FID C 6 806
FID C 7 216
FID C 8 2384
SNT TOP B 272 0
FID C 6 808
FID C 7 217
FID C 8 2387
SNT TOP B 278 1
FID C 6 817
FID C 7 221
FID C 8 2400
SNT TOP B 281 1
FID C 6 824
FID C 7 225
FID C 8 2415
SNT TOP B 282 0
FID C 6 825
FID C 7 226
FID C 8 2417
SNT TOP B 284 1
FID C 6 827
FID C 7 227
FID C 8 2420
SNT TOP B 287 1
FID C 6 819
FID C 7 222
FID C 8 2404
SNT TOP B 288 0
FID C 6 813
FID C 7 219
FID C 8 2395
SNT TOP B 291 0
FID C 6 910
FID C 7 276
FID C 8 2609
SNT TOP B 295 0
FID C 6 945
FID C 7 287
FID C 8 2670
SNT TOP B 296 0
FID C 6 944
FID C 7 286
FID C 8 2668
SNT TOP B 302 0
FID C 6 926
FID C 7 281
FID C 8 2639
SNT TOP B 304 0
FID C 6 924
FID C 7 280
FID C 8 2636
SNT TOP B 313 1
FID C 6 937
FID C 7 284
FID C 8 2655
SNT TOP B 314 1
FID C 6 954
FID C 7 293
FID C 8 2685
SNT TOP B 315 0
FID C 6 1022
FID C 7 314
FID C 8 2801
SNT TOP B 316 0
FID C 6 922
FID C 7 279
FID C 8 2634
SNT TOP B 317 0
FID C 6 932
FID C 7 282
FID C 8 2646
SNT TOP B 318 1
FID C 6 949
FID C 7 289
FID C 8 2676
SNT TOP B 319 1
FID C 6 948
FID C 7 288
FID C 8 2675
SNT TOP B 325 0
FID C 6 1019
FID C 7 313
FID C 8 2796
SNT TOP B 326 1
FID C 6 953
FID C 7 292
FID C 8 2684
SNT TOP B 327 1
FID C 6 952
FID C 7 291
FID C 8 2682
SNT TOP B 328 1
FID C 6 955
FID C 7 294
FID C 8 2687
SNT TOP B 329 0
FID C 6 1018
FID C 7 312
FID C 8 2794
SNT TOP B 330 1
FID C 6 951
FID C 7 290
FID C 8 2680
SNT TOP B 339 0
FID C 6 915
FID C 7 277
FID C 8 2626
SNT TOP B 340 0
FID C 6 916
FID C 7 278
FID C 8 2628
SNT TOP B 342 0
FID C 6 933
FID C 7 283
FID C 8 2647
SNT TOP B 369 0
FID C 6 866
FID C 7 247
FID C 8 2539
SNT TOP B 370 0
FID C 6 865
FID C 7 246
FID C 8 2538
SNT TOP B 387 0
FID C 6 848
FID C 7 233
FID C 8 2453
SNT TOP B 390 0
FID C 6 815
FID C 7 220
FID C 8 2398
SNT TOP B 393 0
FID C 6 821
FID C 7 223
FID C 8 2406
SNT TOP B 394 1
FID C 6 985
FID C 7 301
FID C 8 2738
SNT TOP B 395 0
FID C 6 1030
FID C 7 318
FID C 8 2816
SNT TOP B 396 0
FID C 6 1017
FID C 7 311
FID C 8 2793
SNT TOP B 400 0
FID C 6 887
FID C 7 261
FID C 8 2565
SNT TOP B 416 0
FID C 6 980
FID C 7 299
FID C 8 2729
SNT TOP B 418 0
FID C 6 883
FID C 7 257
FID C 8 2560
SNT TOP B 419 0
FID C 6 853
FID C 7 237
FID C 8 2470
SNT TOP B 422 0
FID C 6 877
FID C 7 251
FID C 8 2552
SNT TOP B 437 0
FID C 6 939
FID C 7 285
FID C 8 2660
SNT TOP B 444 4
FID C 6 979
FID C 7 298
FID C 8 2726
SNT VIA
FID H 0 909
FID C 4 1563
FID C 6 1023
FID C 3 4007
FID C 8 2802
FID L 11 937
FID L 12 937
FID L 15 937
FID L 16 937
SNT VIA
FID H 0 910
FID C 4 1546
FID C 6 1011
FID C 3 3978
FID C 8 2785
FID L 11 929
FID L 12 929
FID L 15 929
FID L 16 929
SNT VIA
FID H 0 911
FID C 4 1529
FID C 6 1000
FID C 3 3947
FID C 8 2772
FID L 11 920
FID L 12 920
FID L 15 920
FID L 16 920
SNT VIA
FID H 0 912
FID C 4 1516
FID C 6 982
FID C 3 3928
FID C 8 2734
FID L 11 911
FID L 12 911
FID L 15 911
FID L 16 911
SNT VIA
FID H 0 913
FID C 4 1535
FID C 6 1003
FID C 3 3957
FID C 8 2775
FID L 11 923
FID L 12 923
FID L 15 923
FID L 16 923
SNT VIA
FID H 0 914
FID C 4 1555
FID C 6 1015
FID C 3 3994
FID C 8 2789
FID L 11 933
FID L 12 933
FID L 15 933
FID L 16 933
SNT VIA
FID H 0 915
FID C 4 1561
FID C 6 1021
FID C 3 4004
FID C 8 2800
FID L 11 936
FID L 12 936
FID L 15 936
FID L 16 936
SNT VIA
FID H 0 916
FID C 4 1502
FID C 6 974
FID C 3 3901
FID C 9 1968
FID C 8 2719
FID L 11 906
FID L 12 906
FID L 13 839
FID L 15 906
FID L 16 906
SNT VIA
FID H 0 917
FID C 4 1571
FID C 6 1031
FID C 3 4025
FID C 10 2618
FID C 8 2819
FID L 11 941
FID L 12 941
FID L 15 941
FID L 16 941
SNT VIA
FID H 0 918
FID C 4 1519
FID C 6 989
FID C 3 3931
FID C 8 2746
FID L 11 914
FID L 12 914
FID L 15 914
FID L 16 914
SNT VIA
FID H 0 919
FID C 4 1499
FID C 6 971
FID C 3 3895
FID C 10 2608
FID C 8 2716
FID L 11 903
FID L 12 903
FID L 15 903
FID L 16 903
SNT VIA
FID H 0 920
FID C 4 1500
FID C 6 972
FID C 3 3896
FID C 10 2609
FID C 8 2717
FID L 11 904
FID L 12 904
FID L 15 904
FID L 16 904
SNT VIA
FID H 0 921
FID C 4 1501
FID C 6 973
FID C 3 3897
FID C 10 2616
FID C 8 2718
FID L 11 905
FID L 12 905
FID L 13 838
FID L 15 905
FID L 16 905
SNT VIA
FID H 0 922
FID C 4 1320
FID C 6 810
FID C 3 3530
FID C 8 2389
FID L 11 796
FID L 12 796
FID L 13 779
FID L 15 796
FID L 16 796
SNT VIA
FID H 0 923
FID C 4 1493
FID C 6 967
FID C 3 3882
FID C 10 2599
FID C 8 2709
FID L 11 899
FID L 12 899
FID L 13 836
FID L 14 783
FID L 15 899
FID L 16 899
SNT VIA
FID H 0 924
FID C 4 1495
FID C 6 969
FID C 3 3884
FID C 10 2601
FID C 8 2711
FID L 11 901
FID L 12 901
FID L 13 837
FID L 15 901
FID L 16 901
SNT VIA
FID H 0 925
FID C 4 1494
FID C 6 968
FID C 3 3883
FID C 10 2600
FID C 8 2710
FID L 11 900
FID L 12 900
FID L 15 900
FID L 16 900
SNT VIA
FID H 0 926
FID C 4 1518
FID C 6 987
FID C 3 3930
FID C 8 2741
FID L 11 913
FID L 12 913
FID L 15 913
FID L 16 913
SNT VIA
FID H 0 927
FID C 4 1509
FID C 6 977
FID C 3 3910
FID C 8 2722
FID L 11 909
FID L 12 909
FID L 15 909
FID L 16 909
SNT VIA
FID H 0 928
FID C 4 1488
FID C 6 964
FID C 3 3863
FID C 8 2703
FID L 11 897
FID L 12 897
FID L 13 834
FID L 15 897
FID L 16 897
SNT VIA
FID H 0 929
FID C 4 1497
FID C 6 970
FID C 3 3887
FID C 8 2712
FID L 11 902
FID L 12 902
FID L 15 902
FID L 16 902
SNT VIA
FID H 0 930
FID C 4 1317
FID C 6 803
FID C 3 3527
FID C 9 1885
FID C 8 2380
FID L 11 793
FID L 12 793
FID L 13 776
FID L 15 793
FID L 16 793
SNT VIA
FID H 0 931
FID C 4 1507
FID C 6 975
FID C 3 3908
FID C 8 2720
FID L 11 907
FID L 12 907
FID L 15 907
FID L 16 907
SNT VIA
FID H 0 932
FID C 4 1347
FID C 6 839
FID C 3 3585
FID C 8 2438
FID L 11 814
FID L 12 814
FID L 13 797
FID L 15 814
FID L 16 814
SNT VIA
FID H 0 933
FID C 4 1346
FID C 6 838
FID C 3 3577
FID C 8 2432
FID L 11 813
FID L 12 813
FID L 13 796
FID L 15 813
FID L 16 813
SNT VIA
FID H 0 934
FID C 4 1340
FID C 6 834
FID C 3 3561
FID C 8 2427
FID L 11 809
FID L 12 809
FID L 13 792
FID L 15 809
FID L 16 809
SNT VIA
FID H 0 935
FID C 4 1334
FID C 6 830
FID C 3 3548
FID C 8 2423
FID L 11 806
FID L 12 806
FID L 13 789
FID L 15 806
FID L 16 806
SNT VIA
FID H 0 936
FID C 4 1332
FID C 6 829
FID C 3 3545
FID C 9 1906
FID C 8 2422
FID L 11 805
FID L 12 805
FID L 13 788
FID L 14 748
FID L 15 805
FID L 16 805
SNT VIA
FID H 0 937
FID C 4 1341
FID C 6 836
FID C 3 3572
FID C 8 2430
FID L 11 811
FID L 12 811
FID L 13 794
FID L 15 811
FID L 16 811
SNT VIA
FID H 0 938
FID C 4 1323
FID C 6 814
FID C 3 3534
FID C 8 2396
FID L 11 798
FID L 12 798
FID L 13 781
FID L 15 798
FID L 16 798
SNT VIA
FID H 0 939
FID C 4 1354
FID C 6 847
FID C 3 3594
FID C 8 2450
FID L 11 818
FID L 12 818
FID L 13 801
FID L 15 818
FID L 16 818
SNT VIA
FID H 0 940
FID C 4 1342
FID C 6 837
FID C 3 3573
FID C 8 2431
FID L 11 812
FID L 12 812
FID L 13 795
FID L 15 812
FID L 16 812
SNT VIA
FID H 0 941
FID C 4 1327
FID C 6 820
FID C 3 3539
FID C 9 1893
FID C 10 2551
FID C 8 2405
FID L 11 801
FID L 12 801
FID L 13 784
FID L 14 744
FID L 15 801
FID L 16 801
SNT VIA
FID H 0 942
FID C 4 1339
FID C 6 832
FID C 3 3557
FID C 8 2425
FID L 11 808
FID L 12 808
FID L 13 791
FID L 15 808
FID L 16 808
SNT VIA
FID H 0 943
FID C 4 1326
FID C 6 818
FID C 3 3538
FID C 9 1892
FID C 8 2402
FID L 11 800
FID L 12 800
FID L 13 783
FID L 14 743
FID L 15 800
FID L 16 800
SNT VIA
FID H 0 944
FID C 4 1330
FID C 6 826
FID C 3 3543
FID C 9 1904
FID C 8 2418
FID L 11 803
FID L 12 803
FID L 13 786
FID L 14 746
FID L 15 803
FID L 16 803
SNT VIA
FID H 0 945
FID C 4 1415
FID C 6 900
FID C 3 3732
FID C 10 2560
FID C 8 2589
FID L 11 856
FID L 12 856
FID L 13 804
FID L 14 759
FID L 15 856
FID L 16 856
SNT VIA
FID H 0 946
FID C 4 1520
FID C 6 992
FID C 3 3932
FID C 8 2752
FID L 11 915
FID L 12 915
FID L 15 915
FID L 16 915
SNT VIA
FID H 0 947
FID C 4 1374
FID C 6 863
FID C 3 3642
FID C 10 2559
FID C 8 2499
FID L 11 829
FID L 12 829
FID L 13 803
FID L 14 758
FID L 15 829
FID L 16 829
SNT VIA
FID H 0 948
FID C 4 1358
FID C 6 850
FID C 3 3606
FID C 8 2457
FID L 11 820
FID L 12 820
FID L 14 749
FID L 15 820
FID L 16 820
SNT VIA
FID H 0 949
FID C 4 1424
FID C 6 907
FID C 3 3753
FID C 9 1917
FID C 8 2600
FID L 11 861
FID L 12 861
FID L 13 808
FID L 14 761
FID L 15 861
FID L 16 861
SNT VIA
FID H 0 950
FID C 4 1366
FID C 6 859
FID C 3 3631
FID C 8 2489
FID L 11 828
FID L 12 828
FID L 14 757
FID L 15 828
FID L 16 828
SNT VIA
FID H 0 951
FID C 4 1324
FID C 6 816
FID C 3 3536
FID C 9 1891
FID C 8 2399
FID L 11 799
FID L 12 799
FID L 13 782
FID L 14 742
FID L 15 799
FID L 16 799
SNT VIA
FID H 0 952
FID C 4 1413
FID C 6 899
FID C 3 3723
FID C 8 2586
FID L 11 855
FID L 12 855
FID L 15 855
FID L 16 855
SNT VIA
FID H 0 953
FID C 4 1328
FID C 6 822
FID C 3 3540
FID C 9 1894
FID C 8 2409
FID L 11 802
FID L 12 802
FID L 13 785
FID L 14 745
FID L 15 802
FID L 16 802
SNT VIA
FID H 0 954
FID C 4 1375
FID C 6 864
FID C 3 3643
FID C 8 2500
FID L 11 830
FID L 12 830
FID L 15 830
FID L 16 830
SNT VIA
FID H 0 955
FID C 4 1469
FID C 6 943
FID C 3 3831
FID C 9 1943
FID C 8 2665
FID L 11 886
FID L 12 886
FID L 13 824
FID L 14 775
FID L 15 886
FID L 16 886
SNT VIA
FID H 0 956
FID C 4 1425
FID C 6 909
FID C 3 3754
FID C 9 1918
FID C 8 2602
FID L 11 862
FID L 12 862
FID L 13 809
FID L 14 762
FID L 15 862
FID L 16 862
SNT VIA
FID H 0 957
FID C 4 1392
FID C 6 874
FID C 3 3685
FID C 8 2549
FID L 11 852
FID L 12 852
FID L 15 852
FID L 16 852
SNT VIA
FID H 0 958
FID C 4 1470
FID C 6 946
FID C 3 3832
FID C 8 2671
FID L 11 887
FID L 12 887
FID L 13 825
FID L 14 776
FID L 15 887
FID L 16 887
SNT VIA
FID H 0 959
FID C 4 1468
FID C 6 942
FID C 3 3830
FID C 8 2664
FID L 11 885
FID L 12 885
FID L 13 823
FID L 14 774
FID L 15 885
FID L 16 885
SNT VIA
FID H 0 960
FID C 4 1463
FID C 6 941
FID C 3 3821
FID C 9 1940
FID C 8 2663
FID L 11 884
FID L 12 884
FID L 13 822
FID L 14 773
FID L 15 884
FID L 16 884
SNT VIA
FID H 0 961
FID C 4 1390
FID C 6 872
FID C 3 3682
FID C 8 2546
FID L 11 851
FID L 12 851
FID L 15 851
FID L 16 851
SNT VIA
FID H 0 962
FID C 4 1457
FID C 6 935
FID C 3 3811
FID C 8 2653
FID L 11 880
FID L 12 880
FID L 13 818
FID L 15 880
FID L 16 880
SNT VIA
FID H 0 963
FID C 4 1479
FID C 6 959
FID C 3 3845
FID C 10 2583
FID C 8 2691
FID L 11 892
FID L 12 892
FID L 13 829
FID L 14 780
FID L 15 892
FID L 16 892
SNT VIA
FID H 0 964
FID C 4 1455
FID C 6 934
FID C 3 3806
FID C 8 2650
FID L 11 879
FID L 12 879
FID L 13 817
FID L 15 879
FID L 16 879
SNT VIA
FID H 0 965
FID C 4 1478
FID C 6 957
FID C 3 3841
FID C 10 2582
FID C 8 2689
FID L 11 891
FID L 12 891
FID L 13 828
FID L 14 779
FID L 15 891
FID L 16 891
SNT VIA
FID H 0 966
FID C 4 1394
FID C 6 876
FID C 3 3687
FID C 8 2551
FID L 11 854
FID L 12 854
FID L 15 854
FID L 16 854
SNT VIA
FID H 0 967
FID C 4 1393
FID C 6 875
FID C 3 3686
FID C 8 2550
FID L 11 853
FID L 12 853
FID L 15 853
FID L 16 853
SNT VIA
FID H 0 968
FID C 4 1352
FID C 6 844
FID C 3 3592
FID C 8 2446
FID L 11 816
FID L 12 816
FID L 13 799
FID L 15 816
FID L 16 816
SNT VIA
FID H 0 969
FID C 4 1350
FID C 6 842
FID C 3 3590
FID C 8 2442
FID L 11 815
FID L 12 815
FID L 13 798
FID L 15 815
FID L 16 815
SNT VIA
FID H 0 970
FID C 4 1428
FID C 6 911
FID C 3 3765
FID C 8 2619
FID L 11 863
FID L 12 863
FID L 13 810
FID L 14 763
FID L 15 863
FID L 16 863
SNT VIA
FID H 0 971
FID C 4 1422
FID C 6 905
FID C 3 3741
FID C 10 2569
FID C 8 2595
FID L 11 859
FID L 12 859
FID L 13 807
FID L 15 859
FID L 16 859
SNT VIA
FID H 0 972
FID C 4 1353
FID C 6 846
FID C 3 3593
FID C 8 2449
FID L 11 817
FID L 12 817
FID L 13 800
FID L 15 817
FID L 16 817
SNT VIA
FID H 0 973
FID C 4 1419
FID C 6 901
FID C 3 3738
FID C 10 2568
FID C 8 2590
FID L 11 857
FID L 12 857
FID L 13 805
FID L 14 760
FID L 15 857
FID L 16 857
SNT VIA
FID H 0 974
FID C 4 1553
FID C 6 1014
FID C 3 3991
FID C 8 2788
FID L 11 932
FID L 12 932
FID L 15 932
FID L 16 932
SNT VIA
FID H 0 975
FID C 4 1542
FID C 6 1009
FID C 3 3971
FID C 8 2783
FID L 11 927
FID L 12 927
FID L 15 927
FID L 16 927
SNT VIA
FID H 0 976
FID C 4 1531
FID C 6 1001
FID C 3 3950
FID C 8 2773
FID L 11 921
FID L 12 921
FID L 15 921
FID L 16 921
SNT VIA
FID H 0 977
FID C 4 1443
FID C 6 920
FID C 3 3786
FID C 8 2632
FID L 11 870
FID L 12 870
FID L 13 811
FID L 14 764
FID L 15 870
FID L 16 870
SNT VIA
FID H 0 978
FID C 4 1460
FID C 6 938
FID C 3 3815
FID C 9 1936
FID C 10 2570
FID C 8 2659
FID L 11 882
FID L 12 882
FID L 13 820
FID L 14 771
FID L 15 882
FID L 16 882
SNT VIA
FID H 0 979
FID C 4 1482
FID C 6 960
FID C 3 3848
FID C 10 2584
FID C 8 2692
FID L 11 893
FID L 12 893
FID L 13 830
FID L 14 781
FID L 15 893
FID L 16 893
SNT VIA
FID H 0 980
FID C 4 1487
FID C 6 963
FID C 3 3858
FID C 8 2700
FID L 11 896
FID L 12 896
FID L 13 833
FID L 15 896
FID L 16 896
SNT VIA
FID H 0 981
FID C 4 1485
FID C 6 962
FID C 3 3855
FID C 8 2699
FID L 11 895
FID L 12 895
FID L 13 832
FID L 14 782
FID L 15 895
FID L 16 895
SNT VIA
FID H 0 982
FID C 4 1444
FID C 6 921
FID C 3 3787
FID C 9 1922
FID C 8 2633
FID L 11 871
FID L 12 871
FID L 13 812
FID L 14 765
FID L 15 871
FID L 16 871
SNT VIA
FID H 0 983
FID C 4 1445
FID C 6 923
FID C 3 3788
FID C 9 1923
FID C 8 2635
FID L 11 872
FID L 12 872
FID L 13 813
FID L 14 766
FID L 15 872
FID L 16 872
SNT VIA
FID H 0 984
FID C 4 1453
FID C 6 931
FID C 3 3796
FID C 9 1926
FID C 8 2645
FID L 11 878
FID L 12 878
FID L 13 816
FID L 14 769
FID L 15 878
FID L 16 878
SNT VIA
FID H 0 985
FID C 4 1521
FID C 6 993
FID C 3 3935
FID C 8 2757
FID L 11 916
FID L 12 916
FID L 15 916
FID L 16 916
SNT VIA
FID H 0 986
FID C 4 1492
FID C 6 966
FID C 3 3874
FID C 8 2708
FID L 11 898
FID L 12 898
FID L 13 835
FID L 15 898
FID L 16 898
SNT VIA
FID H 0 987
FID C 4 1483
FID C 6 961
FID C 3 3852
FID C 8 2693
FID L 11 894
FID L 12 894
FID L 13 831
FID L 15 894
FID L 16 894
SNT VIA
FID H 0 988
FID C 4 1446
FID C 6 925
FID C 3 3789
FID C 9 1924
FID C 8 2637
FID L 11 873
FID L 12 873
FID L 13 814
FID L 14 767
FID L 15 873
FID L 16 873
SNT VIA
FID H 0 989
FID C 4 1452
FID C 6 930
FID C 3 3795
FID C 9 1925
FID C 8 2643
FID L 11 877
FID L 12 877
FID L 13 815
FID L 14 768
FID L 15 877
FID L 16 877
SNT VIA
FID H 0 990
FID C 4 1533
FID C 6 1002
FID C 3 3953
FID C 8 2774
FID L 11 922
FID L 12 922
FID L 15 922
FID L 16 922
SNT VIA
FID H 0 991
FID C 4 1473
FID C 6 950
FID C 3 3835
FID C 10 2573
FID C 8 2678
FID L 11 889
FID L 12 889
FID L 13 827
FID L 14 778
FID L 15 889
FID L 16 889
SNT VIA
FID H 0 992
FID C 4 1450
FID C 6 929
FID C 3 3793
FID C 8 2642
FID L 11 876
FID L 12 876
FID L 15 876
FID L 16 876
SNT VIA
FID H 0 993
FID C 4 1437
FID C 6 918
FID C 3 3775
FID C 8 2630
FID L 11 868
FID L 12 868
FID L 15 868
FID L 16 868
SNT VIA
FID H 0 994
FID C 4 1435
FID C 6 917
FID C 3 3773
FID C 8 2629
FID L 11 867
FID L 12 867
FID L 15 867
FID L 16 867
SNT VIA
FID H 0 995
FID C 4 1430
FID C 6 912
FID C 3 3767
FID C 8 2620
FID L 11 864
FID L 12 864
FID L 15 864
FID L 16 864
SNT VIA
FID H 0 996
FID C 4 1568
FID C 6 1029
FID C 3 4017
FID C 8 2815
FID L 11 940
FID L 12 940
FID L 15 940
FID L 16 940
SNT VIA
FID H 0 997
FID C 4 1472
FID C 6 947
FID C 3 3834
FID C 10 2572
FID C 8 2674
FID L 11 888
FID L 12 888
FID L 13 826
FID L 14 777
FID L 15 888
FID L 16 888
SNT VIA
FID H 0 998
FID C 4 1315
FID C 6 802
FID C 3 3523
FID C 8 2377
FID L 11 792
FID L 12 792
FID L 15 792
FID L 16 792
SNT VIA
FID H 0 999
FID C 4 1566
FID C 6 1028
FID C 3 4015
FID C 8 2812
FID L 11 939
FID L 12 939
FID L 15 939
FID L 16 939
SNT VIA
FID H 0 1000
FID C 4 1543
FID C 6 1010
FID C 3 3972
FID C 8 2784
FID L 11 928
FID L 12 928
FID L 15 928
FID L 16 928
SNT VIA
FID H 0 1001
FID C 4 1434
FID C 6 914
FID C 3 3772
FID C 8 2625
FID L 11 866
FID L 12 866
FID L 15 866
FID L 16 866
SNT VIA
FID H 0 1002
FID C 4 1449
FID C 6 928
FID C 3 3792
FID C 8 2641
FID L 11 875
FID L 12 875
FID L 15 875
FID L 16 875
SNT VIA
FID H 0 1003
FID C 4 1474
FID C 6 956
FID C 3 3836
FID C 10 2577
FID C 8 2688
FID L 11 890
FID L 12 890
FID L 15 890
FID L 16 890
SNT VIA
FID H 0 1004
FID C 4 1447
FID C 6 927
FID C 3 3790
FID C 8 2640
FID L 11 874
FID L 12 874
FID L 15 874
FID L 16 874
SNT VIA
FID H 0 1005
FID C 4 1423
FID C 6 906
FID C 3 3752
FID C 8 2598
FID L 11 860
FID L 12 860
FID L 15 860
FID L 16 860
SNT VIA
FID H 0 1006
FID C 4 1549
FID C 6 1012
FID C 3 3985
FID C 8 2786
FID L 11 930
FID L 12 930
FID L 15 930
FID L 16 930
SNT VIA
FID H 0 1007
FID C 4 1431
FID C 6 913
FID C 3 3768
FID C 8 2621
FID L 11 865
FID L 12 865
FID L 15 865
FID L 16 865
SNT VIA
FID H 0 1008
FID C 4 1538
FID C 6 1004
FID C 3 3966
FID C 8 2776
FID L 11 924
FID L 12 924
FID L 15 924
FID L 16 924
SNT VIA
FID H 0 1009
FID C 4 1440
FID C 6 919
FID C 3 3780
FID C 8 2631
FID L 11 869
FID L 12 869
FID L 15 869
FID L 16 869
SNT VIA
FID H 0 1010
FID C 4 1523
FID C 6 994
FID C 3 3940
FID C 8 2762
FID L 11 917
FID L 12 917
FID L 13 841
FID L 14 785
FID L 15 917
FID L 16 917
SNT VIA
FID H 0 1011
FID C 4 1527
FID C 6 998
FID C 3 3945
FID C 9 1973
FID C 8 2769
FID L 11 919
FID L 12 919
FID L 13 843
FID L 14 787
FID L 15 919
FID L 16 919
SNT VIA
FID H 0 1012
FID C 4 1558
FID C 6 1020
FID C 3 4001
FID C 8 2797
FID L 11 935
FID L 12 935
FID L 15 935
FID L 16 935
SNT VIA
FID H 0 1013
FID C 4 1517
FID C 6 983
FID C 3 3929
FID C 9 1969
FID C 8 2735
FID L 11 912
FID L 12 912
FID L 13 840
FID L 14 784
FID L 15 912
FID L 16 912
SNT VIA
FID H 0 1014
FID C 4 1557
FID C 6 1016
FID C 3 4000
FID C 8 2790
FID L 11 934
FID L 12 934
FID L 15 934
FID L 16 934
SNT VIA
FID H 0 1015
FID C 4 1526
FID C 6 997
FID C 3 3944
FID C 9 1972
FID C 10 2617
FID C 8 2768
FID L 11 918
FID L 12 918
FID L 13 842
FID L 14 786
FID L 15 918
FID L 16 918
SNT VIA
FID H 0 1016
FID C 4 1565
FID C 6 1026
FID C 3 4014
FID C 8 2807
FID L 11 938
FID L 12 938
FID L 15 938
FID L 16 938
SNT VIA
FID H 0 1017
FID C 4 1539
FID C 6 1005
FID C 3 3967
FID C 8 2777
FID L 11 925
FID L 12 925
FID L 15 925
FID L 16 925
SNT VIA
FID H 0 1382
FID C 4 1388
FID C 6 868
FID C 3 3680
FID C 8 2541
FID L 11 849
FID L 12 849
FID L 15 849
FID L 16 849
SNT VIA
FID H 0 1383
FID C 4 1389
FID C 6 869
FID C 3 3681
FID C 8 2542
FID L 11 850
FID L 12 850
FID L 15 850
FID L 16 850
SNT VIA
FID H 0 1384
FID C 4 1387
FID C 6 867
FID C 3 3679
FID C 8 2540
FID L 11 848
FID L 12 848
FID L 15 848
FID L 16 848
SNT VIA
FID H 0 1385
FID C 4 1421
FID C 6 903
FID C 3 3740
FID C 8 2592
FID L 11 858
FID L 12 858
FID L 13 806
FID L 15 858
FID L 16 858
SNT VIA
FID H 0 1386
FID C 4 1550
FID C 6 1013
FID C 3 3986
FID C 8 2787
FID L 11 931
FID L 12 931
FID L 15 931
FID L 16 931
SNT VIA
FID H 0 1963
FID C 4 1510
FID C 6 981
FID C 3 3911
FID C 8 2733
FID L 11 910
FID L 12 910
FID L 15 910
FID L 16 910
SNT VIA
FID H 0 1964
FID C 4 1508
FID C 6 976
FID C 3 3909
FID C 8 2721
FID L 11 908
FID L 12 908
FID L 15 908
FID L 16 908
SNT VIA
FID H 0 1965
FID C 4 1319
FID C 6 809
FID C 3 3529
FID C 9 1886
FID C 10 2550
FID C 8 2388
FID L 11 795
FID L 12 795
FID L 13 778
FID L 15 795
FID L 16 795
SNT VIA
FID H 0 1966
FID C 4 1322
FID C 6 812
FID C 3 3533
FID C 8 2392
FID L 11 797
FID L 12 797
FID L 13 780
FID L 15 797
FID L 16 797
SNT VIA
FID H 0 1967
FID C 4 1318
FID C 6 807
FID C 3 3528
FID C 10 2549
FID C 8 2386
FID L 11 794
FID L 12 794
FID L 13 777
FID L 14 741
FID L 15 794
FID L 16 794
SNT VIA
FID H 0 1968
FID C 4 1337
FID C 6 831
FID C 3 3555
FID C 8 2424
FID L 11 807
FID L 12 807
FID L 13 790
FID L 15 807
FID L 16 807
SNT VIA
FID H 0 1969
FID C 4 1331
FID C 6 828
FID C 3 3544
FID C 9 1905
FID C 10 2552
FID C 8 2421
FID L 11 804
FID L 12 804
FID L 13 787
FID L 14 747
FID L 15 804
FID L 16 804
SNT VIA
FID H 0 1970
FID C 4 1462
FID C 6 940
FID C 3 3820
FID C 9 1937
FID C 8 2662
FID L 11 883
FID L 12 883
FID L 13 821
FID L 14 772
FID L 15 883
FID L 16 883
SNT VIA
FID H 0 1971
FID C 4 1458
FID C 6 936
FID C 3 3812
FID C 9 1935
FID C 8 2654
FID L 11 881
FID L 12 881
FID L 13 819
FID L 14 770
FID L 15 881
FID L 16 881
SNT VIA
FID H 0 1972
FID C 4 1540
FID C 6 1007
FID C 3 3968
FID C 8 2780
FID L 11 926
FID L 12 926
FID L 15 926
FID L 16 926
SNT VIA
FID H 0 2530
FID C 3 3616
FID C 8 2478
FID L 11 824
FID L 12 824
FID L 14 753
FID L 15 824
FID L 16 824
SNT VIA
FID H 0 2531
FID C 3 3619
FID C 8 2481
FID L 11 825
FID L 12 825
FID L 14 754
FID L 15 825
FID L 16 825
SNT VIA
FID H 0 2532
FID C 3 3670
FID C 8 2512
FID L 11 842
FID L 12 842
FID L 15 842
FID L 16 842
SNT VIA
FID H 0 2533
FID C 3 3607
FID C 8 2458
FID L 11 821
FID L 12 821
FID L 14 750
FID L 15 821
FID L 16 821
SNT VIA
FID H 0 2534
FID C 3 3613
FID C 8 2473
FID L 11 823
FID L 12 823
FID L 14 752
FID L 15 823
FID L 16 823
SNT VIA
FID H 0 2535
FID C 3 3622
FID C 8 2482
FID L 11 826
FID L 12 826
FID L 14 755
FID L 15 826
FID L 16 826
SNT VIA
FID H 0 2536
FID C 3 3669
FID C 8 2511
FID L 11 841
FID L 12 841
FID L 15 841
FID L 16 841
SNT VIA
FID H 0 2537
FID C 3 3668
FID C 8 2510
FID L 11 840
FID L 12 840
FID L 15 840
FID L 16 840
SNT VIA
FID H 0 2538
FID C 3 3667
FID C 8 2509
FID L 11 839
FID L 12 839
FID L 15 839
FID L 16 839
SNT VIA
FID H 0 2539
FID C 3 3625
FID C 8 2483
FID L 11 827
FID L 12 827
FID L 14 756
FID L 15 827
FID L 16 827
SNT VIA
FID H 0 2540
FID C 3 3666
FID C 8 2508
FID L 11 838
FID L 12 838
FID L 15 838
FID L 16 838
SNT VIA
FID H 0 2541
FID C 3 3665
FID C 8 2507
FID L 11 837
FID L 12 837
FID L 15 837
FID L 16 837
SNT VIA
FID H 0 2542
FID C 3 3610
FID C 8 2465
FID L 11 822
FID L 12 822
FID L 14 751
FID L 15 822
FID L 16 822
SNT VIA
FID H 0 2543
FID C 3 3664
FID C 8 2506
FID L 11 836
FID L 12 836
FID L 15 836
FID L 16 836
SNT VIA
FID H 0 2544
FID C 3 3663
FID C 8 2505
FID L 11 835
FID L 12 835
FID L 15 835
FID L 16 835
SNT VIA
FID H 0 2545
FID C 3 3662
FID C 8 2504
FID L 11 834
FID L 12 834
FID L 15 834
FID L 16 834
SNT VIA
FID H 0 2546
FID C 3 3675
FID C 8 2517
FID L 11 847
FID L 12 847
FID L 15 847
FID L 16 847
SNT VIA
FID H 0 2547
FID C 3 3661
FID C 8 2503
FID L 11 833
FID L 12 833
FID L 15 833
FID L 16 833
SNT VIA
FID H 0 2548
FID C 3 3660
FID C 8 2502
FID L 11 832
FID L 12 832
FID L 15 832
FID L 16 832
SNT VIA
FID H 0 2549
FID C 3 3672
FID C 8 2514
FID L 11 844
FID L 12 844
FID L 15 844
FID L 16 844
SNT VIA
FID H 0 2550
FID C 3 3674
FID C 8 2516
FID L 11 846
FID L 12 846
FID L 15 846
FID L 16 846
SNT VIA
FID H 0 2551
FID C 3 3600
FID C 8 2454
FID L 11 819
FID L 12 819
FID L 13 802
FID L 15 819
FID L 16 819
SNT VIA
FID H 0 2552
FID C 3 3659
FID C 8 2501
FID L 11 831
FID L 12 831
FID L 15 831
FID L 16 831
SNT VIA
FID H 0 2553
FID C 3 3671
FID C 8 2513
FID L 11 843
FID L 12 843
FID L 15 843
FID L 16 843
SNT VIA
FID H 0 2554
FID C 3 3673
FID C 8 2515
FID L 11 845
FID L 12 845
FID L 15 845
FID L 16 845
SNT PLN S C 0
SNT PLN S C 0
SNT PLN S C 0
SNT TRC
FID C 3 3521
SNT TRC
FID C 3 3522
SNT TRC
FID C 3 3524
FID C 3 3525
SNT PLN S C 0
SNT PLN S C 0
SNT TRC
FID C 9 1881
FID C 9 1882
FID C 9 1883
FID C 9 1884
SNT TRC
FID C 10 2547
FID C 10 2548
SNT TRC
FID C 8 2378
SNT TRC
FID C 8 2379
SNT TRC
FID C 8 2383
SNT TRC
FID C 8 2385
SNT TRC
FID C 3 3532
SNT TRC
FID C 8 2391
SNT TRC
FID C 8 2393
FID C 8 2394
SNT TRC
FID C 9 1887
FID C 9 1888
FID C 9 1889
FID C 9 1890
SNT TRC
FID C 8 2397
SNT TRC
FID C 3 3535
SNT TRC
FID C 8 2401
SNT TRC
FID C 8 2403
SNT TRC
FID C 8 2407
FID C 8 2408
SNT TRC
FID C 3 3541
SNT TRC
FID C 9 1895
FID C 9 1896
FID C 9 1897
FID C 9 1898
SNT TRC
FID C 8 2410
FID C 8 2411
SNT TRC
FID C 9 1899
FID C 9 1900
SNT TRC
FID C 9 1901
FID C 9 1902
FID C 9 1903
SNT TRC
FID C 8 2413
FID C 8 2414
SNT TRC
FID C 8 2416
SNT TRC
FID C 8 2419
SNT TRC
FID C 3 3546
SNT TRC
FID C 10 2553
FID C 10 2554
FID C 10 2555
FID C 10 2556
SNT TRC
FID C 9 1907
FID C 9 1908
FID C 9 1909
FID C 9 1910
SNT TRC
FID C 3 3549
FID C 3 3550
SNT TRC
FID C 3 3552
SNT TRC
FID C 3 3553
SNT TRC
FID C 3 3558
FID C 3 3559
FID C 3 3560
SNT TRC
FID C 8 2428
SNT PLN S C 0
FID C 3 3562
SNT TRC
FID C 3 3563
FID C 3 3564
FID C 3 3565
SNT TRC
FID C 3 3566
FID C 3 3567
FID C 3 3568
SNT TRC
FID C 3 3569
FID C 3 3570
SNT TRC
FID C 3 3578
SNT TRC
FID C 8 2433
FID C 8 2434
FID C 8 2435
FID C 8 2436
FID C 8 2437
SNT TRC
FID C 3 3579
FID C 3 3580
FID C 3 3581
SNT TRC
FID C 3 3582
FID C 3 3583
FID C 3 3584
SNT TRC
FID C 8 2440
SNT TRC
FID C 3 3588
FID C 3 3589
SNT TRC
FID C 8 2443
FID C 8 2444
SNT TRC
FID C 8 2448
SNT TRC
FID C 3 3595
FID C 3 3596
FID C 3 3597
FID C 3 3598
SNT TRC
FID C 8 2451
FID C 8 2452
SNT TRC
FID C 8 2456
SNT TRC
FID C 3 3602
SNT TRC
FID C 3 3603
FID C 3 3604
SNT TRC
FID C 8 2459
FID C 8 2460
SNT TRC
FID C 8 2461
FID C 8 2462
SNT TRC
FID C 3 3608
SNT TRC
FID C 8 2466
FID C 8 2467
SNT TRC
FID C 8 2468
FID C 8 2469
SNT TRC
FID C 3 3611
SNT TRC
FID C 8 2472
SNT TRC
FID C 3 3614
SNT TRC
FID C 8 2475
FID C 8 2476
SNT TRC
FID C 3 3617
SNT TRC
FID C 8 2480
SNT TRC
FID C 3 3620
SNT TRC
FID C 3 3623
SNT TRC
FID C 8 2484
FID C 8 2485
FID C 8 2486
SNT TRC
FID C 3 3626
SNT PLN S C 0
FID C 3 3628
SNT PLN S C 0
FID C 3 3629
SNT PLN S C 0
FID C 8 2488
SNT TRC
FID C 10 2557
FID C 10 2558
SNT TRC
FID C 3 3630
SNT TRC
FID C 8 2491
FID C 8 2492
SNT TRC
FID C 8 2493
SNT TRC
FID C 3 3639
SNT TRC
FID C 3 3640
SNT TRC
FID C 8 2494
FID C 8 2495
SNT TRC
FID C 8 2498
SNT TRC
FID C 3 3641
SNT TRC
FID C 3 3644
SNT TRC
FID C 3 3646
SNT TRC
FID C 3 3648
SNT TRC
FID C 3 3650
SNT TRC
FID C 3 3652
SNT TRC
FID C 3 3654
SNT TRC
FID C 3 3657
SNT TRC
FID C 8 2518
FID C 8 2519
SNT TRC
FID C 8 2520
FID C 8 2521
SNT TRC
FID C 8 2522
FID C 8 2523
SNT TRC
FID C 8 2524
SNT TRC
FID C 8 2525
FID C 8 2526
SNT TRC
FID C 8 2527
FID C 8 2528
SNT TRC
FID C 8 2529
SNT TRC
FID C 8 2530
FID C 8 2531
SNT TRC
FID C 8 2532
FID C 8 2533
SNT TRC
FID C 8 2534
FID C 8 2535
SNT TRC
FID C 8 2536
FID C 8 2537
SNT TRC
FID C 8 2544
SNT TRC
FID C 3 3684
SNT TRC
FID C 8 2548
SNT TRC
FID C 3 3689
SNT TRC
FID C 3 3691
SNT TRC
FID C 8 2554
SNT TRC
FID C 3 3693
SNT TRC
FID C 8 2557
SNT TRC
FID C 3 3695
SNT TRC
FID C 3 3697
SNT TRC
FID C 3 3699
SNT TRC
FID C 3 3701
SNT TRC
FID C 3 3703
SNT TRC
FID C 8 2564
SNT TRC
FID C 3 3705
SNT TRC
FID C 8 2566
SNT TRC
FID C 3 3707
SNT TRC
FID C 8 2568
SNT TRC
FID C 3 3709
SNT TRC
FID C 8 2572
FID C 8 2573
SNT TRC
FID C 3 3711
SNT TRC
FID C 8 2574
SNT TRC
FID C 3 3713
SNT TRC
FID C 3 3715
SNT TRC
FID C 8 2577
SNT TRC
FID C 3 3717
SNT TRC
FID C 3 3719
SNT TRC
FID C 8 2581
FID C 8 2582
SNT TRC
FID C 3 3721
SNT TRC
FID C 8 2583
SNT TRC
FID C 8 2587
FID C 8 2588
SNT TRC
FID C 3 3724
SNT TRC
FID C 3 3725
FID C 3 3726
FID C 3 3727
FID C 3 3728
SNT TRC
FID C 3 3729
FID C 3 3730
SNT TRC
FID C 3 3734
SNT TRC
FID C 10 2561
FID C 10 2562
FID C 10 2563
FID C 10 2564
FID C 10 2565
FID C 10 2566
FID C 10 2567
SNT TRC
FID C 3 3736
SNT TRC
FID C 8 2594
SNT TRC
FID C 3 3742
FID C 3 3743
SNT TRC
FID C 8 2596
FID C 8 2597
SNT TRC
FID C 3 3744
FID C 3 3745
FID C 3 3746
FID C 3 3747
FID C 3 3748
SNT TRC
FID C 9 1911
FID C 9 1912
FID C 9 1913
FID C 9 1914
FID C 9 1915
FID C 9 1916
SNT TRC
FID C 3 3749
SNT PLN S C 0
FID C 3 3750
SNT TRC
FID C 3 3751
SNT TRC
FID C 8 2599
SNT TRC
FID C 3 3755
SNT TRC
FID C 3 3756
FID C 3 3757
FID C 3 3758
SNT TRC
FID C 8 2603
FID C 8 2604
FID C 8 2605
FID C 8 2606
FID C 8 2607
FID C 8 2608
SNT TRC
FID C 8 2610
FID C 8 2611
SNT TRC
FID C 8 2612
FID C 8 2613
FID C 8 2614
FID C 8 2615
SNT TRC
FID C 3 3761
FID C 3 3762
SNT TRC
FID C 8 2616
FID C 8 2617
FID C 8 2618
SNT TRC
FID C 9 1919
FID C 9 1920
FID C 9 1921
SNT TRC
FID C 3 3763
FID C 3 3764
SNT TRC
FID C 3 3769
SNT TRC
FID C 8 2622
FID C 8 2623
FID C 8 2624
SNT TRC
FID C 8 2627
SNT TRC
FID C 3 3776
SNT TRC
FID C 3 3778
SNT TRC
FID C 3 3781
SNT TRC
FID C 3 3783
FID C 3 3784
SNT TRC
FID C 8 2638
SNT TRC
FID C 8 2644
SNT TRC
FID C 3 3797
FID C 3 3798
SNT TRC
FID C 3 3799
SNT TRC
FID C 3 3800
FID C 3 3801
SNT TRC
FID C 8 2648
FID C 8 2649
SNT TRC
FID C 3 3802
FID C 3 3803
FID C 3 3804
SNT TRC
FID C 3 3807
FID C 3 3808
FID C 3 3809
SNT TRC
FID C 9 1927
FID C 9 1928
FID C 9 1929
FID C 9 1930
SNT TRC
FID C 8 2651
FID C 8 2652
SNT TRC
FID C 9 1931
FID C 9 1932
SNT TRC
FID C 9 1933
FID C 9 1934
SNT TRC
FID C 3 3813
SNT TRC
FID C 8 2656
FID C 8 2657
FID C 8 2658
SNT TRC
FID C 8 2661
SNT TRC
FID C 3 3817
FID C 3 3818
SNT TRC
FID C 3 3819
SNT TRC
FID C 9 1938
FID C 9 1939
SNT TRC
FID C 9 1941
FID C 9 1942
SNT TRC
FID C 3 3826
FID C 3 3827
FID C 3 3828
SNT TRC
FID C 3 3829
SNT TRC
FID C 8 2666
FID C 8 2667
SNT TRC
FID C 8 2669
SNT TRC
FID C 9 1944
FID C 9 1945
FID C 9 1946
FID C 9 1947
SNT TRC
FID C 9 1948
FID C 9 1949
SNT TRC
FID C 9 1950
FID C 9 1951
FID C 9 1952
FID C 9 1953
FID C 9 1954
FID C 9 1955
FID C 9 1956
FID C 9 1957
SNT TRC
FID C 10 2571
SNT TRC
FID C 8 2672
SNT TRC
FID C 8 2673
SNT TRC
FID C 8 2677
SNT TRC
FID C 8 2679
SNT TRC
FID C 8 2681
SNT TRC
FID C 8 2683
SNT TRC
FID C 8 2686
SNT TRC
FID C 10 2574
FID C 10 2575
FID C 10 2576
SNT TRC
FID C 10 2578
FID C 10 2579
FID C 10 2580
FID C 10 2581
SNT TRC
FID C 3 3837
SNT TRC
FID C 3 3842
SNT TRC
FID C 3 3843
FID C 3 3844
SNT TRC
FID C 3 3849
FID C 3 3850
FID C 3 3851
SNT TRC
FID C 8 2694
FID C 8 2695
FID C 8 2696
SNT TRC
FID C 3 3853
SNT TRC
FID C 8 2697
FID C 8 2698
SNT TRC
FID C 10 2585
FID C 10 2586
FID C 10 2587
FID C 10 2588
FID C 10 2589
SNT TRC
FID C 10 2590
FID C 10 2591
FID C 10 2592
FID C 10 2593
FID C 10 2594
FID C 10 2595
FID C 10 2596
FID C 10 2597
SNT TRC
FID C 3 3856
SNT TRC
FID C 3 3859
FID C 3 3860
FID C 3 3861
FID C 3 3862
SNT TRC
FID C 8 2701
FID C 8 2702
SNT TRC
FID C 3 3864
FID C 3 3865
SNT TRC
FID C 3 3867
FID C 3 3868
FID C 3 3869
SNT TRC
FID C 3 3871
FID C 3 3872
SNT TRC
FID C 8 2704
FID C 8 2705
FID C 8 2706
SNT PLN S C 0
FID C 10 2598
SNT TRC
FID C 3 3875
FID C 3 3876
FID C 3 3877
FID C 3 3878
FID C 3 3879
FID C 3 3880
FID C 3 3881
SNT TRC
FID C 3 3885
SNT TRC
FID C 3 3888
SNT TRC
FID C 3 3890
FID C 3 3891
FID C 3 3892
SNT TRC
FID C 10 2602
FID C 10 2603
FID C 10 2604
FID C 10 2605
FID C 10 2606
FID C 10 2607
SNT TRC
FID C 8 2713
FID C 8 2714
FID C 8 2715
SNT TRC
FID C 3 3893
FID C 3 3894
SNT TRC
FID C 10 2610
FID C 10 2611
FID C 10 2612
FID C 10 2613
FID C 10 2614
FID C 10 2615
SNT TRC
FID C 9 1958
FID C 9 1959
FID C 9 1960
FID C 9 1961
FID C 9 1962
FID C 9 1963
FID C 9 1964
FID C 9 1965
FID C 9 1966
FID C 9 1967
SNT TRC
FID C 3 3898
FID C 3 3899
FID C 3 3900
SNT TRC
FID C 3 3905
SNT TRC
FID C 3 3907
SNT TRC
FID C 8 2724
FID C 8 2725
SNT TRC
FID C 8 2727
FID C 8 2728
SNT TRC
FID C 8 2730
FID C 8 2731
FID C 8 2732
SNT TRC
FID C 3 3912
SNT TRC
FID C 3 3915
SNT TRC
FID C 3 3917
SNT TRC
FID C 3 3918
FID C 3 3919
FID C 3 3920
FID C 3 3921
SNT TRC
FID C 3 3922
FID C 3 3923
FID C 3 3924
SNT TRC
FID C 3 3927
SNT TRC
FID C 8 2737
SNT TRC
FID C 8 2740
SNT TRC
FID C 8 2742
FID C 8 2743
FID C 8 2744
SNT TRC
FID C 8 2747
SNT TRC
FID C 8 2749
SNT TRC
FID C 8 2751
SNT TRC
FID C 8 2753
FID C 8 2754
FID C 8 2755
FID C 8 2756
SNT TRC
FID C 3 3933
FID C 3 3934
SNT TRC
FID C 8 2758
FID C 8 2759
FID C 8 2760
FID C 8 2761
SNT TRC
FID C 3 3937
FID C 3 3938
FID C 3 3939
SNT TRC
FID C 3 3941
SNT TRC
FID C 9 1970
FID C 9 1971
SNT TRC
FID C 8 2764
SNT TRC
FID C 8 2766
FID C 8 2767
SNT TRC
FID C 8 2770
SNT TRC
FID C 3 3948
SNT TRC
FID C 3 3951
SNT TRC
FID C 3 3954
FID C 3 3955
SNT TRC
FID C 3 3958
FID C 3 3959
SNT TRC
FID C 3 3962
FID C 3 3963
FID C 3 3964
SNT TRC
FID C 3 3965
SNT TRC
FID C 8 2778
SNT TRC
FID C 8 2781
SNT TRC
FID C 3 3970
SNT TRC
FID C 3 3974
FID C 3 3975
SNT TRC
FID C 3 3977
SNT TRC
FID C 3 3981
FID C 3 3982
FID C 3 3983
SNT TRC
FID C 3 3984
SNT TRC
FID C 3 3988
FID C 3 3989
SNT TRC
FID C 3 3992
SNT TRC
FID C 3 3995
FID C 3 3996
SNT TRC
FID C 3 3998
FID C 3 3999
SNT TRC
FID C 8 2791
FID C 8 2792
SNT TRC
FID C 8 2795
SNT TRC
FID C 8 2798
FID C 8 2799
SNT TRC
FID C 3 4005
SNT TRC
FID C 3 4008
FID C 3 4009
SNT TRC
FID C 8 2803
FID C 8 2804
SNT TRC
FID C 3 4011
FID C 3 4012
FID C 3 4013
SNT TRC
FID C 8 2808
FID C 8 2809
FID C 8 2810
SNT TRC
FID C 8 2813
FID C 8 2814
SNT TRC
FID C 3 4018
FID C 3 4019
FID C 3 4020
SNT TRC
FID C 8 2817
FID C 8 2818
SNT TRC
FID C 3 4023
FID C 3 4024
SNT PLN S C 0
SNT TRC
FID C 3 4027
# NET 2
NET SG 
SNT TOP T 0 8
FID C 4 2589
FID C 5 1411
FID C 3 6184
SNT TOP T 0 9
FID C 4 2586
FID C 5 1410
FID C 3 6177
SNT TOP T 1 0
FID H 0 9
FID C 4 2845
FID C 6 2124
FID C 3 6643
FID C 8 4844
FID L 11 1390
FID L 12 1390
FID L 13 1467
FID L 14 1466
FID L 15 1390
FID L 16 1390
SNT TOP T 1 6
FID H 0 15
FID C 4 2846
FID C 6 2125
FID C 3 6644
FID C 8 4845
FID L 11 1391
FID L 12 1391
FID L 13 1468
FID L 14 1467
FID L 15 1391
FID L 16 1391
SNT TOP T 1 7
FID H 0 16
FID C 4 2847
FID C 6 2126
FID C 3 6645
FID C 8 4846
FID L 11 1392
FID L 12 1392
FID L 13 1469
FID L 14 1468
FID L 15 1392
FID L 16 1392
SNT TOP T 1 13
FID H 0 22
FID C 4 2848
FID C 6 2127
FID C 3 6646
FID C 8 4847
FID L 11 1393
FID L 12 1393
FID L 13 1470
FID L 14 1469
FID L 15 1393
FID L 16 1393
SNT TOP T 1 14
FID H 0 23
FID C 4 2841
FID C 6 2120
FID C 3 6639
FID C 8 4840
FID L 11 1386
FID L 12 1386
FID L 13 1463
FID L 14 1462
FID L 15 1386
FID L 16 1386
SNT TOP T 1 15
FID H 0 24
FID C 4 2842
FID C 6 2121
FID C 3 6640
FID C 8 4841
FID L 11 1387
FID L 12 1387
FID L 13 1464
FID L 14 1463
FID L 15 1387
FID L 16 1387
SNT TOP T 1 16
FID H 0 25
FID C 4 2843
FID C 6 2122
FID C 3 6641
FID C 8 4842
FID L 11 1388
FID L 12 1388
FID L 13 1465
FID L 14 1464
FID L 15 1388
FID L 16 1388
SNT TOP T 1 17
FID H 0 26
FID C 4 2844
FID C 6 2123
FID C 3 6642
FID C 8 4843
FID L 11 1389
FID L 12 1389
FID L 13 1466
FID L 14 1465
FID L 15 1389
FID L 16 1389
SNT TOP T 2 1
FID C 4 2756
FID C 5 1475
FID C 3 6522
SNT TOP T 3 1
FID C 4 2754
FID C 5 1474
FID C 3 6520
SNT TOP T 4 7
FID C 4 2746
FID C 5 1469
FID C 3 6509
SNT TOP T 5 7
FID C 4 2759
FID C 5 1476
FID C 3 6525
SNT TOP T 6 7
FID C 4 2761
FID C 5 1477
FID C 3 6527
SNT TOP T 7 3
FID C 4 2817
FID C 5 1501
FID C 3 6611
SNT TOP T 13 0
FID C 4 2737
FID C 5 1467
FID C 3 6492
SNT TOP T 13 4
FID C 4 2806
FID C 5 1497
FID C 3 6600
SNT TOP T 13 9
FID C 4 2808
FID C 5 1498
FID C 3 6602
SNT TOP T 13 10
FID C 4 2810
FID C 5 1499
FID C 3 6604
SNT TOP T 13 12
FID C 4 3734
FID C 5 1763
FID C 3 7854
SNT TOP T 13 14
FID C 4 2813
FID C 5 1500
FID C 3 6607
SNT TOP T 13 24
FID C 4 2683
FID C 5 1447
FID C 3 6395
SNT TOP T 13 34
FID C 4 2720
FID C 5 1464
FID C 3 6464
SNT TOP T 13 46
FID C 4 2681
FID C 5 1446
FID C 3 6393
SNT TOP T 13 50
FID C 4 2696
FID C 5 1452
FID C 3 6409
SNT TOP T 15 1
FID C 4 2699
FID C 5 1454
FID C 3 6414
SNT TOP T 105 1
FID C 4 3374
FID C 5 1563
FID C 3 7337
SNT TOP T 105 3
FID C 4 3372
FID C 5 1562
FID C 3 7332
SNT TOP T 106 1
FID H 0 1
FID C 4 3709
FID C 6 2861
FID C 3 7826
FID C 8 5851
FID L 11 1405
FID L 12 1405
FID L 13 2182
FID L 14 2181
FID L 15 1405
FID L 16 1405
SNT TOP T 106 2
FID H 0 2
FID C 4 3710
FID C 6 2862
FID C 3 7827
FID C 8 5852
FID L 11 1406
FID L 12 1406
FID L 13 2183
FID L 14 2182
FID L 15 1406
FID L 16 1406
SNT TOP T 106 3
FID H 0 3
FID C 4 3711
FID C 6 2863
FID C 3 7828
FID C 8 5853
FID L 11 1407
FID L 12 1407
FID L 13 2184
FID L 14 2183
FID L 15 1407
FID L 16 1407
SNT TOP T 106 4
FID H 0 4
FID C 4 3712
FID C 6 2864
FID C 3 7829
FID C 8 5854
FID L 11 1408
FID L 12 1408
FID L 13 2185
FID L 14 2184
FID L 15 1408
FID L 16 1408
SNT TOP T 107 1
FID H 0 28
FID C 4 3713
FID C 6 2865
FID C 3 7830
FID C 8 5855
FID L 11 1409
FID L 12 1409
FID L 13 2186
FID L 14 2185
FID L 15 1409
FID L 16 1409
SNT TOP T 107 2
FID H 0 29
FID C 4 3714
FID C 6 2866
FID C 3 7831
FID C 8 5856
FID L 11 1410
FID L 12 1410
FID L 13 2187
FID L 14 2186
FID L 15 1410
FID L 16 1410
SNT TOP T 107 3
FID H 0 30
FID C 4 3715
FID C 6 2867
FID C 3 7832
FID C 8 5857
FID L 11 1411
FID L 12 1411
FID L 13 2188
FID L 14 2187
FID L 15 1411
FID L 16 1411
SNT TOP T 107 4
FID H 0 31
FID C 4 3716
FID C 6 2868
FID C 3 7833
FID C 8 5858
FID L 11 1412
FID L 12 1412
FID L 13 2189
FID L 14 2188
FID L 15 1412
FID L 16 1412
SNT TOP T 108 1
FID H 0 33
FID C 4 3717
FID C 6 2869
FID C 3 7834
FID C 8 5859
FID L 11 1413
FID L 12 1413
FID L 13 2190
FID L 14 2189
FID L 15 1413
FID L 16 1413
SNT TOP T 108 2
FID H 0 34
FID C 4 3718
FID C 6 2870
FID C 3 7835
FID C 8 5860
FID L 11 1414
FID L 12 1414
FID L 13 2191
FID L 14 2190
FID L 15 1414
FID L 16 1414
SNT TOP T 108 3
FID H 0 35
FID C 4 3719
FID C 6 2871
FID C 3 7836
FID C 8 5861
FID L 11 1415
FID L 12 1415
FID L 13 2192
FID L 14 2191
FID L 15 1415
FID L 16 1415
SNT TOP T 108 4
FID H 0 36
FID C 4 3720
FID C 6 2872
FID C 3 7837
FID C 8 5862
FID L 11 1416
FID L 12 1416
FID L 13 2193
FID L 14 2192
FID L 15 1416
FID L 16 1416
SNT TOP T 109 1
FID H 0 38
FID C 4 3721
FID C 6 2873
FID C 3 7838
FID C 8 5863
FID L 11 1417
FID L 12 1417
FID L 13 2194
FID L 14 2193
FID L 15 1417
FID L 16 1417
SNT TOP T 109 2
FID H 0 39
FID C 4 3722
FID C 6 2874
FID C 3 7839
FID C 8 5864
FID L 11 1418
FID L 12 1418
FID L 13 2195
FID L 14 2194
FID L 15 1418
FID L 16 1418
SNT TOP T 109 3
FID H 0 40
FID C 4 3723
FID C 6 2875
FID C 3 7840
FID C 8 5865
FID L 11 1419
FID L 12 1419
FID L 13 2196
FID L 14 2195
FID L 15 1419
FID L 16 1419
SNT TOP T 109 4
FID H 0 41
FID C 4 3724
FID C 6 2876
FID C 3 7841
FID C 8 5866
FID L 11 1420
FID L 12 1420
FID L 13 2197
FID L 14 2196
FID L 15 1420
FID L 16 1420
SNT TOP T 115 4
FID C 4 2605
FID C 5 1419
FID C 3 6228
SNT TOP T 115 10
FID C 3 6229
SNT TOP T 116 4
FID C 4 2609
FID C 5 1420
FID C 3 6233
SNT TOP T 116 10
FID C 3 6234
SNT TOP T 117 4
FID C 4 3392
FID C 5 1571
FID C 3 7361
SNT TOP T 117 10
FID C 3 7395
SNT TOP T 118 4
FID C 4 3376
FID C 5 1564
FID C 3 7340
SNT TOP T 118 10
FID C 3 7762
SNT TOP T 119 3
FID C 4 2622
FID C 5 1425
FID C 3 6256
SNT TOP T 120 3
FID C 4 3738
FID C 5 1767
FID C 3 7860
SNT TOP T 120 10
FID C 4 2613
FID C 5 1424
FID C 3 6246
SNT TOP T 120 17
FID C 4 2611
FID C 5 1422
FID C 3 6238
SNT TOP T 120 24
FID C 4 2612
FID C 5 1423
FID C 3 6241
SNT TOP T 120 28
FID C 3 6255
SNT TOP T 125 3
FID C 4 2822
FID C 5 1503
FID C 3 6617
SNT TOP T 126 3
FID C 4 2828
FID C 5 1506
FID C 3 6624
SNT TOP T 127 3
FID C 4 2831
FID C 5 1507
FID C 3 6627
SNT TOP T 128 3
FID C 4 2837
FID C 5 1510
FID C 3 6635
SNT TOP T 129 0
FID H 0 69
FID C 4 2577
FID C 6 1899
FID C 3 6168
FID C 8 4514
FID L 13 1300
FID L 14 1299
SNT TOP T 129 1
FID H 0 70
FID C 4 2576
FID C 6 1898
FID C 3 6167
FID C 8 4513
FID L 13 1299
FID L 14 1298
SNT TOP T 129 2
FID H 0 71
FID C 4 2575
FID C 6 1897
FID C 3 6166
FID C 8 4512
FID L 13 1298
FID L 14 1297
SNT TOP T 129 3
FID H 0 72
FID C 4 2574
FID C 6 1896
FID C 3 6165
FID C 8 4511
FID L 13 1297
FID L 14 1296
SNT TOP T 129 4
FID H 0 73
FID C 4 2573
FID C 6 1895
FID C 3 6164
FID C 8 4510
FID L 13 1296
FID L 14 1295
SNT TOP T 129 5
FID H 0 74
FID C 4 2572
FID C 6 1894
FID C 3 6163
FID C 8 4509
FID L 13 1295
FID L 14 1294
SNT TOP T 129 6
FID H 0 75
FID C 4 2571
FID C 6 1893
FID C 3 6162
FID C 8 4508
FID L 13 1294
FID L 14 1293
SNT TOP T 129 7
FID H 0 76
FID C 4 2570
FID C 6 1892
FID C 3 6161
FID C 8 4507
FID L 13 1293
FID L 14 1292
SNT TOP T 130 0
FID H 0 85
FID C 4 3123
FID C 6 2373
FID C 3 7061
FID C 8 5280
FID L 13 1801
FID L 14 1800
SNT TOP T 130 1
FID H 0 86
FID C 4 3122
FID C 6 2372
FID C 3 7060
FID C 8 5279
FID L 13 1800
FID L 14 1799
SNT TOP T 130 2
FID H 0 87
FID C 4 3121
FID C 6 2371
FID C 3 7059
FID C 8 5278
FID L 13 1799
FID L 14 1798
SNT TOP T 130 3
FID H 0 88
FID C 4 3120
FID C 6 2370
FID C 3 7058
FID C 8 5277
FID L 13 1798
FID L 14 1797
SNT TOP T 130 4
FID H 0 89
FID C 4 3119
FID C 6 2369
FID C 3 7057
FID C 8 5276
FID L 13 1797
FID L 14 1796
SNT TOP T 130 5
FID H 0 90
FID C 4 3118
FID C 6 2368
FID C 3 7056
FID C 8 5275
FID L 13 1796
FID L 14 1795
SNT TOP T 130 6
FID H 0 91
FID C 4 3117
FID C 6 2367
FID C 3 7055
FID C 8 5274
FID L 13 1795
FID L 14 1794
SNT TOP T 130 7
FID H 0 92
FID C 4 3116
FID C 6 2366
FID C 3 7054
FID C 8 5273
FID L 13 1794
FID L 14 1793
SNT TOP T 131 0
FID H 0 51
FID C 4 2569
FID C 6 1891
FID C 3 6160
FID C 8 4506
FID L 13 1292
FID L 14 1291
SNT TOP T 131 1
FID H 0 52
FID C 4 2568
FID C 6 1890
FID C 3 6159
FID C 8 4505
FID L 13 1291
FID L 14 1290
SNT TOP T 131 2
FID H 0 53
FID C 4 2567
FID C 6 1889
FID C 3 6158
FID C 8 4504
FID L 13 1290
FID L 14 1289
SNT TOP T 131 3
FID H 0 54
FID C 4 2566
FID C 6 1888
FID C 3 6157
FID C 8 4503
FID L 13 1289
FID L 14 1288
SNT TOP T 131 4
FID H 0 55
FID C 4 2565
FID C 6 1887
FID C 3 6156
FID C 8 4502
FID L 13 1288
FID L 14 1287
SNT TOP T 131 5
FID H 0 56
FID C 4 2564
FID C 6 1886
FID C 3 6155
FID C 8 4501
FID L 13 1287
FID L 14 1286
SNT TOP T 131 6
FID H 0 57
FID C 4 2563
FID C 6 1885
FID C 3 6154
FID C 8 4500
FID L 13 1286
FID L 14 1285
SNT TOP T 131 7
FID H 0 58
FID C 4 2562
FID C 6 1884
FID C 3 6153
FID C 8 4499
FID L 13 1285
FID L 14 1284
SNT TOP T 132 0
FID H 0 60
FID C 4 2585
FID C 6 1907
FID C 3 6176
FID C 8 4522
FID L 13 1308
FID L 14 1307
SNT TOP T 132 1
FID H 0 61
FID C 4 2584
FID C 6 1906
FID C 3 6175
FID C 8 4521
FID L 13 1307
FID L 14 1306
SNT TOP T 132 2
FID H 0 62
FID C 4 2583
FID C 6 1905
FID C 3 6174
FID C 8 4520
FID L 13 1306
FID L 14 1305
SNT TOP T 132 3
FID H 0 63
FID C 4 2582
FID C 6 1904
FID C 3 6173
FID C 8 4519
FID L 13 1305
FID L 14 1304
SNT TOP T 132 4
FID H 0 64
FID C 4 2581
FID C 6 1903
FID C 3 6172
FID C 8 4518
FID L 13 1304
FID L 14 1303
SNT TOP T 132 5
FID H 0 65
FID C 4 2580
FID C 6 1902
FID C 3 6171
FID C 8 4517
FID L 13 1303
FID L 14 1302
SNT TOP T 132 6
FID H 0 66
FID C 4 2579
FID C 6 1901
FID C 3 6170
FID C 8 4516
FID L 13 1302
FID L 14 1301
SNT TOP T 132 7
FID H 0 67
FID C 4 2578
FID C 6 1900
FID C 3 6169
FID C 8 4515
FID L 13 1301
FID L 14 1300
SNT TOP T 133 1
FID C 4 2965
FID C 5 1535
FID C 3 6879
SNT TOP T 134 0
FID H 0 45
FID C 4 2547
FID C 6 1869
FID C 3 6111
FID C 8 4470
FID L 11 1383
FID L 12 1383
FID L 13 1270
FID L 14 1269
FID L 15 1383
FID L 16 1383
SNT TOP T 141 0
FID H 0 43
FID C 4 3725
FID C 6 2877
FID C 3 7842
FID C 8 5867
FID L 11 1421
FID L 12 1421
FID L 13 2198
FID L 14 2197
FID L 15 1421
FID L 16 1421
SNT TOP T 142 6
FID C 4 2602
FID C 5 1418
FID C 3 6225
SNT TOP T 142 7
FID C 4 2601
FID C 5 1417
FID C 3 6224
SNT TOP T 142 8
FID C 3 6150
SNT TOP T 143 3
FID H 0 97
FID C 4 3672
FID C 6 2847
FID C 3 7785
FID C 8 5830
FID L 11 1400
FID L 12 1400
FID L 13 2170
FID L 14 2169
FID L 15 1400
FID L 16 1400
SNT TOP T 143 4
FID H 0 98
FID C 4 3671
FID C 6 2846
FID C 3 7784
FID C 8 5829
FID L 11 1399
FID L 12 1399
FID L 13 2169
FID L 14 2168
FID L 15 1399
FID L 16 1399
SNT TOP T 143 5
FID H 0 99
FID C 4 3670
FID C 6 2845
FID C 3 7783
FID C 8 5828
FID L 11 1398
FID L 12 1398
FID L 13 2168
FID L 14 2167
FID L 15 1398
FID L 16 1398
SNT TOP T 144 0
FID H 0 79
FID C 4 3650
FID C 6 2826
FID C 3 7759
FID C 8 5806
FID L 11 1394
FID L 12 1394
FID L 13 2152
FID L 14 2151
FID L 15 1394
FID L 16 1394
SNT TOP T 145 0
FID H 0 80
FID C 4 3651
FID C 6 2827
FID C 3 7760
FID C 8 5807
FID L 11 1395
FID L 12 1395
FID L 13 2153
FID L 14 2152
FID L 15 1395
FID L 16 1395
SNT TOP T 146 0
FID H 0 50
FID C 4 3653
FID C 6 2829
FID C 3 7765
FID C 8 5809
FID L 11 1396
FID L 12 1396
FID L 13 2155
FID L 14 2154
FID L 15 1396
FID L 16 1396
SNT TOP T 147 0
FID H 0 78
FID C 4 3654
FID C 6 2830
FID C 3 7766
FID C 8 5810
FID L 11 1397
FID L 12 1397
FID L 13 2156
FID L 14 2155
FID L 15 1397
FID L 16 1397
SNT TOP T 148 7
FID C 4 3015
FID C 5 1542
FID C 3 6939
SNT TOP T 148 8
FID C 4 2991
FID C 5 1538
FID C 3 6908
SNT TOP T 149 1
FID C 4 3465
FID C 5 1592
FID C 3 7452
SNT TOP T 149 24
FID C 4 3462
FID C 5 1591
FID C 3 7449
SNT TOP T 165 2
FID C 4 2532
FID C 5 1405
FID C 3 6080
SNT TOP T 166 2
FID C 4 3431
FID C 5 1583
FID C 3 7417
SNT TOP T 167 7
FID C 4 3647
FID C 5 1724
FID C 3 7756
SNT TOP T 168 3
FID C 4 2711
FID C 5 1461
FID C 3 6443
SNT TOP T 169 7
FID C 4 3471
FID C 5 1595
FID C 3 7459
SNT TOP T 169 8
FID C 4 3452
FID C 5 1588
FID C 3 7439
SNT TOP T 169 14
FID C 4 3451
FID C 5 1587
FID C 3 7438
SNT TOP T 170 1
FID C 4 3538
FID C 5 1661
FID C 3 7592
SNT TOP T 170 2
FID C 4 3536
FID C 5 1659
FID C 3 7588
SNT TOP T 170 4
FID C 4 3535
FID C 5 1658
FID C 3 7586
SNT TOP T 170 6
FID C 4 3532
FID C 5 1655
FID C 3 7580
SNT TOP T 170 8
FID C 4 3526
FID C 5 1649
FID C 3 7568
SNT TOP T 170 10
FID C 4 3522
FID C 5 1645
FID C 3 7560
SNT TOP T 170 11
FID C 4 3515
FID C 5 1638
FID C 3 7546
SNT TOP T 170 21
FID C 4 3507
FID C 5 1630
FID C 3 7530
SNT TOP T 170 23
FID C 4 3478
FID C 5 1601
FID C 3 7472
SNT TOP T 170 33
FID C 4 3555
FID C 5 1678
FID C 3 7626
SNT TOP T 170 43
FID C 4 3539
FID C 5 1662
FID C 3 7594
SNT TOP T 170 52
FID C 4 3449
FID C 5 1586
FID C 3 7436
SNT TOP T 170 62
FID C 4 3550
FID C 5 1673
FID C 3 7616
SNT TOP T 170 68
FID C 4 3537
FID C 5 1660
FID C 3 7590
SNT TOP T 170 77
FID C 4 3517
FID C 5 1640
FID C 3 7550
SNT TOP T 170 84
FID C 4 3508
FID C 5 1631
FID C 3 7532
SNT TOP T 170 90
FID C 4 3506
FID C 5 1629
FID C 3 7528
SNT TOP T 170 93
FID C 4 3534
FID C 5 1657
FID C 3 7584
SNT TOP T 170 97
FID C 4 3525
FID C 5 1648
FID C 3 7566
SNT TOP T 170 99
FID C 4 3516
FID C 5 1639
FID C 3 7548
SNT TOP T 170 103
FID C 4 3509
FID C 5 1632
FID C 3 7534
SNT TOP T 170 112
FID C 4 3505
FID C 5 1628
FID C 3 7526
SNT TOP T 170 113
FID C 4 3504
FID C 5 1627
FID C 3 7524
SNT TOP T 170 117
FID C 4 3531
FID C 5 1654
FID C 3 7578
SNT TOP T 170 121
FID C 4 3514
FID C 5 1637
FID C 3 7544
SNT TOP T 170 122
FID C 4 3511
FID C 5 1634
FID C 3 7538
SNT TOP T 170 135
FID C 4 3503
FID C 5 1626
FID C 3 7522
SNT TOP T 170 136
FID C 4 3502
FID C 5 1625
FID C 3 7520
SNT TOP T 170 138
FID C 4 3533
FID C 5 1656
FID C 3 7582
SNT TOP T 170 140
FID C 4 3529
FID C 5 1652
FID C 3 7574
SNT TOP T 170 142
FID C 4 3521
FID C 5 1644
FID C 3 7558
SNT TOP T 170 151
FID C 4 3549
FID C 5 1672
FID C 3 7614
SNT TOP T 170 158
FID C 4 3501
FID C 5 1624
FID C 3 7518
SNT TOP T 170 164
FID C 4 3520
FID C 5 1643
FID C 3 7556
SNT TOP T 170 170
FID C 4 3548
FID C 5 1671
FID C 3 7612
SNT TOP T 170 180
FID C 4 3500
FID C 5 1623
FID C 3 7516
SNT TOP T 170 181
FID C 4 3499
FID C 5 1622
FID C 3 7514
SNT TOP T 170 182
FID C 4 3498
FID C 5 1621
FID C 3 7512
SNT TOP T 170 183
FID C 4 3530
FID C 5 1653
FID C 3 7576
SNT TOP T 170 184
FID C 4 3528
FID C 5 1651
FID C 3 7572
SNT TOP T 170 185
FID C 4 3524
FID C 5 1647
FID C 3 7564
SNT TOP T 170 187
FID C 4 3513
FID C 5 1636
FID C 3 7542
SNT TOP T 170 189
FID C 4 3510
FID C 5 1633
FID C 3 7536
SNT TOP T 170 198
FID C 4 3497
FID C 5 1620
FID C 3 7510
SNT TOP T 170 204
FID C 4 3496
FID C 5 1619
FID C 3 7508
SNT TOP T 170 206
FID C 4 3527
FID C 5 1650
FID C 3 7570
SNT TOP T 170 208
FID C 4 3519
FID C 5 1642
FID C 3 7554
SNT TOP T 170 218
FID C 4 3547
FID C 5 1670
FID C 3 7610
SNT TOP T 170 227
FID C 4 3495
FID C 5 1618
FID C 3 7506
SNT TOP T 170 229
FID C 4 3523
FID C 5 1646
FID C 3 7562
SNT TOP T 170 231
FID C 4 3512
FID C 5 1635
FID C 3 7540
SNT TOP T 170 237
FID C 4 3546
FID C 5 1669
FID C 3 7608
SNT TOP T 170 246
FID C 4 3493
FID C 5 1616
FID C 3 7502
SNT TOP T 170 248
FID C 4 3492
FID C 5 1615
FID C 3 7500
SNT TOP T 170 250
FID C 4 3494
FID C 5 1617
FID C 3 7504
SNT TOP T 170 252
FID C 4 3518
FID C 5 1641
FID C 3 7552
SNT TOP T 170 256
FID C 4 3545
FID C 5 1668
FID C 3 7606
SNT TOP T 170 265
FID C 4 3489
FID C 5 1612
FID C 3 7494
SNT TOP T 170 271
FID C 4 3488
FID C 5 1611
FID C 3 7492
SNT TOP T 170 272
FID C 4 3490
FID C 5 1613
FID C 3 7496
SNT TOP T 170 273
FID C 4 3491
FID C 5 1614
FID C 3 7498
SNT TOP T 170 285
FID C 4 3474
FID C 5 1597
FID C 3 7465
SNT TOP T 170 292
FID C 4 3485
FID C 5 1608
FID C 3 7486
SNT TOP T 170 294
FID C 4 3487
FID C 5 1610
FID C 3 7490
SNT TOP T 170 295
FID C 4 3486
FID C 5 1609
FID C 3 7488
SNT TOP T 170 296
FID C 4 3559
FID C 5 1682
FID C 3 7634
SNT TOP T 170 304
FID C 4 3544
FID C 5 1667
FID C 3 7604
SNT TOP T 170 313
FID C 4 3483
FID C 5 1606
FID C 3 7482
SNT TOP T 170 315
FID C 4 3482
FID C 5 1605
FID C 3 7480
SNT TOP T 170 316
FID C 4 3484
FID C 5 1607
FID C 3 7484
SNT TOP T 170 317
FID C 4 3561
FID C 5 1684
FID C 3 7638
SNT TOP T 170 323
FID C 4 3543
FID C 5 1666
FID C 3 7602
SNT TOP T 170 332
FID C 4 3481
FID C 5 1604
FID C 3 7478
SNT TOP T 170 336
FID C 4 3480
FID C 5 1603
FID C 3 7476
SNT TOP T 170 338
FID C 4 3563
FID C 5 1686
FID C 3 7642
SNT TOP T 170 340
FID C 4 3558
FID C 5 1681
FID C 3 7632
SNT TOP T 170 342
FID C 4 3554
FID C 5 1677
FID C 3 7624
SNT TOP T 170 359
FID C 4 3565
FID C 5 1688
FID C 3 7646
SNT TOP T 170 361
FID C 4 3560
FID C 5 1683
FID C 3 7636
SNT TOP T 170 363
FID C 4 3556
FID C 5 1679
FID C 3 7628
SNT TOP T 170 371
FID C 4 3542
FID C 5 1665
FID C 3 7600
SNT TOP T 170 380
FID C 4 3566
FID C 5 1689
FID C 3 7648
SNT TOP T 170 382
FID C 4 3562
FID C 5 1685
FID C 3 7640
SNT TOP T 170 384
FID C 4 3557
FID C 5 1680
FID C 3 7630
SNT TOP T 170 390
FID C 4 3541
FID C 5 1664
FID C 3 7598
SNT TOP T 170 399
FID C 4 3479
FID C 5 1602
FID C 3 7474
SNT TOP T 170 409
FID C 4 3553
FID C 5 1676
FID C 3 7622
SNT TOP T 170 418
FID C 4 3477
FID C 5 1600
FID C 3 7471
SNT TOP T 170 428
FID C 4 3356
FID C 5 1557
FID C 3 7314
SNT TOP T 170 438
FID C 4 3540
FID C 5 1663
FID C 3 7596
SNT TOP T 170 447
FID C 4 3564
FID C 5 1687
FID C 3 7644
SNT TOP T 170 457
FID C 4 3551
FID C 5 1674
FID C 3 7618
SNT TOP T 170 466
FID C 4 3567
FID C 5 1690
FID C 3 7650
SNT TOP T 170 476
FID C 4 3552
FID C 5 1675
FID C 3 7620
SNT TOP T 171 1
FID C 4 3408
FID C 5 1576
FID C 3 7378
SNT TOP T 172 1
FID C 4 2747
FID C 5 1470
FID C 3 6510
SNT TOP T 173 1
FID C 4 3409
FID C 5 1577
FID C 3 7379
SNT TOP T 174 1
FID C 4 3705
FID C 5 1751
FID C 3 7822
SNT TOP T 175 1
FID C 4 3613
FID C 5 1712
FID C 3 7707
SNT TOP T 178 0
FID C 4 2774
FID C 5 1479
FID C 3 6541
SNT TOP T 179 8
FID C 4 3473
FID C 5 1596
FID C 3 7463
SNT TOP T 180 2
FID C 4 2887
FID C 5 1530
FID C 3 6801
SNT TOP T 180 3
FID C 4 2888
FID C 5 1531
FID C 3 6802
SNT TOP T 180 4
FID C 4 2889
FID C 5 1532
FID C 3 6803
SNT TOP T 180 7
FID C 4 2882
FID C 5 1525
FID C 3 6796
SNT TOP T 180 8
FID C 4 2883
FID C 5 1526
FID C 3 6797
SNT TOP T 180 9
FID C 4 2884
FID C 5 1527
FID C 3 6798
SNT TOP T 181 2
FID C 4 3577
FID C 5 1696
FID C 3 7667
SNT TOP T 181 3
FID C 4 3578
FID C 5 1697
FID C 3 7668
SNT TOP T 181 4
FID C 4 3579
FID C 5 1698
FID C 3 7669
SNT TOP T 181 7
FID C 4 3580
FID C 5 1699
FID C 3 7670
SNT TOP T 181 8
FID C 4 3581
FID C 5 1700
FID C 3 7671
SNT TOP T 181 9
FID C 4 3582
FID C 5 1701
FID C 3 7672
SNT TOP T 182 2
FID C 4 3677
FID C 5 1734
FID C 3 7791
SNT TOP T 182 3
FID C 4 3678
FID C 5 1735
FID C 3 7792
SNT TOP T 182 4
FID C 4 3679
FID C 5 1736
FID C 3 7793
SNT TOP T 182 7
FID C 4 3682
FID C 5 1739
FID C 3 7796
SNT TOP T 182 8
FID C 4 3683
FID C 5 1740
FID C 3 7797
SNT TOP T 182 9
FID C 4 3684
FID C 5 1741
FID C 3 7798
SNT TOP T 183 3
FID C 4 3058
FID C 5 1547
FID C 3 6994
SNT TOP T 186 3
FID C 4 2629
FID C 5 1428
FID C 3 6263
SNT TOP T 187 3
FID C 4 3020
FID C 5 1544
FID C 3 6951
SNT TOP T 188 3
FID C 4 2591
FID C 5 1412
FID C 3 6197
SNT TOP T 189 6
FID C 4 2610
FID C 5 1421
FID C 3 6235
SNT TOP T 190 0
FID C 4 3610
FID C 5 1711
FID C 3 7704
SNT TOP T 191 0
FID C 4 3659
FID C 5 1727
FID C 3 7771
SNT TOP T 193 1
FID C 4 2534
FID C 5 1407
FID C 3 6085
SNT TOP T 194 1
FID C 4 2531
FID C 5 1404
FID C 3 6070
SNT TOP T 201 1
FID C 4 2463
FID C 5 1401
FID C 3 5965
SNT TOP T 206 1
FID C 4 2545
FID C 5 1409
FID C 3 6100
SNT TOP T 220 0
FID C 4 2672
FID C 5 1442
FID C 3 6364
SNT TOP T 221 0
FID C 4 2833
FID C 5 1508
FID C 3 6630
SNT TOP T 222 0
FID C 4 2598
FID C 5 1415
FID C 3 6215
SNT TOP T 223 0
FID C 4 2678
FID C 5 1445
FID C 3 6375
SNT TOP T 234 0
FID C 4 2705
FID C 5 1457
FID C 3 6432
SNT TOP T 235 0
FID C 4 2752
FID C 5 1473
FID C 3 6517
SNT TOP T 236 1
FID C 4 2697
FID C 5 1453
FID C 3 6410
SNT TOP T 256 1
FID C 4 2688
FID C 5 1449
FID C 3 6400
SNT TOP T 257 1
FID C 4 2692
FID C 5 1451
FID C 3 6405
SNT TOP T 259 0
FID C 4 2849
FID C 5 1511
FID C 3 6647
SNT TOP T 262 1
FID C 4 2852
FID C 5 1514
FID C 3 6650
SNT TOP T 265 1
FID C 4 2851
FID C 5 1513
FID C 3 6649
SNT TOP T 269 1
FID C 4 2850
FID C 5 1512
FID C 3 6648
SNT TOP T 270 1
FID C 4 2650
FID C 5 1437
FID C 3 6312
SNT TOP T 271 1
FID C 4 2651
FID C 5 1438
FID C 3 6313
SNT TOP T 324 0
FID C 4 2775
FID C 5 1480
FID C 3 6542
SNT TOP T 325 0
FID C 4 2401
FID C 5 1394
FID C 3 5865
SNT TOP T 331 0
FID C 4 2780
FID C 5 1483
FID C 3 6550
SNT TOP T 338 1
FID C 4 3735
FID C 5 1764
FID C 3 7855
SNT TOP T 350 1
FID C 4 3736
FID C 5 1765
FID C 3 7857
SNT TOP T 355 1
FID C 4 3468
FID C 5 1593
FID C 3 7456
SNT TOP T 356 1
FID C 4 3728
FID C 5 1757
FID C 3 7846
SNT TOP T 359 1
FID C 4 3402
FID C 5 1575
FID C 3 7372
SNT TOP T 363 1
FID C 4 3470
FID C 5 1594
FID C 3 7458
SNT TOP T 372 1
FID C 4 3400
FID C 5 1574
FID C 3 7370
SNT TOP T 374 1
FID C 4 3432
FID C 5 1584
FID C 3 7418
SNT TOP T 375 1
FID C 4 3434
FID C 5 1585
FID C 3 7420
SNT TOP T 377 1
FID C 4 3729
FID C 5 1758
FID C 3 7847
SNT TOP T 380 0
FID C 4 3730
FID C 5 1759
FID C 3 7849
SNT TOP T 384 1
FID C 4 3649
FID C 5 1725
FID C 3 7758
SNT TOP T 390 1
FID C 4 3638
FID C 5 1720
FID C 3 7744
SNT TOP T 400 1
FID C 4 2700
FID C 5 1455
FID C 3 6419
SNT TOP T 401 0
FID C 4 3643
FID C 5 1721
FID C 3 7750
SNT TOP T 402 1
FID C 4 3645
FID C 5 1723
FID C 3 7754
SNT TOP T 416 1
FID C 4 3697
FID C 5 1748
FID C 3 7813
SNT TOP T 424 1
FID C 4 3706
FID C 5 1752
FID C 3 7823
SNT TOP T 426 1
FID C 4 2626
FID C 5 1426
FID C 3 6260
SNT TOP T 427 1
FID C 4 2784
FID C 5 1485
FID C 3 6557
SNT TOP T 433 1
FID C 4 2802
FID C 5 1495
FID C 3 6584
SNT TOP T 434 1
FID C 4 2803
FID C 5 1496
FID C 3 6586
SNT TOP T 435 1
FID C 4 2801
FID C 5 1494
FID C 3 6583
SNT TOP T 437 1
FID C 4 2797
FID C 5 1490
FID C 3 6575
SNT TOP T 439 1
FID C 4 3669
FID C 5 1729
FID C 3 7782
SNT TOP T 441 1
FID C 4 2798
FID C 5 1491
FID C 3 6576
SNT TOP T 444 1
FID C 4 2800
FID C 5 1493
FID C 3 6581
SNT TOP T 445 1
FID C 4 2799
FID C 5 1492
FID C 3 6579
SNT TOP T 447 0
FID C 4 2717
FID C 5 1463
FID C 3 6452
SNT TOP T 448 0
FID C 4 3733
FID C 5 1762
FID C 3 7853
SNT TOP T 449 0
FID C 4 2820
FID C 5 1502
FID C 3 6614
SNT TOP T 450 0
FID C 4 2826
FID C 5 1505
FID C 3 6621
SNT TOP T 451 1
FID C 4 2643
FID C 5 1435
FID C 3 6280
SNT TOP T 452 0
FID C 4 2777
FID C 5 1481
FID C 3 6545
SNT TOP T 453 1
FID C 4 2787
FID C 5 1486
FID C 3 6562
SNT TOP T 456 0
FID C 4 3024
FID C 5 1546
FID C 3 6960
SNT TOP T 457 0
FID C 4 2735
FID C 5 1466
FID C 3 6490
SNT TOP T 458 0
FID C 4 2733
FID C 5 1465
FID C 3 6487
SNT TOP T 459 1
FID C 4 3455
FID C 5 1589
FID C 3 7442
SNT TOP T 460 1
FID C 4 3457
FID C 5 1590
FID C 3 7444
SNT TOP T 461 1
FID C 4 3390
FID C 5 1570
FID C 3 7358
SNT TOP T 462 1
FID C 4 3385
FID C 5 1568
FID C 3 7353
SNT TOP T 463 1
FID C 4 3626
FID C 5 1716
FID C 3 7725
SNT TOP T 464 1
FID C 4 3618
FID C 5 1713
FID C 3 7713
SNT TOP T 465 1
FID C 4 3624
FID C 5 1715
FID C 3 7723
SNT TOP T 468 0
FID C 4 3637
FID C 5 1719
FID C 3 7743
SNT TOP T 469 1
FID C 4 2600
FID C 5 1416
FID C 3 6219
SNT TOP T 470 0
FID C 4 3689
FID C 5 1746
FID C 3 7805
SNT TOP T 473 1
FID C 4 2523
FID C 5 1403
FID C 3 6047
SNT TOP T 474 1
FID C 4 2408
FID C 5 1396
FID C 3 5882
SNT TOP T 475 1
FID C 4 2407
FID C 5 1395
FID C 3 5881
SNT TOP T 476 1
FID C 4 2627
FID C 5 1427
FID C 3 6261
SNT TOP T 477 1
FID C 4 2632
FID C 5 1430
FID C 3 6268
SNT TOP T 478 1
FID C 4 2795
FID C 5 1489
FID C 3 6571
SNT TOP T 479 1
FID C 4 2794
FID C 5 1488
FID C 3 6570
SNT TOP T 480 1
FID C 4 2793
FID C 5 1487
FID C 3 6569
SNT TOP T 481 1
FID C 4 2881
FID C 5 1524
FID C 3 6795
SNT TOP T 482 1
FID C 4 2890
FID C 5 1533
FID C 3 6804
SNT TOP T 483 1
FID C 4 2879
FID C 5 1522
FID C 3 6793
SNT TOP T 484 1
FID C 4 2878
FID C 5 1521
FID C 3 6792
SNT TOP T 485 1
FID C 4 2886
FID C 5 1529
FID C 3 6800
SNT TOP T 486 1
FID C 4 2748
FID C 5 1471
FID C 3 6511
SNT TOP T 487 1
FID C 4 2874
FID C 5 1517
FID C 3 6679
SNT TOP T 488 1
FID C 4 3475
FID C 5 1598
FID C 3 7469
SNT TOP T 489 1
FID C 4 2875
FID C 5 1518
FID C 3 6680
SNT TOP T 490 1
FID C 4 2868
FID C 5 1516
FID C 3 6673
SNT TOP T 491 1
FID C 4 3397
FID C 5 1573
FID C 3 7367
SNT TOP T 492 1
FID C 4 3423
FID C 5 1581
FID C 3 7402
SNT TOP T 493 1
FID C 4 3421
FID C 5 1579
FID C 3 7400
SNT TOP T 494 1
FID C 4 3393
FID C 5 1572
FID C 3 7362
SNT TOP T 495 1
FID C 4 3584
FID C 5 1703
FID C 3 7674
SNT TOP T 496 1
FID C 4 3144
FID C 5 1556
FID C 3 7095
SNT TOP T 497 1
FID C 4 3141
FID C 5 1553
FID C 3 7092
SNT TOP T 498 1
FID C 4 3132
FID C 5 1550
FID C 3 7070
SNT TOP T 499 1
FID C 4 3571
FID C 5 1691
FID C 3 7659
SNT TOP T 500 1
FID C 4 3142
FID C 5 1554
FID C 3 7093
SNT TOP T 501 1
FID C 4 3572
FID C 5 1692
FID C 3 7660
SNT TOP T 502 1
FID C 4 3589
FID C 5 1708
FID C 3 7679
SNT TOP T 503 1
FID C 4 3366
FID C 5 1559
FID C 3 7326
SNT TOP T 504 1
FID C 4 3588
FID C 5 1707
FID C 3 7678
SNT TOP T 505 1
FID C 4 3576
FID C 5 1695
FID C 3 7666
SNT TOP T 506 1
FID C 4 3367
FID C 5 1560
FID C 3 7327
SNT TOP T 507 1
FID C 4 3675
FID C 5 1732
FID C 3 7788
SNT TOP T 508 1
FID C 4 2633
FID C 5 1431
FID C 3 6269
SNT TOP T 509 1
FID C 4 3699
FID C 5 1749
FID C 3 7815
SNT TOP T 510 1
FID C 4 3136
FID C 5 1552
FID C 3 7087
SNT TOP T 511 1
FID C 4 3688
FID C 5 1745
FID C 3 7802
SNT TOP T 514 1
FID C 4 2533
FID C 5 1406
FID C 3 6081
SNT TOP T 515 1
FID C 4 2409
FID C 5 1397
FID C 3 5883
SNT TOP T 516 1
FID C 4 2500
FID C 5 1402
FID C 3 6010
SNT TOP T 517 1
FID C 4 2428
FID C 5 1399
FID C 3 5913
SNT TOP T 518 1
FID C 4 2427
FID C 5 1398
FID C 3 5910
SNT TOP T 519 1
FID C 4 2535
FID C 5 1408
FID C 3 6087
SNT TOP T 520 1
FID C 4 2664
FID C 5 1440
FID C 3 6342
SNT TOP T 521 1
FID C 4 2630
FID C 5 1429
FID C 3 6265
SNT TOP T 522 1
FID C 4 2647
FID C 5 1436
FID C 3 6288
SNT TOP T 523 1
FID C 4 2634
FID C 5 1432
FID C 3 6270
SNT TOP T 524 1
FID C 4 2635
FID C 5 1433
FID C 3 6271
SNT TOP T 525 1
FID C 4 2636
FID C 5 1434
FID C 3 6272
SNT TOP T 526 1
FID C 4 2824
FID C 5 1504
FID C 3 6619
SNT TOP T 527 1
FID C 4 2703
FID C 5 1456
FID C 3 6426
SNT TOP T 528 1
FID C 4 2835
FID C 5 1509
FID C 3 6633
SNT TOP T 529 1
FID C 4 3737
FID C 5 1766
FID C 3 7859
SNT TOP T 530 1
FID C 4 2763
FID C 5 1478
FID C 3 6529
SNT TOP T 531 1
FID C 4 2779
FID C 5 1482
FID C 3 6548
SNT TOP T 532 1
FID C 4 2781
FID C 5 1484
FID C 3 6553
SNT TOP T 533 1
FID C 4 2877
FID C 5 1520
FID C 3 6791
SNT TOP T 534 1
FID C 4 2876
FID C 5 1519
FID C 3 6790
SNT TOP T 535 1
FID C 4 3018
FID C 5 1543
FID C 3 6946
SNT TOP T 536 1
FID C 4 2979
FID C 5 1537
FID C 3 6895
SNT TOP T 537 1
FID C 4 2994
FID C 5 1539
FID C 3 6916
SNT TOP T 538 1
FID C 4 2996
FID C 5 1540
FID C 3 6919
SNT TOP T 539 1
FID C 4 2880
FID C 5 1523
FID C 3 6794
SNT TOP T 540 1
FID C 4 2891
FID C 5 1534
FID C 3 6805
SNT TOP T 541 1
FID C 4 3022
FID C 5 1545
FID C 3 6955
SNT TOP T 543 1
FID C 4 2687
FID C 5 1448
FID C 3 6399
SNT TOP T 544 1
FID C 4 3078
FID C 5 1548
FID C 3 7014
SNT TOP T 545 1
FID C 4 2885
FID C 5 1528
FID C 3 6799
SNT TOP T 546 0
FID C 4 3110
FID C 5 1549
FID C 3 7046
SNT TOP T 547 1
FID C 4 2867
FID C 5 1515
FID C 3 6672
SNT TOP T 548 1
FID C 4 2706
FID C 5 1458
FID C 3 6433
SNT TOP T 549 1
FID C 4 3727
FID C 5 1756
FID C 3 7844
SNT TOP T 550 1
FID C 4 3476
FID C 5 1599
FID C 3 7470
SNT TOP T 551 1
FID C 4 3387
FID C 5 1569
FID C 3 7355
SNT TOP T 554 1
FID C 4 3424
FID C 5 1582
FID C 3 7403
SNT TOP T 555 1
FID C 4 3422
FID C 5 1580
FID C 3 7401
SNT TOP T 556 1
FID C 4 3416
FID C 5 1578
FID C 3 7394
SNT TOP T 557 1
FID C 4 3143
FID C 5 1555
FID C 3 7094
SNT TOP T 558 1
FID C 4 3583
FID C 5 1702
FID C 3 7673
SNT TOP T 559 1
FID C 4 3732
FID C 5 1761
FID C 3 7852
SNT TOP T 560 1
FID C 4 3731
FID C 5 1760
FID C 3 7850
SNT TOP T 561 1
FID C 4 3133
FID C 5 1551
FID C 3 7071
SNT TOP T 562 1
FID C 4 3573
FID C 5 1693
FID C 3 7661
SNT TOP T 563 1
FID C 4 3620
FID C 5 1714
FID C 3 7717
SNT TOP T 564 1
FID C 4 3363
FID C 5 1558
FID C 3 7323
SNT TOP T 565 1
FID C 4 3644
FID C 5 1722
FID C 3 7752
SNT TOP T 566 1
FID C 4 2669
FID C 5 1441
FID C 3 6357
SNT TOP T 567 1
FID C 4 3587
FID C 5 1706
FID C 3 7677
SNT TOP T 568 1
FID C 4 3586
FID C 5 1705
FID C 3 7676
SNT TOP T 569 1
FID C 4 3632
FID C 5 1717
FID C 3 7732
SNT TOP T 570 1
FID C 4 3590
FID C 5 1709
FID C 3 7680
SNT TOP T 572 1
FID C 4 3633
FID C 5 1718
FID C 3 7735
SNT TOP T 573 1
FID C 4 3585
FID C 5 1704
FID C 3 7675
SNT TOP T 574 1
FID C 4 3592
FID C 5 1710
FID C 3 7683
SNT TOP T 575 1
FID C 4 3575
FID C 5 1694
FID C 3 7665
SNT TOP T 576 1
FID C 4 3368
FID C 5 1561
FID C 3 7328
SNT TOP T 577 1
FID C 4 3673
FID C 5 1730
FID C 3 7786
SNT TOP T 578 1
FID C 4 3674
FID C 5 1731
FID C 3 7787
SNT TOP T 580 1
FID C 4 3690
FID C 5 1747
FID C 3 7806
SNT TOP T 581 1
FID C 4 3681
FID C 5 1738
FID C 3 7795
SNT TOP T 582 1
FID C 4 2710
FID C 5 1460
FID C 3 6442
SNT TOP T 583 1
FID C 4 3676
FID C 5 1733
FID C 3 7790
SNT TOP T 584 1
FID C 4 3680
FID C 5 1737
FID C 3 7794
SNT TOP T 585 0
FID C 4 2750
FID C 5 1472
FID C 3 6514
SNT TOP T 586 1
FID C 4 3687
FID C 5 1744
FID C 3 7801
SNT TOP T 587 1
FID C 4 3380
FID C 5 1567
FID C 3 7344
SNT TOP T 588 1
FID C 4 3377
FID C 5 1565
FID C 3 7341
SNT TOP T 589 1
FID C 4 3378
FID C 5 1566
FID C 3 7342
SNT TOP T 590 1
FID C 4 3707
FID C 5 1753
FID C 3 7824
SNT TOP T 591 1
FID C 4 3708
FID C 5 1754
FID C 3 7825
SNT TOP T 592 1
FID C 4 3704
FID C 5 1750
FID C 3 7821
SNT TOP T 593 0
FID C 4 2977
FID C 5 1536
FID C 3 6893
SNT TOP T 593 2
FID C 4 2998
FID C 5 1541
FID C 3 6922
SNT TOP T 594 0
FID C 4 2674
FID C 5 1443
FID C 3 6368
SNT TOP T 595 0
FID C 4 2676
FID C 5 1444
FID C 3 6372
SNT TOP T 596 1
FID C 4 2596
FID C 5 1414
FID C 3 6212
SNT TOP T 596 3
FID C 4 2594
FID C 5 1413
FID C 3 6203
SNT TOP T 597 2
FID C 4 2454
FID C 5 1400
FID C 3 5951
SNT TOP T 598 1
FID C 4 2662
FID C 5 1439
FID C 3 6338
SNT TOP T 599 1
FID C 4 2690
FID C 5 1450
FID C 3 6403
SNT TOP T 600 1
FID C 4 2708
FID C 5 1459
FID C 3 6440
SNT TOP T 601 8
FID C 4 2715
FID C 5 1462
FID C 3 6450
SNT TOP T 602 1
FID C 4 3657
FID C 5 1726
FID C 3 7769
SNT TOP T 602 9
FID C 4 3666
FID C 5 1728
FID C 3 7778
SNT TOP T 603 4
FID C 4 2741
FID C 5 1468
FID C 3 6497
SNT TOP T 603 5
FID C 4 3685
FID C 5 1742
FID C 3 7799
SNT TOP T 603 6
FID C 4 3686
FID C 5 1743
FID C 3 7800
SNT TOP T 603 7
FID H 0 5
FID C 4 3703
FID C 6 2860
FID C 3 7820
FID C 8 5850
FID L 11 1404
FID L 12 1404
FID L 13 2181
FID L 14 2180
FID L 15 1404
FID L 16 1404
SNT TOP T 603 8
FID H 0 6
FID C 4 3702
FID C 6 2859
FID C 3 7819
FID C 8 5849
FID L 11 1403
FID L 12 1403
FID L 13 2180
FID L 14 2179
FID L 15 1403
FID L 16 1403
SNT TOP T 603 9
FID H 0 7
FID C 4 3701
FID C 6 2858
FID C 3 7818
FID C 8 5848
FID L 11 1402
FID L 12 1402
FID L 13 2179
FID L 14 2178
FID L 15 1402
FID L 16 1402
SNT TOP T 603 10
FID H 0 8
FID C 4 3700
FID C 6 2857
FID C 3 7817
FID C 8 5847
FID L 11 1401
FID L 12 1401
FID L 13 2178
FID L 14 2177
FID L 15 1401
FID L 16 1401
SNT TOP T 604 7
FID C 4 3726
FID C 5 1755
FID C 3 7843
SNT TOP T 605 3
FID C 6 1745
FID C 8 4287
SNT TOP T 605 11
FID C 6 1783
FID C 8 4342
SNT TOP T 605 14
FID C 6 1775
FID C 8 4331
SNT TOP T 605 17
FID C 6 1778
FID C 8 4335
SNT TOP T 605 19
FID C 6 1771
FID C 8 4325
SNT TOP T 605 22
FID C 6 1769
FID C 8 4321
SNT TOP T 605 23
FID C 6 1761
FID C 8 4311
SNT TOP T 605 26
FID C 6 1757
FID C 8 4305
SNT TOP T 605 27
FID C 6 1755
FID C 8 4301
SNT TOP T 605 30
FID C 6 1814
FID C 8 4375
SNT TOP T 605 35
FID C 4 2433
FID C 3 5921
SNT TOP T 605 38
FID C 4 2431
FID C 3 5918
SNT TOP T 605 44
FID C 4 2472
FID C 3 5979
SNT TOP T 605 47
FID C 4 2465
FID C 3 5969
SNT TOP T 605 49
FID C 4 2467
FID C 3 5972
SNT TOP T 605 52
FID C 4 2458
FID C 3 5959
SNT TOP T 605 53
FID C 4 2456
FID C 3 5955
SNT TOP T 605 56
FID C 4 2447
FID C 3 5941
SNT TOP T 605 57
FID C 4 2445
FID C 3 5937
SNT TOP T 605 60
FID C 4 2443
FID C 3 5933
SNT TOP T 605 63
FID C 4 2546
FID C 3 6108
SNT TOP B 4 1
FID C 6 2129
FID C 7 702
FID C 8 4849
SNT TOP B 12 1
FID C 6 1948
FID C 7 651
FID C 8 4579
SNT TOP B 13 1
FID C 6 1949
FID C 7 652
FID C 8 4582
SNT TOP B 14 0
FID C 6 1952
FID C 7 654
FID C 8 4589
SNT TOP B 15 0
FID C 6 1953
FID C 7 655
FID C 8 4591
SNT TOP B 16 0
FID C 6 1954
FID C 7 656
FID C 8 4594
SNT TOP B 20 0
FID C 6 2007
FID C 7 664
FID C 8 4683
SNT TOP B 21 0
FID C 6 2008
FID C 7 665
FID C 8 4686
SNT TOP B 22 1
FID C 6 1859
FID C 7 633
FID C 8 4446
SNT TOP B 23 1
FID C 6 1856
FID C 7 630
FID C 8 4435
SNT TOP B 24 1
FID C 6 1858
FID C 7 632
FID C 8 4445
SNT TOP B 25 1
FID C 6 1860
FID C 7 634
FID C 8 4448
SNT TOP B 26 1
FID C 6 1852
FID C 7 626
FID C 8 4421
SNT TOP B 27 1
FID C 6 1853
FID C 7 627
FID C 8 4422
SNT TOP B 28 1
FID C 6 1861
FID C 7 635
FID C 8 4450
SNT TOP B 29 1
FID C 6 1855
FID C 7 629
FID C 8 4432
SNT TOP B 30 1
FID C 6 1854
FID C 7 628
FID C 8 4429
SNT TOP B 31 1
FID C 6 1864
FID C 7 638
FID C 8 4459
SNT TOP B 32 1
FID C 6 1862
FID C 7 636
FID C 8 4454
SNT TOP B 33 1
FID C 6 1867
FID C 7 641
FID C 8 4466
SNT TOP B 34 1
FID C 6 1866
FID C 7 640
FID C 8 4464
SNT TOP B 35 1
FID C 6 2669
FID C 7 743
FID C 8 5618
SNT TOP B 36 1
FID C 6 2729
FID C 7 764
FID C 8 5687
SNT TOP B 37 1
FID C 6 2728
FID C 7 763
FID C 8 5686
SNT TOP B 38 1
FID C 6 2744
FID C 7 779
FID C 8 5706
SNT TOP B 39 1
FID C 6 2745
FID C 7 780
FID C 8 5707
SNT TOP B 40 1
FID C 6 2749
FID C 7 784
FID C 8 5712
SNT TOP B 41 1
FID C 6 2725
FID C 7 760
FID C 8 5682
SNT TOP B 42 1
FID C 6 2726
FID C 7 761
FID C 8 5683
SNT TOP B 43 1
FID C 6 2731
FID C 7 766
FID C 8 5689
SNT TOP B 44 1
FID C 6 2727
FID C 7 762
FID C 8 5685
SNT TOP B 45 1
FID C 6 2730
FID C 7 765
FID C 8 5688
SNT TOP B 46 1
FID C 6 2767
FID C 7 802
FID C 8 5734
SNT TOP B 47 1
FID C 6 2768
FID C 7 803
FID C 8 5735
SNT TOP B 48 1
FID C 6 2722
FID C 7 757
FID C 8 5678
SNT TOP B 49 1
FID C 6 2723
FID C 7 758
FID C 8 5679
SNT TOP B 50 1
FID C 6 2884
FID C 7 827
FID C 8 5882
SNT TOP B 51 1
FID C 6 2883
FID C 7 826
FID C 8 5878
SNT TOP B 52 1
FID C 6 2766
FID C 7 801
FID C 8 5733
SNT TOP B 53 1
FID C 6 2765
FID C 7 800
FID C 8 5732
SNT TOP B 54 1
FID C 6 2732
FID C 7 767
FID C 8 5690
SNT TOP B 55 1
FID C 6 2737
FID C 7 772
FID C 8 5695
SNT TOP B 56 1
FID C 6 2735
FID C 7 770
FID C 8 5693
SNT TOP B 57 1
FID C 6 2719
FID C 7 754
FID C 8 5672
SNT TOP B 58 1
FID C 6 2733
FID C 7 768
FID C 8 5691
SNT TOP B 59 1
FID C 6 2738
FID C 7 773
FID C 8 5696
SNT TOP B 60 1
FID C 6 2743
FID C 7 778
FID C 8 5705
SNT TOP B 61 1
FID C 6 2760
FID C 7 795
FID C 8 5727
SNT TOP B 62 1
FID C 6 2009
FID C 7 666
FID C 8 4688
SNT TOP B 63 1
FID C 6 2608
FID C 7 721
FID C 8 5537
SNT TOP B 64 1
FID C 6 2720
FID C 7 755
FID C 8 5676
SNT TOP B 65 1
FID C 6 2751
FID C 7 786
FID C 8 5714
SNT TOP B 66 1
FID C 6 2752
FID C 7 787
FID C 8 5716
SNT TOP B 67 1
FID C 6 2759
FID C 7 794
FID C 8 5726
SNT TOP B 68 1
FID C 6 2758
FID C 7 793
FID C 8 5725
SNT TOP B 69 1
FID C 6 2754
FID C 7 789
FID C 8 5719
SNT TOP B 70 1
FID C 6 2761
FID C 7 796
FID C 8 5728
SNT TOP B 71 1
FID C 6 2750
FID C 7 785
FID C 8 5713
SNT TOP B 72 1
FID C 6 2769
FID C 7 804
FID C 8 5737
SNT TOP B 73 1
FID C 6 2010
FID C 7 667
FID C 8 4691
SNT TOP B 74 1
FID C 6 2757
FID C 7 792
FID C 8 5724
SNT TOP B 75 1
FID C 6 2882
FID C 7 825
FID C 8 5877
SNT TOP B 76 1
FID C 6 2764
FID C 7 799
FID C 8 5731
SNT TOP B 77 1
FID C 6 2763
FID C 7 798
FID C 8 5730
SNT TOP B 78 1
FID C 6 2886
FID C 7 829
FID C 8 5884
SNT TOP B 79 1
FID C 6 2770
FID C 7 805
FID C 8 5739
SNT TOP B 80 1
FID C 6 2705
FID C 7 752
FID C 8 5654
SNT TOP B 81 1
FID C 6 2881
FID C 7 824
FID C 8 5875
SNT TOP B 82 1
FID C 6 1857
FID C 7 631
FID C 8 4442
SNT TOP B 83 1
FID C 6 1865
FID C 7 639
FID C 8 4463
SNT TOP B 84 1
FID C 6 2724
FID C 7 759
FID C 8 5680
SNT TOP B 85 1
FID C 6 2746
FID C 7 781
FID C 8 5709
SNT TOP B 86 1
FID C 6 2736
FID C 7 771
FID C 8 5694
SNT TOP B 87 1
FID C 6 2755
FID C 7 790
FID C 8 5722
SNT TOP B 88 1
FID C 6 2762
FID C 7 797
FID C 8 5729
SNT TOP B 89 1
FID C 6 2753
FID C 7 788
FID C 8 5717
SNT TOP B 90 1
FID C 6 2721
FID C 7 756
FID C 8 5677
SNT TOP B 94 1
FID C 6 2663
FID C 7 741
FID C 8 5610
SNT TOP B 95 1
FID C 6 2014
FID C 7 670
FID C 8 4700
SNT TOP B 96 1
FID C 6 2021
FID C 7 674
FID C 8 4707
SNT TOP B 97 1
FID C 6 2020
FID C 7 673
FID C 8 4706
SNT TOP B 98 1
FID C 6 2024
FID C 7 676
FID C 8 4712
SNT TOP B 99 1
FID C 6 2661
FID C 7 740
FID C 8 5608
SNT TOP B 100 1
FID C 6 2756
FID C 7 791
FID C 8 5723
SNT TOP B 101 1
FID C 6 2706
FID C 7 753
FID C 8 5657
SNT TOP B 102 0
FID C 7 706
FID C 8 5050
SNT TOP B 103 0
FID C 7 806
FID C 8 5744
SNT TOP B 104 0
FID C 7 818
FID C 8 5832
SNT TOP B 105 0
FID C 6 2066
FID C 7 691
FID C 8 4775
SNT TOP B 106 1
FID C 6 2887
FID C 7 830
FID C 8 5886
SNT TOP B 107 4
FID C 6 2894
FID C 7 837
FID C 8 5897
SNT TOP B 108 3
FID C 6 1984
FID C 7 658
FID C 8 4657
SNT TOP B 109 1
FID C 6 1939
FID C 7 650
FID C 8 4566
SNT TOP B 111 0
FID C 6 2836
FID C 7 816
FID C 8 5818
SNT TOP B 116 1
FID C 6 2307
FID C 7 708
FID C 8 5210
SNT TOP B 118 1
FID C 6 2387
FID C 7 715
FID C 8 5302
SNT TOP B 119 1
FID C 6 2386
FID C 7 714
FID C 8 5297
SNT TOP B 128 0
FID C 6 1950
FID C 7 653
FID C 8 4585
SNT TOP B 132 0
FID C 6 2045
FID C 7 680
FID C 8 4743
SNT TOP B 133 0
FID C 6 2044
FID C 7 679
FID C 8 4741
SNT TOP B 134 0
FID C 6 2046
FID C 7 681
FID C 8 4745
SNT TOP B 135 0
FID C 6 2050
FID C 7 685
FID C 8 4752
SNT TOP B 136 0
FID C 6 2051
FID C 7 686
FID C 8 4754
SNT TOP B 150 0
FID C 6 1972
FID C 7 657
FID C 8 4631
SNT TOP B 152 0
FID C 6 2060
FID C 7 689
FID C 8 4768
SNT TOP B 153 1
FID C 6 2063
FID C 7 690
FID C 8 4772
SNT TOP B 157 1
FID C 6 1921
FID C 7 649
FID C 8 4543
SNT TOP B 161 1
FID C 6 2118
FID C 7 699
FID C 8 4834
SNT TOP B 162 1
FID C 6 2119
FID C 7 700
FID C 8 4836
SNT TOP B 169 1
FID C 6 2128
FID C 7 701
FID C 8 4848
SNT TOP B 173 1
FID C 6 2006
FID C 7 663
FID C 8 4682
SNT TOP B 178 1
FID C 6 2099
FID C 7 695
FID C 8 4814
SNT TOP B 179 1
FID C 6 2102
FID C 7 697
FID C 8 4818
SNT TOP B 180 0
FID C 6 2049
FID C 7 684
FID C 8 4751
SNT TOP B 190 1
FID C 6 2088
FID C 7 692
FID C 8 4800
SNT TOP B 192 1
FID C 6 2090
FID C 7 693
FID C 8 4802
SNT TOP B 194 1
FID C 6 1986
FID C 7 659
FID C 8 4659
SNT TOP B 199 1
FID C 6 2897
FID C 7 840
FID C 8 5903
SNT TOP B 203 1
FID C 6 2893
FID C 7 836
FID C 8 5895
SNT TOP B 212 1
FID C 6 2361
FID C 7 710
FID C 8 5266
SNT TOP B 213 1
FID C 6 2360
FID C 7 709
FID C 8 5264
SNT TOP B 219 1
FID C 6 2272
FID C 7 707
FID C 8 5174
SNT TOP B 225 1
FID C 6 2892
FID C 7 835
FID C 8 5893
SNT TOP B 226 1
FID C 6 2362
FID C 7 711
FID C 8 5267
SNT TOP B 233 1
FID C 6 2653
FID C 7 738
FID C 8 5595
SNT TOP B 246 1
FID C 6 2635
FID C 7 733
FID C 8 5569
SNT TOP B 249 1
FID C 6 2040
FID C 7 678
FID C 8 4728
SNT TOP B 250 1
FID C 6 2597
FID C 7 716
FID C 8 5519
SNT TOP B 252 1
FID C 6 2659
FID C 7 739
FID C 8 5601
SNT TOP B 259 0
FID C 6 2629
FID C 7 732
FID C 8 5563
SNT TOP B 261 1
FID C 6 2885
FID C 7 828
FID C 8 5883
SNT TOP B 263 1
FID C 6 2803
FID C 7 810
FID C 8 5778
SNT TOP B 266 0
FID C 6 2775
FID C 7 807
FID C 8 5748
SNT TOP B 267 0
FID C 6 2880
FID C 7 823
FID C 8 5874
SNT TOP B 270 0
FID C 6 2879
FID C 7 822
FID C 8 5871
SNT TOP B 273 0
FID C 6 2805
FID C 7 811
FID C 8 5781
SNT TOP B 274 1
FID C 6 2814
FID C 7 812
FID C 8 5791
SNT TOP B 286 1
FID C 6 2002
FID C 7 662
FID C 8 4678
SNT TOP B 305 1
FID C 6 2878
FID C 7 821
FID C 8 5870
SNT TOP B 307 0
FID C 6 2048
FID C 7 683
FID C 8 4749
SNT TOP B 311 1
FID C 6 2100
FID C 7 696
FID C 8 4816
SNT TOP B 333 1
FID C 6 2850
FID C 7 820
FID C 8 5839
SNT TOP B 336 1
FID C 6 2889
FID C 7 832
FID C 8 5888
SNT TOP B 337 1
FID C 6 2891
FID C 7 834
FID C 8 5892
SNT TOP B 338 1
FID C 6 2890
FID C 7 833
FID C 8 5890
SNT TOP B 341 1
FID C 6 2895
FID C 7 838
FID C 8 5898
SNT TOP B 343 0
FID C 6 2047
FID C 7 682
FID C 8 4747
SNT TOP B 349 1
FID C 6 2023
FID C 7 675
FID C 8 4711
SNT TOP B 350 1
FID C 6 2896
FID C 7 839
FID C 8 5901
SNT TOP B 351 0
FID C 6 2643
FID C 7 736
FID C 8 5581
SNT TOP B 352 0
FID C 6 2670
FID C 7 744
FID C 8 5619
SNT TOP B 355 1
FID C 6 1835
FID C 7 624
FID C 8 4400
SNT TOP B 356 1
FID C 6 1722
FID C 7 620
FID C 8 4260
SNT TOP B 357 1
FID C 6 1720
FID C 7 618
FID C 8 4258
SNT TOP B 358 1
FID C 6 1917
FID C 7 648
FID C 8 4539
SNT TOP B 359 1
FID C 6 1915
FID C 7 646
FID C 8 4537
SNT TOP B 360 1
FID C 6 1916
FID C 7 647
FID C 8 4538
SNT TOP B 361 1
FID C 6 1914
FID C 7 645
FID C 8 4536
SNT TOP B 362 1
FID C 6 2147
FID C 7 704
FID C 8 4869
SNT TOP B 363 1
FID C 6 2667
FID C 7 742
FID C 8 5614
SNT TOP B 364 1
FID C 6 2615
FID C 7 726
FID C 8 5545
SNT TOP B 365 1
FID C 6 2648
FID C 7 737
FID C 8 5588
SNT TOP B 366 1
FID C 6 2688
FID C 7 746
FID C 8 5637
SNT TOP B 367 1
FID C 6 2689
FID C 7 747
FID C 8 5638
SNT TOP B 368 1
FID C 6 2687
FID C 7 745
FID C 8 5636
SNT TOP B 369 1
FID C 6 2777
FID C 7 809
FID C 8 5750
SNT TOP B 370 1
FID C 6 2776
FID C 7 808
FID C 8 5749
SNT TOP B 371 1
FID C 6 2693
FID C 7 750
FID C 8 5642
SNT TOP B 372 1
FID C 6 2848
FID C 7 819
FID C 8 5834
SNT TOP B 373 1
FID C 6 1840
FID C 7 625
FID C 8 4407
SNT TOP B 374 1
FID C 6 1721
FID C 7 619
FID C 8 4259
SNT TOP B 385 1
FID C 6 1739
FID C 7 621
FID C 8 4278
SNT TOP B 386 1
FID C 6 1741
FID C 7 622
FID C 8 4282
SNT TOP B 387 1
FID C 6 1752
FID C 7 623
FID C 8 4296
SNT TOP B 388 1
FID C 6 1868
FID C 7 642
FID C 8 4469
SNT TOP B 389 1
FID C 6 1863
FID C 7 637
FID C 8 4458
SNT TOP B 390 1
FID C 6 2057
FID C 7 688
FID C 8 4764
SNT TOP B 391 1
FID C 6 1989
FID C 7 661
FID C 8 4662
SNT TOP B 392 1
FID C 6 1912
FID C 7 644
FID C 8 4531
SNT TOP B 393 1
FID C 6 2055
FID C 7 687
FID C 8 4762
SNT TOP B 394 0
FID C 6 1988
FID C 7 660
FID C 8 4661
SNT TOP B 395 1
FID C 6 2116
FID C 7 698
FID C 8 4832
SNT TOP B 396 1
FID C 6 2097
FID C 7 694
FID C 8 4809
SNT TOP B 400 1
FID C 6 2703
FID C 7 751
FID C 8 5652
SNT TOP B 402 1
FID C 6 2013
FID C 7 669
FID C 8 4699
SNT TOP B 403 1
FID C 6 2148
FID C 7 705
FID C 8 4870
SNT TOP B 404 1
FID C 6 2140
FID C 7 703
FID C 8 4862
SNT TOP B 405 1
FID C 6 2613
FID C 7 725
FID C 8 5543
SNT TOP B 406 1
FID C 6 2612
FID C 7 724
FID C 8 5542
SNT TOP B 407 1
FID C 6 2739
FID C 7 774
FID C 8 5697
SNT TOP B 408 1
FID C 6 2742
FID C 7 777
FID C 8 5704
SNT TOP B 409 1
FID C 6 2747
FID C 7 782
FID C 8 5710
SNT TOP B 410 1
FID C 6 2603
FID C 7 718
FID C 8 5529
SNT TOP B 411 1
FID C 6 2690
FID C 7 748
FID C 8 5639
SNT TOP B 412 1
FID C 6 2604
FID C 7 719
FID C 8 5533
SNT TOP B 413 1
FID C 6 2637
FID C 7 734
FID C 8 5572
SNT TOP B 414 1
FID C 6 2888
FID C 7 831
FID C 8 5887
SNT TOP B 415 1
FID C 6 2691
FID C 7 749
FID C 8 5640
SNT TOP B 416 1
FID C 6 2602
FID C 7 717
FID C 8 5526
SNT TOP B 417 1
FID C 6 2639
FID C 7 735
FID C 8 5575
SNT TOP B 418 1
FID C 6 2734
FID C 7 769
FID C 8 5692
SNT TOP B 419 1
FID C 6 2740
FID C 7 775
FID C 8 5700
SNT TOP B 420 1
FID C 6 2741
FID C 7 776
FID C 8 5703
SNT TOP B 421 1
FID C 6 2748
FID C 7 783
FID C 8 5711
SNT TOP B 422 1
FID C 6 2607
FID C 7 720
FID C 8 5536
SNT TOP B 423 1
FID C 6 2011
FID C 7 668
FID C 8 4696
SNT TOP B 424 1
FID C 6 2611
FID C 7 723
FID C 8 5541
SNT TOP B 425 1
FID C 6 2610
FID C 7 722
FID C 8 5539
SNT TOP B 427 1
FID C 6 2383
FID C 7 713
FID C 8 5293
SNT TOP B 428 1
FID C 6 2382
FID C 7 712
FID C 8 5291
SNT TOP B 429 1
FID C 6 2621
FID C 7 728
FID C 8 5555
SNT TOP B 430 1
FID C 6 2622
FID C 7 729
FID C 8 5556
SNT TOP B 431 1
FID C 6 1911
FID C 7 643
FID C 8 4528
SNT TOP B 432 1
FID C 6 2816
FID C 7 813
FID C 8 5795
SNT TOP B 435 1
FID C 6 2628
FID C 7 731
FID C 8 5562
SNT TOP B 436 1
FID C 6 2627
FID C 7 730
FID C 8 5561
SNT TOP B 437 1
FID C 6 2822
FID C 7 814
FID C 8 5802
SNT TOP B 438 1
FID C 6 2019
FID C 7 672
FID C 8 4705
SNT TOP B 439 1
FID C 6 2025
FID C 7 677
FID C 8 4713
SNT TOP B 440 1
FID C 6 2017
FID C 7 671
FID C 8 4703
SNT TOP B 442 0
FID C 6 2832
FID C 7 815
FID C 8 5814
SNT TOP B 443 0
FID C 6 2843
FID C 7 817
FID C 8 5826
SNT TOP B 444 2
FID C 6 2617
FID C 7 727
FID C 8 5548
SNT VIA
FID H 0 348
FID C 4 3009
FID C 6 2262
FID C 3 6933
FID C 8 5161
FID L 13 1695
FID L 14 1694
SNT VIA
FID H 0 349
FID C 4 2811
FID C 6 2094
FID C 3 6605
FID C 8 4806
FID L 13 1444
FID L 14 1443
SNT VIA
FID H 0 350
FID C 4 2742
FID C 6 2041
FID C 3 6499
FID C 8 4732
FID L 13 1406
FID L 14 1405
SNT VIA
FID H 0 351
FID C 4 2719
FID C 6 2015
FID C 3 6463
FID C 8 4701
FID L 13 1388
FID L 14 1387
SNT VIA
FID H 0 352
FID C 4 2809
FID C 6 2093
FID C 3 6603
FID C 8 4805
FID L 13 1443
FID L 14 1442
SNT VIA
FID H 0 353
FID C 4 2807
FID C 6 2092
FID C 3 6601
FID C 8 4804
FID L 13 1442
FID L 14 1441
SNT VIA
FID H 0 354
FID C 4 2726
FID C 6 2028
FID C 3 6476
FID C 8 4716
FID L 13 1394
FID L 14 1393
SNT VIA
FID H 0 355
FID C 4 2727
FID C 6 2029
FID C 3 6479
FID C 8 4717
FID L 13 1395
FID L 14 1394
SNT VIA
FID H 0 356
FID C 4 2732
FID C 6 2034
FID C 3 6486
FID C 8 4722
FID L 13 1400
FID L 14 1399
SNT VIA
FID H 0 357
FID C 4 2978
FID C 6 2236
FID C 3 6894
FID C 8 5135
FID L 13 1669
FID L 14 1668
SNT VIA
FID H 0 358
FID C 4 2805
FID C 6 2091
FID C 3 6599
FID C 8 4803
FID L 13 1441
FID L 14 1440
SNT VIA
FID H 0 359
FID C 4 2725
FID C 6 2027
FID C 3 6475
FID C 8 4715
FID L 13 1393
FID L 14 1392
SNT VIA
FID H 0 360
FID C 4 2723
FID C 6 2022
FID C 3 6473
FID C 8 4710
FID L 13 1391
FID L 14 1390
SNT VIA
FID H 0 361
FID C 4 2595
FID C 6 1919
FID C 3 6211
FID C 8 4541
FID L 13 1314
FID L 14 1313
SNT VIA
FID H 0 362
FID C 4 2722
FID C 6 2018
FID C 3 6466
FID C 8 4704
FID L 13 1390
FID L 14 1389
SNT VIA
FID H 0 363
FID C 4 2680
FID C 6 1981
FID C 3 6391
FID C 8 4654
FID L 13 1367
FID L 14 1366
SNT VIA
FID H 0 364
FID C 4 2728
FID C 6 2030
FID C 3 6480
FID C 8 4718
FID L 13 1396
FID L 14 1395
SNT VIA
FID H 0 365
FID C 4 2405
FID C 6 1718
FID C 3 5870
FID C 8 4248
FID L 13 1154
FID L 14 1153
SNT VIA
FID H 0 366
FID C 4 2736
FID C 6 2036
FID C 3 6491
FID C 8 4724
FID L 13 1402
FID L 14 1401
SNT VIA
FID H 0 367
FID C 4 2729
FID C 6 2031
FID C 3 6481
FID C 8 4719
FID L 13 1397
FID L 14 1396
SNT VIA
FID H 0 368
FID C 4 2679
FID C 6 1980
FID C 3 6386
FID C 8 4653
FID L 13 1366
FID L 14 1365
SNT VIA
FID H 0 369
FID C 4 2734
FID C 6 2035
FID C 3 6488
FID C 8 4723
FID L 13 1401
FID L 14 1400
SNT VIA
FID H 0 370
FID C 4 2730
FID C 6 2032
FID C 3 6482
FID C 8 4720
FID L 13 1398
FID L 14 1397
SNT VIA
FID H 0 371
FID C 4 2593
FID C 6 1918
FID C 3 6202
FID C 8 4540
FID L 13 1313
FID L 14 1312
SNT VIA
FID H 0 372
FID C 4 2731
FID C 6 2033
FID C 3 6483
FID C 8 4721
FID L 13 1399
FID L 14 1398
SNT VIA
FID H 0 373
FID C 4 3021
FID C 6 2271
FID C 3 6952
FID C 8 5171
FID L 13 1704
FID L 14 1703
SNT VIA
FID H 0 374
FID C 4 3023
FID C 6 2273
FID C 3 6956
FID C 8 5175
FID L 13 1705
FID L 14 1704
SNT VIA
FID H 0 375
FID C 4 2724
FID C 6 2026
FID C 3 6474
FID C 8 4714
FID L 13 1392
FID L 14 1391
SNT VIA
FID H 0 376
FID C 4 2625
FID C 6 1938
FID C 3 6259
FID C 8 4565
FID L 13 1332
FID L 14 1331
SNT VIA
FID H 0 377
FID C 4 2721
FID C 6 2016
FID C 3 6465
FID C 8 4702
FID L 13 1389
FID L 14 1388
SNT VIA
FID H 0 378
FID C 4 2695
FID C 6 1994
FID C 3 6408
FID C 8 4669
FID L 13 1376
FID L 14 1375
SNT VIA
FID H 0 379
FID C 4 2628
FID C 6 1940
FID C 3 6262
FID C 8 4569
FID L 13 1333
FID L 14 1332
SNT VIA
FID H 0 380
FID C 4 3025
FID C 6 2274
FID C 3 6961
FID C 8 5176
FID L 13 1706
FID L 14 1705
SNT VIA
FID H 0 381
FID C 4 2631
FID C 6 1941
FID C 3 6267
FID C 8 4572
FID L 13 1334
FID L 14 1333
SNT VIA
FID H 0 382
FID C 4 3036
FID C 6 2285
FID C 3 6972
FID C 8 5187
FID L 13 1717
FID L 14 1716
SNT VIA
FID H 0 383
FID C 4 2718
FID C 6 2012
FID C 3 6462
FID C 8 4697
FID L 13 1387
FID L 14 1386
SNT VIA
FID H 0 384
FID C 4 2685
FID C 6 1985
FID C 3 6397
FID C 8 4658
FID L 13 1370
FID L 14 1369
SNT VIA
FID H 0 385
FID C 4 2686
FID C 6 1987
FID C 3 6398
FID C 8 4660
FID L 13 1371
FID L 14 1370
SNT VIA
FID H 0 386
FID C 4 2641
FID C 6 1946
FID C 3 6277
FID C 8 4577
FID L 13 1339
FID L 14 1338
SNT VIA
FID H 0 387
FID C 4 2716
FID C 6 2005
FID C 3 6451
FID C 8 4681
FID L 13 1386
FID L 14 1385
SNT VIA
FID H 0 388
FID C 4 2642
FID C 6 1947
FID C 3 6278
FID C 8 4578
FID L 13 1340
FID L 14 1339
SNT VIA
FID H 0 389
FID C 4 2675
FID C 6 1978
FID C 3 6371
FID C 8 4651
FID L 13 1364
FID L 14 1363
SNT VIA
FID H 0 390
FID C 4 3066
FID C 6 2315
FID C 3 7002
FID C 8 5218
FID L 13 1746
FID L 14 1745
SNT VIA
FID H 0 391
FID C 4 3063
FID C 6 2312
FID C 3 6999
FID C 8 5215
FID L 13 1743
FID L 14 1742
SNT VIA
FID H 0 392
FID C 4 2673
FID C 6 1977
FID C 3 6367
FID C 8 4650
FID L 13 1363
FID L 14 1362
SNT VIA
FID H 0 393
FID C 4 3065
FID C 6 2314
FID C 3 7001
FID C 8 5217
FID L 13 1745
FID L 14 1744
SNT VIA
FID H 0 394
FID C 4 2854
FID C 6 2131
FID C 3 6654
FID C 8 4853
FID L 13 1472
FID L 14 1471
SNT VIA
FID H 0 395
FID C 4 3068
FID C 6 2317
FID C 3 7004
FID C 8 5220
FID L 13 1748
FID L 14 1747
SNT VIA
FID H 0 396
FID C 4 3069
FID C 6 2318
FID C 3 7005
FID C 8 5221
FID L 13 1749
FID L 14 1748
SNT VIA
FID H 0 397
FID C 4 2637
FID C 6 1942
FID C 3 6273
FID C 8 4573
FID L 13 1335
FID L 14 1334
SNT VIA
FID H 0 398
FID C 4 2638
FID C 6 1943
FID C 3 6274
FID C 8 4574
FID L 13 1336
FID L 14 1335
SNT VIA
FID H 0 399
FID C 4 2640
FID C 6 1945
FID C 3 6276
FID C 8 4576
FID L 13 1338
FID L 14 1337
SNT VIA
FID H 0 400
FID C 4 2639
FID C 6 1944
FID C 3 6275
FID C 8 4575
FID L 13 1337
FID L 14 1336
SNT VIA
FID H 0 401
FID C 4 3057
FID C 6 2306
FID C 3 6993
FID C 8 5208
FID L 13 1738
FID L 14 1737
SNT VIA
FID H 0 402
FID C 4 2429
FID C 6 1742
FID C 3 5914
FID C 8 4283
FID L 13 1173
FID L 14 1172
SNT VIA
FID H 0 403
FID C 4 2804
FID C 6 2089
FID C 3 6598
FID C 8 4801
FID L 13 1440
FID L 14 1439
SNT VIA
FID H 0 404
FID C 4 2426
FID C 6 1740
FID C 3 5909
FID C 8 4279
FID L 13 1172
FID L 14 1171
SNT VIA
FID H 0 405
FID C 4 3105
FID C 6 2353
FID C 3 7041
FID C 8 5256
FID L 13 1784
FID L 14 1783
SNT VIA
FID H 0 406
FID C 4 3108
FID C 6 2356
FID C 3 7044
FID C 8 5259
FID L 13 1787
FID L 14 1786
SNT VIA
FID H 0 407
FID C 4 2425
FID C 6 1738
FID C 3 5908
FID C 8 4276
FID L 13 1171
FID L 14 1170
SNT VIA
FID H 0 408
FID C 4 2856
FID C 6 2133
FID C 3 6656
FID C 8 4855
FID L 13 1474
FID L 14 1473
SNT VIA
FID H 0 409
FID C 4 3107
FID C 6 2355
FID C 3 7043
FID C 8 5258
FID L 13 1786
FID L 14 1785
SNT VIA
FID H 0 410
FID C 4 3106
FID C 6 2354
FID C 3 7042
FID C 8 5257
FID L 13 1785
FID L 14 1784
SNT VIA
FID H 0 411
FID C 4 2855
FID C 6 2132
FID C 3 6655
FID C 8 4854
FID L 13 1473
FID L 14 1472
SNT VIA
FID H 0 412
FID C 4 3099
FID C 6 2347
FID C 3 7035
FID C 8 5250
FID L 13 1778
FID L 14 1777
SNT VIA
FID H 0 413
FID C 4 3359
FID C 6 2616
FID C 3 7317
FID C 8 5547
FID L 13 2029
FID L 14 2028
SNT VIA
FID H 0 414
FID C 4 3353
FID C 6 2601
FID C 3 7310
FID C 8 5524
FID L 13 2024
FID L 14 2023
SNT VIA
FID H 0 415
FID C 4 3382
FID C 6 2636
FID C 3 7346
FID C 8 5571
FID L 13 2042
FID L 14 2041
SNT VIA
FID H 0 416
FID C 4 3383
FID C 6 2638
FID C 3 7347
FID C 8 5574
FID L 13 2043
FID L 14 2042
SNT VIA
FID H 0 417
FID C 4 2462
FID C 6 1774
FID C 3 5963
FID C 8 4328
FID L 13 1198
FID L 14 1197
SNT VIA
FID H 0 418
FID C 4 3360
FID C 6 2618
FID C 3 7318
FID C 8 5552
FID L 13 2030
FID L 14 2029
SNT VIA
FID H 0 419
FID C 4 2424
FID C 6 1737
FID C 3 5907
FID C 8 4275
FID L 13 1170
FID L 14 1169
SNT VIA
FID H 0 420
FID C 4 2453
FID C 6 1766
FID C 3 5947
FID C 8 4316
FID L 13 1192
FID L 14 1191
SNT VIA
FID H 0 421
FID C 4 3355
FID C 6 2606
FID C 3 7312
FID C 8 5535
FID L 13 2026
FID L 14 2025
SNT VIA
FID H 0 422
FID C 4 3354
FID C 6 2605
FID C 3 7311
FID C 8 5534
FID L 13 2025
FID L 14 2024
SNT VIA
FID H 0 423
FID C 4 2423
FID C 6 1736
FID C 3 5906
FID C 8 4274
FID L 13 1169
FID L 14 1168
SNT VIA
FID H 0 424
FID C 4 3439
FID C 6 2686
FID C 3 7425
FID C 8 5635
FID L 13 2081
FID L 14 2080
SNT VIA
FID H 0 425
FID C 4 2668
FID C 6 1974
FID C 3 6356
FID C 8 4647
FID L 13 1360
FID L 14 1359
SNT VIA
FID H 0 426
FID C 4 3438
FID C 6 2685
FID C 3 7424
FID C 8 5634
FID L 13 2080
FID L 14 2079
SNT VIA
FID H 0 427
FID C 4 2420
FID C 6 1733
FID C 3 5903
FID C 8 4271
FID L 13 1166
FID L 14 1165
SNT VIA
FID H 0 428
FID C 4 3437
FID C 6 2684
FID C 3 7423
FID C 8 5633
FID L 13 2079
FID L 14 2078
SNT VIA
FID H 0 429
FID C 4 3440
FID C 6 2692
FID C 3 7426
FID C 8 5641
FID L 13 2082
FID L 14 2081
SNT VIA
FID H 0 430
FID C 4 2499
FID C 6 1810
FID C 3 6006
FID C 8 4369
FID L 13 1231
FID L 14 1230
SNT VIA
FID H 0 431
FID C 4 3358
FID C 6 2614
FID C 3 7316
FID C 8 5544
FID L 13 2028
FID L 14 2027
SNT VIA
FID H 0 432
FID C 4 2864
FID C 6 2142
FID C 3 6666
FID C 8 4864
FID L 13 1482
FID L 14 1481
SNT VIA
FID H 0 433
FID C 4 3466
FID C 6 2715
FID C 3 7453
FID C 8 5666
FID L 13 2101
FID L 14 2100
SNT VIA
FID H 0 434
FID C 4 3467
FID C 6 2716
FID C 3 7454
FID C 8 5667
FID L 13 2102
FID L 14 2101
SNT VIA
FID H 0 435
FID C 4 3436
FID C 6 2683
FID C 3 7422
FID C 8 5632
FID L 13 2078
FID L 14 2077
SNT VIA
FID H 0 436
FID C 4 3375
FID C 6 2632
FID C 3 7339
FID C 8 5566
FID L 13 2039
FID L 14 2038
SNT VIA
FID H 0 437
FID C 4 3601
FID C 6 2787
FID C 3 7692
FID C 8 5760
FID L 13 2118
FID L 14 2117
SNT VIA
FID H 0 438
FID C 4 3574
FID C 6 2774
FID C 3 7664
FID C 8 5746
FID L 13 2108
FID L 14 2107
SNT VIA
FID H 0 439
FID C 4 3600
FID C 6 2786
FID C 3 7691
FID C 8 5759
FID L 13 2117
FID L 14 2116
SNT VIA
FID H 0 440
FID C 4 3602
FID C 6 2788
FID C 3 7693
FID C 8 5761
FID L 13 2119
FID L 14 2118
SNT VIA
FID H 0 441
FID C 4 3604
FID C 6 2790
FID C 3 7695
FID C 8 5763
FID L 13 2121
FID L 14 2120
SNT VIA
FID H 0 442
FID C 4 3598
FID C 6 2784
FID C 3 7689
FID C 8 5757
FID L 13 2115
FID L 14 2114
SNT VIA
FID H 0 443
FID C 4 3599
FID C 6 2785
FID C 3 7690
FID C 8 5758
FID L 13 2116
FID L 14 2115
SNT VIA
FID H 0 444
FID C 4 3140
FID C 6 2391
FID C 3 7091
FID C 8 5306
FID L 13 1815
FID L 14 1814
SNT VIA
FID H 0 445
FID C 4 3373
FID C 6 2631
FID C 3 7336
FID C 8 5565
FID L 13 2038
FID L 14 2037
SNT VIA
FID H 0 446
FID C 4 3139
FID C 6 2390
FID C 3 7090
FID C 8 5305
FID L 13 1814
FID L 14 1813
SNT VIA
FID H 0 447
FID C 4 3640
FID C 6 2820
FID C 3 7746
FID C 8 5799
FID L 13 2147
FID L 14 2146
SNT VIA
FID H 0 448
FID C 4 3138
FID C 6 2389
FID C 3 7089
FID C 8 5304
FID L 13 1813
FID L 14 1812
SNT VIA
FID H 0 449
FID C 4 3464
FID C 6 2714
FID C 3 7451
FID C 8 5665
FID L 13 2100
FID L 14 2099
SNT VIA
FID H 0 450
FID C 4 3461
FID C 6 2712
FID C 3 7448
FID C 8 5663
FID L 13 2098
FID L 14 2097
SNT VIA
FID H 0 451
FID C 4 3137
FID C 6 2388
FID C 3 7088
FID C 8 5303
FID L 13 1812
FID L 14 1811
SNT VIA
FID H 0 452
FID C 4 3611
FID C 6 2796
FID C 3 7705
FID C 8 5769
FID L 13 2127
FID L 14 2126
SNT VIA
FID H 0 453
FID C 4 2439
FID C 6 1751
FID C 3 5927
FID C 8 4293
FID L 13 1181
FID L 14 1180
SNT VIA
FID H 0 454
FID C 4 2659
FID C 6 1966
FID C 3 6334
FID C 8 4618
FID L 13 1353
FID L 14 1352
SNT VIA
FID H 0 455
FID C 4 2543
FID C 6 1850
FID C 3 6095
FID C 8 4417
FID L 13 1268
FID L 14 1267
SNT VIA
FID H 0 456
FID C 4 3463
FID C 6 2713
FID C 3 7450
FID C 8 5664
FID L 13 2099
FID L 14 2098
SNT VIA
FID H 0 457
FID C 4 2475
FID C 6 1786
FID C 3 5982
FID C 8 4345
FID L 13 1207
FID L 14 1206
SNT VIA
FID H 0 458
FID C 4 3472
FID C 6 2718
FID C 3 7460
FID C 8 5669
FID L 13 2104
FID L 14 2103
SNT VIA
FID H 0 459
FID C 4 2542
FID C 6 1849
FID C 3 6094
FID C 8 4416
FID L 13 1267
FID L 14 1266
SNT VIA
FID H 0 460
FID C 4 2474
FID C 6 1785
FID C 3 5981
FID C 8 4344
FID L 13 1206
FID L 14 1205
SNT VIA
FID H 0 461
FID C 4 2476
FID C 6 1787
FID C 3 5983
FID C 8 4346
FID L 13 1208
FID L 14 1207
SNT VIA
FID H 0 462
FID C 4 3458
FID C 6 2709
FID C 3 7445
FID C 8 5660
FID L 13 2095
FID L 14 2094
SNT VIA
FID H 0 463
FID C 4 3460
FID C 6 2711
FID C 3 7447
FID C 8 5662
FID L 13 2097
FID L 14 2096
SNT VIA
FID H 0 464
FID C 4 2540
FID C 6 1847
FID C 3 6092
FID C 8 4414
FID L 13 1265
FID L 14 1264
SNT VIA
FID H 0 465
FID C 4 2660
FID C 6 1967
FID C 3 6335
FID C 8 4619
FID L 13 1354
FID L 14 1353
SNT VIA
FID H 0 466
FID C 4 2473
FID C 6 1784
FID C 3 5980
FID C 8 4343
FID L 13 1205
FID L 14 1204
SNT VIA
FID H 0 467
FID C 4 2541
FID C 6 1848
FID C 3 6093
FID C 8 4415
FID L 13 1266
FID L 14 1265
SNT VIA
FID H 0 468
FID C 4 3634
FID C 6 2815
FID C 3 7736
FID C 8 5792
FID L 13 2143
FID L 14 2142
SNT VIA
FID H 0 469
FID C 4 3636
FID C 6 2818
FID C 3 7738
FID C 8 5797
FID L 13 2145
FID L 14 2144
SNT VIA
FID H 0 470
FID C 4 3459
FID C 6 2710
FID C 3 7446
FID C 8 5661
FID L 13 2096
FID L 14 2095
SNT VIA
FID H 0 471
FID C 4 3597
FID C 6 2783
FID C 3 7688
FID C 8 5756
FID L 13 2114
FID L 14 2113
SNT VIA
FID H 0 472
FID C 4 3593
FID C 6 2779
FID C 3 7684
FID C 8 5752
FID L 13 2110
FID L 14 2109
SNT VIA
FID H 0 473
FID C 4 3596
FID C 6 2782
FID C 3 7687
FID C 8 5755
FID L 13 2113
FID L 14 2112
SNT VIA
FID H 0 474
FID C 4 3639
FID C 6 2819
FID C 3 7745
FID C 8 5798
FID L 13 2146
FID L 14 2145
SNT VIA
FID H 0 475
FID C 4 3635
FID C 6 2817
FID C 3 7737
FID C 8 5796
FID L 13 2144
FID L 14 2143
SNT VIA
FID H 0 476
FID C 4 2544
FID C 6 1851
FID C 3 6096
FID C 8 4418
FID L 13 1269
FID L 14 1268
SNT VIA
FID H 0 477
FID C 4 2862
FID C 6 2139
FID C 3 6662
FID C 8 4861
FID L 13 1480
FID L 14 1479
SNT VIA
FID H 0 478
FID C 4 2515
FID C 6 1826
FID C 3 6030
FID C 8 4387
FID L 13 1246
FID L 14 1245
SNT VIA
FID H 0 479
FID C 4 3594
FID C 6 2780
FID C 3 7685
FID C 8 5753
FID L 13 2111
FID L 14 2110
SNT VIA
FID H 0 480
FID C 4 3595
FID C 6 2781
FID C 3 7686
FID C 8 5754
FID L 13 2112
FID L 14 2111
SNT VIA
FID H 0 481
FID C 4 2521
FID C 6 1832
FID C 3 6036
FID C 8 4393
FID L 13 1252
FID L 14 1251
SNT VIA
FID H 0 482
FID C 4 2863
FID C 6 2141
FID C 3 6663
FID C 8 4863
FID L 13 1481
FID L 14 1480
SNT VIA
FID H 0 483
FID C 4 3454
FID C 6 2707
FID C 3 7441
FID C 8 5658
FID L 13 2093
FID L 14 2092
SNT VIA
FID H 0 484
FID C 4 2516
FID C 6 1827
FID C 3 6031
FID C 8 4388
FID L 13 1247
FID L 14 1246
SNT VIA
FID H 0 485
FID C 4 2661
FID C 6 1968
FID C 3 6337
FID C 8 4620
FID L 13 1355
FID L 14 1354
SNT VIA
FID H 0 486
FID C 4 3414
FID C 6 2666
FID C 3 7387
FID C 8 5613
FID L 13 2064
FID L 14 2063
SNT VIA
FID H 0 487
FID C 4 3629
FID C 6 2811
FID C 3 7728
FID C 8 5787
FID L 13 2140
FID L 14 2139
SNT VIA
FID H 0 488
FID C 4 2519
FID C 6 1830
FID C 3 6034
FID C 8 4391
FID L 13 1250
FID L 14 1249
SNT VIA
FID H 0 489
FID C 4 2517
FID C 6 1828
FID C 3 6032
FID C 8 4389
FID L 13 1248
FID L 14 1247
SNT VIA
FID H 0 490
FID C 4 3413
FID C 6 2665
FID C 3 7386
FID C 8 5612
FID L 13 2063
FID L 14 2062
SNT VIA
FID H 0 491
FID C 4 2663
FID C 6 1969
FID C 3 6341
FID C 8 4621
FID L 13 1356
FID L 14 1355
SNT VIA
FID H 0 492
FID C 4 2520
FID C 6 1831
FID C 3 6035
FID C 8 4392
FID L 13 1251
FID L 14 1250
SNT VIA
FID H 0 493
FID C 4 2518
FID C 6 1829
FID C 3 6033
FID C 8 4390
FID L 13 1249
FID L 14 1248
SNT VIA
FID H 0 494
FID C 4 3630
FID C 6 2812
FID C 3 7729
FID C 8 5788
FID L 13 2141
FID L 14 2140
SNT VIA
FID H 0 495
FID C 4 2525
FID C 6 1836
FID C 3 6049
FID C 8 4401
FID L 13 1255
FID L 14 1254
SNT VIA
FID H 0 496
FID C 4 3609
FID C 6 2795
FID C 3 7700
FID C 8 5768
FID L 13 2126
FID L 14 2125
SNT VIA
FID H 0 497
FID C 4 3628
FID C 6 2810
FID C 3 7727
FID C 8 5786
FID L 13 2139
FID L 14 2138
SNT VIA
FID H 0 498
FID C 4 2514
FID C 6 1825
FID C 3 6029
FID C 8 4386
FID L 13 1245
FID L 14 1244
SNT VIA
FID H 0 499
FID C 4 2404
FID C 6 1717
FID C 3 5869
FID C 8 4247
FID L 13 1153
FID L 14 1152
SNT VIA
FID H 0 500
FID C 4 3627
FID C 6 2809
FID C 3 7726
FID C 8 5785
FID L 13 2138
FID L 14 2137
SNT VIA
FID H 0 501
FID C 4 2712
FID C 6 2001
FID C 3 6446
FID C 8 4677
FID L 13 1383
FID L 14 1382
SNT VIA
FID H 0 502
FID C 4 2760
FID C 6 2062
FID C 3 6526
FID C 8 4771
FID L 13 1416
FID L 14 1415
SNT VIA
FID H 0 503
FID C 4 2524
FID C 6 1834
FID C 3 6048
FID C 8 4395
FID L 13 1254
FID L 14 1253
SNT VIA
FID H 0 504
FID C 4 2522
FID C 6 1833
FID C 3 6037
FID C 8 4394
FID L 13 1253
FID L 14 1252
SNT VIA
FID H 0 505
FID C 4 2857
FID C 6 2134
FID C 3 6657
FID C 8 4856
FID L 13 1475
FID L 14 1474
SNT VIA
FID H 0 506
FID C 4 3631
FID C 6 2813
FID C 3 7730
FID C 8 5789
FID L 13 2142
FID L 14 2141
SNT VIA
FID H 0 507
FID C 4 2757
FID C 6 2059
FID C 3 6523
FID C 8 4766
FID L 13 1414
FID L 14 1413
SNT VIA
FID H 0 508
FID C 4 3623
FID C 6 2807
FID C 3 7720
FID C 8 5783
FID L 13 2136
FID L 14 2135
SNT VIA
FID H 0 509
FID C 4 2744
FID C 6 2043
FID C 3 6504
FID C 8 4738
FID L 13 1408
FID L 14 1407
SNT VIA
FID H 0 510
FID C 4 2755
FID C 6 2058
FID C 3 6521
FID C 8 4765
FID L 13 1413
FID L 14 1412
SNT VIA
FID H 0 511
FID C 4 3412
FID C 6 2664
FID C 3 7385
FID C 8 5611
FID L 13 2062
FID L 14 2061
SNT VIA
FID H 0 512
FID C 4 3411
FID C 6 2662
FID C 3 7384
FID C 8 5609
FID L 13 2061
FID L 14 2060
SNT VIA
FID H 0 513
FID C 4 2410
FID C 6 1723
FID C 3 5884
FID C 8 4261
FID L 13 1156
FID L 14 1155
SNT VIA
FID H 0 514
FID C 4 3625
FID C 6 2808
FID C 3 7724
FID C 8 5784
FID L 13 2137
FID L 14 2136
SNT VIA
FID H 0 515
FID C 4 2743
FID C 6 2042
FID C 3 6503
FID C 8 4737
FID L 13 1407
FID L 14 1406
SNT VIA
FID H 0 516
FID C 4 2411
FID C 6 1724
FID C 3 5885
FID C 8 4262
FID L 13 1157
FID L 14 1156
SNT VIA
FID H 0 517
FID C 4 2758
FID C 6 2061
FID C 3 6524
FID C 8 4769
FID L 13 1415
FID L 14 1414
SNT VIA
FID H 0 518
FID C 4 3607
FID C 6 2793
FID C 3 7698
FID C 8 5766
FID L 13 2124
FID L 14 2123
SNT VIA
FID H 0 519
FID C 4 3608
FID C 6 2794
FID C 3 7699
FID C 8 5767
FID L 13 2125
FID L 14 2124
SNT VIA
FID H 0 520
FID C 4 3606
FID C 6 2792
FID C 3 7697
FID C 8 5765
FID L 13 2123
FID L 14 2122
SNT VIA
FID H 0 521
FID C 4 2762
FID C 6 2064
FID C 3 6528
FID C 8 4773
FID L 13 1417
FID L 14 1416
SNT VIA
FID H 0 522
FID C 4 2414
FID C 6 1727
FID C 3 5895
FID C 8 4265
FID L 13 1160
FID L 14 1159
SNT VIA
FID H 0 523
FID C 4 2753
FID C 6 2056
FID C 3 6518
FID C 8 4763
FID L 13 1412
FID L 14 1411
SNT VIA
FID H 0 524
FID C 4 2597
FID C 6 1920
FID C 3 6214
FID C 8 4542
FID L 13 1315
FID L 14 1314
SNT VIA
FID H 0 525
FID C 4 3425
FID C 6 2675
FID C 3 7404
FID C 8 5624
FID L 13 2070
FID L 14 2069
SNT VIA
FID H 0 526
FID C 4 3435
FID C 6 2682
FID C 3 7421
FID C 8 5631
FID L 13 2077
FID L 14 2076
SNT VIA
FID H 0 527
FID C 4 3357
FID C 6 2609
FID C 3 7315
FID C 8 5538
FID L 13 2027
FID L 14 2026
SNT VIA
FID H 0 528
FID C 4 2865
FID C 6 2143
FID C 3 6670
FID C 8 4865
FID L 13 1483
FID L 14 1482
SNT VIA
FID H 0 529
FID C 4 3429
FID C 6 2679
FID C 3 7414
FID C 8 5628
FID L 13 2074
FID L 14 2073
SNT VIA
FID H 0 530
FID C 4 2624
FID C 6 1937
FID C 3 6258
FID C 8 4564
FID L 13 1331
FID L 14 1330
SNT VIA
FID H 0 531
FID C 4 3433
FID C 6 2681
FID C 3 7419
FID C 8 5630
FID L 13 2076
FID L 14 2075
SNT VIA
FID H 0 532
FID C 4 3426
FID C 6 2676
FID C 3 7405
FID C 8 5625
FID L 13 2071
FID L 14 2070
SNT VIA
FID H 0 533
FID C 4 3131
FID C 6 2381
FID C 3 7069
FID C 8 5290
FID L 13 1809
FID L 14 1808
SNT VIA
FID H 0 534
FID C 4 3453
FID C 6 2704
FID C 3 7440
FID C 8 5653
FID L 13 2092
FID L 14 2091
SNT VIA
FID H 0 535
FID C 4 3403
FID C 6 2654
FID C 3 7373
FID C 8 5596
FID L 13 2055
FID L 14 2054
SNT VIA
FID H 0 536
FID C 4 3130
FID C 6 2380
FID C 3 7068
FID C 8 5289
FID L 13 1808
FID L 14 1807
SNT VIA
FID H 0 537
FID C 4 3428
FID C 6 2678
FID C 3 7411
FID C 8 5627
FID L 13 2073
FID L 14 2072
SNT VIA
FID H 0 538
FID C 4 2709
FID C 6 2000
FID C 3 6441
FID C 8 4676
FID L 13 1382
FID L 14 1381
SNT VIA
FID H 0 539
FID C 4 2698
FID C 6 1995
FID C 3 6413
FID C 8 4670
FID L 13 1377
FID L 14 1376
SNT VIA
FID H 0 540
FID C 4 3427
FID C 6 2677
FID C 3 7406
FID C 8 5626
FID L 13 2072
FID L 14 2071
SNT VIA
FID H 0 541
FID C 4 2866
FID C 6 2144
FID C 3 6671
FID C 8 4866
FID L 13 1484
FID L 14 1483
SNT VIA
FID H 0 542
FID C 4 2623
FID C 6 1936
FID C 3 6257
FID C 8 4563
FID L 13 1330
FID L 14 1329
SNT VIA
FID H 0 543
FID C 4 3370
FID C 6 2626
FID C 3 7330
FID C 8 5560
FID L 13 2036
FID L 14 2035
SNT VIA
FID H 0 544
FID C 4 3369
FID C 6 2625
FID C 3 7329
FID C 8 5559
FID L 13 2035
FID L 14 2034
SNT VIA
FID H 0 545
FID C 4 2840
FID C 6 2117
FID C 3 6638
FID C 8 4833
FID L 13 1462
FID L 14 1461
SNT VIA
FID H 0 546
FID C 4 2671
FID C 6 1976
FID C 3 6362
FID C 8 4649
FID L 13 1362
FID L 14 1361
SNT VIA
FID H 0 547
FID C 4 2677
FID C 6 1979
FID C 3 6373
FID C 8 4652
FID L 13 1365
FID L 14 1364
SNT VIA
FID H 0 548
FID C 4 2646
FID C 6 1956
FID C 3 6285
FID C 8 4597
FID L 13 1343
FID L 14 1342
SNT VIA
FID H 0 549
FID C 4 2751
FID C 6 2054
FID C 3 6515
FID C 8 4759
FID L 13 1411
FID L 14 1410
SNT VIA
FID H 0 550
FID C 4 3135
FID C 6 2385
FID C 3 7075
FID C 8 5296
FID L 13 1811
FID L 14 1810
SNT VIA
FID H 0 551
FID C 4 3134
FID C 6 2384
FID C 3 7074
FID C 8 5295
FID L 13 1810
FID L 14 1809
SNT VIA
FID H 0 552
FID C 4 2402
FID C 6 1715
FID C 3 5867
FID C 8 4245
FID L 13 1151
FID L 14 1150
SNT VIA
FID H 0 553
FID C 4 3371
FID C 6 2630
FID C 3 7331
FID C 8 5564
FID L 13 2037
FID L 14 2036
SNT VIA
FID H 0 554
FID C 4 2666
FID C 6 1971
FID C 3 6349
FID C 8 4630
FID L 13 1358
FID L 14 1357
SNT VIA
FID H 0 555
FID C 4 2838
FID C 6 2114
FID C 3 6636
FID C 8 4830
FID L 13 1460
FID L 14 1459
SNT VIA
FID H 0 556
FID C 4 3648
FID C 6 2825
FID C 3 7757
FID C 8 5805
FID L 13 2151
FID L 14 2150
SNT VIA
FID H 0 557
FID C 4 3646
FID C 6 2824
FID C 3 7755
FID C 8 5804
FID L 13 2150
FID L 14 2149
SNT VIA
FID H 0 558
FID C 4 2832
FID C 6 2111
FID C 3 6628
FID C 8 4827
FID L 13 1457
FID L 14 1456
SNT VIA
FID H 0 559
FID C 4 3615
FID C 6 2799
FID C 3 7709
FID C 8 5772
FID L 13 2130
FID L 14 2129
SNT VIA
FID H 0 560
FID C 4 3415
FID C 6 2668
FID C 3 7393
FID C 8 5615
FID L 13 2065
FID L 14 2064
SNT VIA
FID H 0 561
FID C 4 3399
FID C 6 2651
FID C 3 7369
FID C 8 5592
FID L 13 2053
FID L 14 2052
SNT VIA
FID H 0 562
FID C 4 2745
FID C 6 2052
FID C 3 6508
FID C 8 4755
FID L 13 1409
FID L 14 1408
SNT VIA
FID H 0 563
FID C 4 3450
FID C 6 2702
FID C 3 7437
FID C 8 5651
FID L 13 2091
FID L 14 2090
SNT VIA
FID H 0 564
FID C 4 2819
FID C 6 2104
FID C 3 6613
FID C 8 4820
FID L 13 1450
FID L 14 1449
SNT VIA
FID H 0 565
FID C 4 3398
FID C 6 2650
FID C 3 7368
FID C 8 5590
FID L 13 2052
FID L 14 2051
SNT VIA
FID H 0 566
FID C 4 3617
FID C 6 2801
FID C 3 7711
FID C 8 5774
FID L 13 2132
FID L 14 2131
SNT VIA
FID H 0 567
FID C 4 3619
FID C 6 2802
FID C 3 7714
FID C 8 5775
FID L 13 2133
FID L 14 2132
SNT VIA
FID H 0 568
FID C 4 3396
FID C 6 2649
FID C 3 7366
FID C 8 5589
FID L 13 2051
FID L 14 2050
SNT VIA
FID H 0 569
FID C 4 3410
FID C 6 2660
FID C 3 7381
FID C 8 5603
FID L 13 2060
FID L 14 2059
SNT VIA
FID H 0 570
FID C 4 2645
FID C 6 1955
FID C 3 6282
FID C 8 4596
FID L 13 1342
FID L 14 1341
SNT VIA
FID H 0 571
FID C 4 3405
FID C 6 2656
FID C 3 7375
FID C 8 5598
FID L 13 2057
FID L 14 2056
SNT VIA
FID H 0 572
FID C 4 3404
FID C 6 2655
FID C 3 7374
FID C 8 5597
FID L 13 2056
FID L 14 2055
SNT VIA
FID H 0 573
FID C 4 3401
FID C 6 2652
FID C 3 7371
FID C 8 5593
FID L 13 2054
FID L 14 2053
SNT VIA
FID H 0 574
FID C 4 3364
FID C 6 2623
FID C 3 7324
FID C 8 5557
FID L 13 2033
FID L 14 2032
SNT VIA
FID H 0 575
FID C 4 3365
FID C 6 2624
FID C 3 7325
FID C 8 5558
FID L 13 2034
FID L 14 2033
SNT VIA
FID H 0 576
FID C 4 2406
FID C 6 1719
FID C 3 5872
FID C 8 4249
FID L 13 1155
FID L 14 1154
SNT VIA
FID H 0 577
FID C 4 3448
FID C 6 2701
FID C 3 7435
FID C 8 5650
FID L 13 2090
FID L 14 2089
SNT VIA
FID H 0 578
FID C 4 3350
FID C 6 2598
FID C 3 7307
FID C 8 5521
FID L 13 2021
FID L 14 2020
SNT VIA
FID H 0 579
FID C 4 3442
FID C 6 2695
FID C 3 7429
FID C 8 5644
FID L 13 2084
FID L 14 2083
SNT VIA
FID H 0 580
FID C 4 3441
FID C 6 2694
FID C 3 7428
FID C 8 5643
FID L 13 2083
FID L 14 2082
SNT VIA
FID H 0 581
FID C 4 3663
FID C 6 2839
FID C 3 7775
FID C 8 5821
FID L 13 2163
FID L 14 2162
SNT VIA
FID H 0 582
FID C 4 3664
FID C 6 2840
FID C 3 7776
FID C 8 5822
FID L 13 2164
FID L 14 2163
SNT VIA
FID H 0 583
FID C 4 3661
FID C 6 2837
FID C 3 7773
FID C 8 5819
FID L 13 2161
FID L 14 2160
SNT VIA
FID H 0 584
FID C 4 3662
FID C 6 2838
FID C 3 7774
FID C 8 5820
FID L 13 2162
FID L 14 2161
SNT VIA
FID H 0 585
FID C 4 2830
FID C 6 2110
FID C 3 6626
FID C 8 4826
FID L 13 1456
FID L 14 1455
SNT VIA
FID H 0 586
FID C 4 2827
FID C 6 2108
FID C 3 6623
FID C 8 4824
FID L 13 1454
FID L 14 1453
SNT VIA
FID H 0 587
FID C 4 2821
FID C 6 2105
FID C 3 6616
FID C 8 4821
FID L 13 1451
FID L 14 1450
SNT VIA
FID H 0 588
FID C 4 2836
FID C 6 2113
FID C 3 6634
FID C 8 4829
FID L 13 1459
FID L 14 1458
SNT VIA
FID H 0 589
FID C 4 2644
FID C 6 1951
FID C 3 6281
FID C 8 4588
FID L 13 1341
FID L 14 1340
SNT VIA
FID H 0 590
FID C 4 2789
FID C 6 2083
FID C 3 6565
FID C 8 4792
FID L 13 1435
FID L 14 1434
SNT VIA
FID H 0 591
FID C 4 2791
FID C 6 2085
FID C 3 6567
FID C 8 4794
FID L 13 1437
FID L 14 1436
SNT VIA
FID H 0 592
FID C 4 3668
FID C 6 2844
FID C 3 7780
FID C 8 5827
FID L 13 2167
FID L 14 2166
SNT VIA
FID H 0 593
FID C 4 2769
FID C 6 2071
FID C 3 6536
FID C 8 4780
FID L 13 1423
FID L 14 1422
SNT VIA
FID H 0 594
FID C 4 2768
FID C 6 2070
FID C 3 6535
FID C 8 4779
FID L 13 1422
FID L 14 1421
SNT VIA
FID H 0 595
FID C 4 2765
FID C 6 2067
FID C 3 6532
FID C 8 4776
FID L 13 1419
FID L 14 1418
SNT VIA
FID H 0 596
FID C 4 2790
FID C 6 2084
FID C 3 6566
FID C 8 4793
FID L 13 1436
FID L 14 1435
SNT VIA
FID H 0 597
FID C 4 3443
FID C 6 2696
FID C 3 7430
FID C 8 5645
FID L 13 2085
FID L 14 2084
SNT VIA
FID H 0 598
FID C 4 3660
FID C 6 2835
FID C 3 7772
FID C 8 5817
FID L 13 2160
FID L 14 2159
SNT VIA
FID H 0 599
FID C 4 2792
FID C 6 2086
FID C 3 6568
FID C 8 4795
FID L 13 1438
FID L 14 1437
SNT VIA
FID H 0 600
FID C 4 2772
FID C 6 2074
FID C 3 6539
FID C 8 4783
FID L 13 1426
FID L 14 1425
SNT VIA
FID H 0 601
FID C 4 2770
FID C 6 2072
FID C 3 6537
FID C 8 4781
FID L 13 1424
FID L 14 1423
SNT VIA
FID H 0 602
FID C 4 2599
FID C 6 1922
FID C 3 6218
FID C 8 4546
FID L 13 1316
FID L 14 1315
SNT VIA
FID H 0 603
FID C 4 2766
FID C 6 2068
FID C 3 6533
FID C 8 4777
FID L 13 1420
FID L 14 1419
SNT VIA
FID H 0 604
FID C 4 2704
FID C 6 1998
FID C 3 6431
FID C 8 4674
FID L 13 1380
FID L 14 1379
SNT VIA
FID H 0 605
FID C 4 2859
FID C 6 2136
FID C 3 6659
FID C 8 4858
FID L 13 1477
FID L 14 1476
SNT VIA
FID H 0 606
FID C 4 2872
FID C 6 2150
FID C 3 6677
FID C 8 4872
FID L 13 1488
FID L 14 1487
SNT VIA
FID H 0 607
FID C 4 2860
FID C 6 2137
FID C 3 6660
FID C 8 4859
FID L 13 1478
FID L 14 1477
SNT VIA
FID H 0 608
FID C 4 2861
FID C 6 2138
FID C 3 6661
FID C 8 4860
FID L 13 1479
FID L 14 1478
SNT VIA
FID H 0 609
FID C 4 3407
FID C 6 2658
FID C 3 7377
FID C 8 5600
FID L 13 2059
FID L 14 2058
SNT VIA
FID H 0 610
FID C 4 3406
FID C 6 2657
FID C 3 7376
FID C 8 5599
FID L 13 2058
FID L 14 2057
SNT VIA
FID H 0 611
FID C 4 3445
FID C 6 2698
FID C 3 7432
FID C 8 5647
FID L 13 2087
FID L 14 2086
SNT VIA
FID H 0 612
FID C 4 3389
FID C 6 2644
FID C 3 7357
FID C 8 5582
FID L 13 2047
FID L 14 2046
SNT VIA
FID H 0 613
FID C 4 2773
FID C 6 2075
FID C 3 6540
FID C 8 4784
FID L 13 1427
FID L 14 1426
SNT VIA
FID H 0 614
FID C 4 2771
FID C 6 2073
FID C 3 6538
FID C 8 4782
FID L 13 1425
FID L 14 1424
SNT VIA
FID H 0 615
FID C 4 2869
FID C 6 2145
FID C 3 6674
FID C 8 4867
FID L 13 1485
FID L 14 1484
SNT VIA
FID H 0 616
FID C 4 2796
FID C 6 2087
FID C 3 6573
FID C 8 4796
FID L 13 1439
FID L 14 1438
SNT VIA
FID H 0 617
FID C 4 2767
FID C 6 2069
FID C 3 6534
FID C 8 4778
FID L 13 1421
FID L 14 1420
SNT VIA
FID H 0 618
FID C 4 2829
FID C 6 2109
FID C 3 6625
FID C 8 4825
FID L 13 1455
FID L 14 1454
SNT VIA
FID H 0 619
FID C 4 3447
FID C 6 2700
FID C 3 7434
FID C 8 5649
FID L 13 2089
FID L 14 2088
SNT VIA
FID H 0 620
FID C 4 3665
FID C 6 2841
FID C 3 7777
FID C 8 5823
FID L 13 2165
FID L 14 2164
SNT VIA
FID H 0 621
FID C 4 2870
FID C 6 2146
FID C 3 6675
FID C 8 4868
FID L 13 1486
FID L 14 1485
SNT VIA
FID H 0 622
FID C 4 2739
FID C 6 2038
FID C 3 6495
FID C 8 4726
FID L 13 1404
FID L 14 1403
SNT VIA
FID H 0 623
FID C 4 3446
FID C 6 2699
FID C 3 7433
FID C 8 5648
FID L 13 2088
FID L 14 2087
SNT VIA
FID H 0 624
FID C 4 3391
FID C 6 2645
FID C 3 7360
FID C 8 5583
FID L 13 2048
FID L 14 2047
SNT VIA
FID H 0 625
FID C 4 2873
FID C 6 2151
FID C 3 6678
FID C 8 4873
FID L 13 1489
FID L 14 1488
SNT VIA
FID H 0 626
FID C 4 3658
FID C 6 2834
FID C 3 7770
FID C 8 5816
FID L 13 2159
FID L 14 2158
SNT VIA
FID H 0 627
FID C 4 3656
FID C 6 2833
FID C 3 7768
FID C 8 5815
FID L 13 2158
FID L 14 2157
SNT VIA
FID H 0 628
FID C 4 3691
FID C 6 2849
FID C 3 7807
FID C 8 5835
FID L 13 2171
FID L 14 2170
SNT VIA
FID H 0 629
FID C 4 3419
FID C 6 2673
FID C 3 7398
FID C 8 5622
FID L 13 2068
FID L 14 2067
SNT VIA
FID H 0 630
FID C 4 3395
FID C 6 2647
FID C 3 7364
FID C 8 5586
FID L 13 2050
FID L 14 2049
SNT VIA
FID H 0 631
FID C 4 3352
FID C 6 2600
FID C 3 7309
FID C 8 5523
FID L 13 2023
FID L 14 2022
SNT VIA
FID H 0 632
FID C 4 2785
FID C 6 2080
FID C 3 6558
FID C 8 4789
FID L 13 1432
FID L 14 1431
SNT VIA
FID H 0 633
FID C 4 3418
FID C 6 2672
FID C 3 7397
FID C 8 5621
FID L 13 2067
FID L 14 2066
SNT VIA
FID H 0 634
FID C 4 3420
FID C 6 2674
FID C 3 7399
FID C 8 5623
FID L 13 2069
FID L 14 2068
SNT VIA
FID H 0 635
FID C 4 3351
FID C 6 2599
FID C 3 7308
FID C 8 5522
FID L 13 2022
FID L 14 2021
SNT VIA
FID H 0 636
FID C 4 2786
FID C 6 2081
FID C 3 6561
FID C 8 4790
FID L 13 1433
FID L 14 1432
SNT VIA
FID H 0 637
FID C 4 3693
FID C 6 2852
FID C 3 7809
FID C 8 5841
FID L 13 2173
FID L 14 2172
SNT VIA
FID H 0 638
FID C 4 3694
FID C 6 2853
FID C 3 7810
FID C 8 5842
FID L 13 2174
FID L 14 2173
SNT VIA
FID H 0 639
FID C 4 3695
FID C 6 2854
FID C 3 7811
FID C 8 5843
FID L 13 2175
FID L 14 2174
SNT VIA
FID H 0 640
FID C 4 2825
FID C 6 2107
FID C 3 6620
FID C 8 4823
FID L 13 1453
FID L 14 1452
SNT VIA
FID H 0 641
FID C 4 2853
FID C 6 2130
FID C 3 6653
FID C 8 4852
FID L 13 1471
FID L 14 1470
SNT VIA
FID H 0 642
FID C 4 2778
FID C 6 2077
FID C 3 6547
FID C 8 4786
FID L 13 1429
FID L 14 1428
SNT VIA
FID H 0 643
FID C 4 2871
FID C 6 2149
FID C 3 6676
FID C 8 4871
FID L 13 1487
FID L 14 1486
SNT VIA
FID H 0 644
FID C 4 2403
FID C 6 1716
FID C 3 5868
FID C 8 4246
FID L 13 1152
FID L 14 1151
SNT VIA
FID H 0 645
FID C 4 2776
FID C 6 2076
FID C 3 6544
FID C 8 4785
FID L 13 1428
FID L 14 1427
SNT VIA
FID H 0 646
FID C 4 2738
FID C 6 2037
FID C 3 6494
FID C 8 4725
FID L 13 1403
FID L 14 1402
SNT VIA
FID H 0 647
FID C 4 2782
FID C 6 2078
FID C 3 6555
FID C 8 4787
FID L 13 1430
FID L 14 1429
SNT VIA
FID H 0 648
FID C 4 2783
FID C 6 2079
FID C 3 6556
FID C 8 4788
FID L 13 1431
FID L 14 1430
SNT VIA
FID H 0 649
FID C 4 2592
FID C 6 1913
FID C 3 6198
FID C 8 4535
FID L 13 1312
FID L 14 1311
SNT VIA
FID H 0 650
FID C 4 3362
FID C 6 2620
FID C 3 7322
FID C 8 5554
FID L 13 2032
FID L 14 2031
SNT VIA
FID H 0 651
FID C 4 3388
FID C 6 2642
FID C 3 7356
FID C 8 5579
FID L 13 2046
FID L 14 2045
SNT VIA
FID H 0 652
FID C 4 3386
FID C 6 2641
FID C 3 7354
FID C 8 5578
FID L 13 2045
FID L 14 2044
SNT VIA
FID H 0 653
FID C 4 3667
FID C 6 2842
FID C 3 7779
FID C 8 5824
FID L 13 2166
FID L 14 2165
SNT VIA
FID H 0 654
FID C 4 3655
FID C 6 2831
FID C 3 7767
FID C 8 5811
FID L 13 2157
FID L 14 2156
SNT VIA
FID H 0 655
FID C 4 3361
FID C 6 2619
FID C 3 7319
FID C 8 5553
FID L 13 2031
FID L 14 2030
SNT VIA
FID H 0 656
FID C 4 3384
FID C 6 2640
FID C 3 7350
FID C 8 5577
FID L 13 2044
FID L 14 2043
SNT VIA
FID H 0 657
FID C 4 3696
FID C 6 2855
FID C 3 7812
FID C 8 5844
FID L 13 2176
FID L 14 2175
SNT VIA
FID H 0 658
FID C 4 2701
FID C 6 1996
FID C 3 6423
FID C 8 4672
FID L 13 1378
FID L 14 1377
SNT VIA
FID H 0 659
FID C 4 2590
FID C 6 1910
FID C 3 6196
FID C 8 4527
FID L 13 1311
FID L 14 1310
SNT VIA
FID H 0 660
FID C 4 2702
FID C 6 1997
FID C 3 6425
FID C 8 4673
FID L 13 1379
FID L 14 1378
SNT VIA
FID H 0 661
FID C 4 3379
FID C 6 2633
FID C 3 7343
FID C 8 5567
FID L 13 2040
FID L 14 2039
SNT VIA
FID H 0 662
FID C 4 2834
FID C 6 2112
FID C 3 6632
FID C 8 4828
FID L 13 1458
FID L 14 1457
SNT VIA
FID H 0 663
FID C 4 2858
FID C 6 2135
FID C 3 6658
FID C 8 4857
FID L 13 1476
FID L 14 1475
SNT VIA
FID H 0 664
FID C 4 3381
FID C 6 2634
FID C 3 7345
FID C 8 5568
FID L 13 2041
FID L 14 2040
SNT VIA
FID H 0 665
FID C 4 2740
FID C 6 2039
FID C 3 6496
FID C 8 4727
FID L 13 1405
FID L 14 1404
SNT VIA
FID H 0 666
FID C 4 2588
FID C 6 1909
FID C 3 6183
FID C 8 4524
FID L 13 1310
FID L 14 1309
SNT VIA
FID H 0 667
FID C 4 2707
FID C 6 1999
FID C 3 6438
FID C 8 4675
FID L 13 1381
FID L 14 1380
SNT VIA
FID H 0 668
FID C 4 3394
FID C 6 2646
FID C 3 7363
FID C 8 5584
FID L 13 2049
FID L 14 2048
SNT VIA
FID H 0 669
FID C 4 2714
FID C 6 2004
FID C 3 6448
FID C 8 4680
FID L 13 1385
FID L 14 1384
SNT VIA
FID H 0 670
FID C 4 2691
FID C 6 1991
FID C 3 6404
FID C 8 4666
FID L 13 1373
FID L 14 1372
SNT VIA
FID H 0 671
FID C 4 3698
FID C 6 2856
FID C 3 7814
FID C 8 5845
FID L 13 2177
FID L 14 2176
SNT VIA
FID H 0 672
FID C 4 2749
FID C 6 2053
FID C 3 6512
FID C 8 4758
FID L 13 1410
FID L 14 1409
SNT VIA
FID H 0 673
FID C 4 2988
FID C 6 2245
FID C 3 6904
FID C 8 5144
FID L 13 1678
FID L 14 1677
SNT VIA
FID H 0 674
FID C 4 2816
FID C 6 2101
FID C 3 6610
FID C 8 4817
FID L 13 1448
FID L 14 1447
SNT VIA
FID H 0 675
FID C 4 2814
FID C 6 2096
FID C 3 6608
FID C 8 4808
FID L 13 1446
FID L 14 1445
SNT VIA
FID H 0 676
FID C 4 2823
FID C 6 2106
FID C 3 6618
FID C 8 4822
FID L 13 1452
FID L 14 1451
SNT VIA
FID H 0 677
FID C 4 2839
FID C 6 2115
FID C 3 6637
FID C 8 4831
FID L 13 1461
FID L 14 1460
SNT VIA
FID H 0 678
FID C 4 2818
FID C 6 2103
FID C 3 6612
FID C 8 4819
FID L 13 1449
FID L 14 1448
SNT VIA
FID H 0 679
FID C 4 2995
FID C 6 2250
FID C 3 6917
FID C 8 5149
FID L 13 1683
FID L 14 1682
SNT VIA
FID H 0 680
FID C 4 2993
FID C 6 2249
FID C 3 6914
FID C 8 5148
FID L 13 1682
FID L 14 1681
SNT VIA
FID H 0 681
FID C 4 2689
FID C 6 1990
FID C 3 6401
FID C 8 4665
FID L 13 1372
FID L 14 1371
SNT VIA
FID H 0 682
FID C 4 2997
FID C 6 2251
FID C 3 6920
FID C 8 5150
FID L 13 1684
FID L 14 1683
SNT VIA
FID H 0 683
FID C 4 2992
FID C 6 2248
FID C 3 6909
FID C 8 5147
FID L 13 1681
FID L 14 1680
SNT VIA
FID H 0 684
FID C 4 2670
FID C 6 1975
FID C 3 6361
FID C 8 4648
FID L 13 1361
FID L 14 1360
SNT VIA
FID H 0 685
FID C 4 2815
FID C 6 2098
FID C 3 6609
FID C 8 4813
FID L 13 1447
FID L 14 1446
SNT VIA
FID H 0 686
FID C 4 2976
FID C 6 2235
FID C 3 6890
FID C 8 5134
FID L 13 1668
FID L 14 1667
SNT VIA
FID H 0 687
FID C 4 2667
FID C 6 1973
FID C 3 6352
FID C 8 4639
FID L 13 1359
FID L 14 1358
SNT VIA
FID H 0 688
FID C 4 3017
FID C 6 2269
FID C 3 6941
FID C 8 5169
FID L 13 1702
FID L 14 1701
SNT VIA
FID H 0 689
FID C 4 2964
FID C 6 2224
FID C 3 6878
FID C 8 5123
FID L 13 1657
FID L 14 1656
SNT VIA
FID H 0 690
FID C 4 3016
FID C 6 2268
FID C 3 6940
FID C 8 5168
FID L 13 1701
FID L 14 1700
SNT VIA
FID H 0 691
FID C 4 3010
FID C 6 2263
FID C 3 6934
FID C 8 5162
FID L 13 1696
FID L 14 1695
SNT VIA
FID H 0 692
FID C 4 2665
FID C 6 1970
FID C 3 6348
FID C 8 4629
FID L 13 1357
FID L 14 1356
SNT VIA
FID H 0 693
FID C 4 2682
FID C 6 1982
FID C 3 6394
FID C 8 4655
FID L 13 1368
FID L 14 1367
SNT VIA
FID H 0 694
FID C 4 3012
FID C 6 2265
FID C 3 6936
FID C 8 5165
FID L 13 1698
FID L 14 1697
SNT VIA
FID H 0 695
FID C 4 2812
FID C 6 2095
FID C 3 6606
FID C 8 4807
FID L 13 1445
FID L 14 1444
SNT VIA
FID H 0 1070
FID C 4 2603
FID C 6 1923
FID C 3 6226
FID C 8 4550
FID L 13 1317
FID L 14 1316
SNT VIA
FID H 0 1071
FID C 4 2615
FID C 6 1929
FID C 3 6248
FID C 8 4556
FID L 13 1323
FID L 14 1322
SNT VIA
FID H 0 1072
FID C 4 2620
FID C 6 1934
FID C 3 6253
FID C 8 4561
FID L 13 1328
FID L 14 1327
SNT VIA
FID H 0 1073
FID C 4 2616
FID C 6 1930
FID C 3 6249
FID C 8 4557
FID L 13 1324
FID L 14 1323
SNT VIA
FID H 0 1074
FID C 4 2619
FID C 6 1933
FID C 3 6252
FID C 8 4560
FID L 13 1327
FID L 14 1326
SNT VIA
FID H 0 1075
FID C 4 2617
FID C 6 1931
FID C 3 6250
FID C 8 4558
FID L 13 1325
FID L 14 1324
SNT VIA
FID H 0 1076
FID C 4 2618
FID C 6 1932
FID C 3 6251
FID C 8 4559
FID L 13 1326
FID L 14 1325
SNT VIA
FID H 0 1077
FID C 4 2621
FID C 6 1935
FID C 3 6254
FID C 8 4562
FID L 13 1329
FID L 14 1328
SNT VIA
FID H 0 1078
FID C 4 2614
FID C 6 1928
FID C 3 6247
FID C 8 4555
FID L 13 1322
FID L 14 1321
SNT VIA
FID H 0 1079
FID C 4 2607
FID C 6 1926
FID C 3 6231
FID C 8 4553
FID L 13 1320
FID L 14 1319
SNT VIA
FID H 0 1080
FID C 4 2606
FID C 6 1925
FID C 3 6230
FID C 8 4552
FID L 13 1319
FID L 14 1318
SNT VIA
FID H 0 1081
FID C 4 2560
FID C 6 1882
FID C 3 6151
FID C 8 4497
FID L 11 1384
FID L 12 1384
FID L 13 1283
FID L 14 1282
FID L 15 1384
FID L 16 1384
SNT VIA
FID H 0 1082
FID C 4 2561
FID C 6 1883
FID C 3 6152
FID C 8 4498
FID L 11 1385
FID L 12 1385
FID L 13 1284
FID L 14 1283
FID L 15 1385
FID L 16 1385
SNT VIA
FID H 0 1225
FID C 4 3077
FID C 6 2326
FID C 3 7013
FID C 8 5229
FID L 13 1757
FID L 14 1756
SNT VIA
FID H 0 1226
FID C 4 3064
FID C 6 2313
FID C 3 7000
FID C 8 5216
FID L 13 1744
FID L 14 1743
SNT VIA
FID H 0 1227
FID C 4 3067
FID C 6 2316
FID C 3 7003
FID C 8 5219
FID L 13 1747
FID L 14 1746
SNT VIA
FID H 0 1228
FID C 4 3100
FID C 6 2348
FID C 3 7036
FID C 8 5251
FID L 13 1779
FID L 14 1778
SNT VIA
FID H 0 1229
FID C 4 3469
FID C 6 2717
FID C 3 7457
FID C 8 5668
FID L 13 2103
FID L 14 2102
SNT VIA
FID H 0 1230
FID C 4 3603
FID C 6 2789
FID C 3 7694
FID C 8 5762
FID L 13 2120
FID L 14 2119
SNT VIA
FID H 0 1231
FID C 4 3614
FID C 6 2798
FID C 3 7708
FID C 8 5771
FID L 13 2129
FID L 14 2128
SNT VIA
FID H 0 1232
FID C 4 3456
FID C 6 2708
FID C 3 7443
FID C 8 5659
FID L 13 2094
FID L 14 2093
SNT VIA
FID H 0 1233
FID C 4 3430
FID C 6 2680
FID C 3 7415
FID C 8 5629
FID L 13 2075
FID L 14 2074
SNT VIA
FID H 0 1234
FID C 4 3616
FID C 6 2800
FID C 3 7710
FID C 8 5773
FID L 13 2131
FID L 14 2130
SNT VIA
FID H 0 1235
FID C 4 3444
FID C 6 2697
FID C 3 7431
FID C 8 5646
FID L 13 2086
FID L 14 2085
SNT VIA
FID H 0 1236
FID C 4 2788
FID C 6 2082
FID C 3 6564
FID C 8 4791
FID L 13 1434
FID L 14 1433
SNT VIA
FID H 0 1237
FID C 4 2764
FID C 6 2065
FID C 3 6531
FID C 8 4774
FID L 13 1418
FID L 14 1417
SNT VIA
FID H 0 1238
FID C 4 2684
FID C 6 1983
FID C 3 6396
FID C 8 4656
FID L 13 1369
FID L 14 1368
SNT VIA
FID H 0 1239
FID C 4 2587
FID C 6 1908
FID C 3 6180
FID C 8 4523
FID L 13 1309
FID L 14 1308
SNT VIA
FID H 0 1240
FID C 4 3013
FID C 6 2266
FID C 3 6937
FID C 8 5166
FID L 13 1699
FID L 14 1698
SNT VIA
FID H 0 1435
FID C 4 3004
FID C 6 2257
FID C 3 6928
FID C 8 5156
FID L 13 1690
FID L 14 1689
SNT VIA
FID H 0 1436
FID C 4 2999
FID C 6 2252
FID C 3 6923
FID C 8 5151
FID L 13 1685
FID L 14 1684
SNT VIA
FID H 0 1437
FID C 4 2549
FID C 6 1871
FID C 3 6114
FID C 8 4474
FID L 13 1272
FID L 14 1271
SNT VIA
FID H 0 1438
FID C 4 3054
FID C 6 2303
FID C 3 6990
FID C 8 5205
FID L 13 1735
FID L 14 1734
SNT VIA
FID H 0 1439
FID C 4 3000
FID C 6 2253
FID C 3 6924
FID C 8 5152
FID L 13 1686
FID L 14 1685
SNT VIA
FID H 0 1440
FID C 4 3053
FID C 6 2302
FID C 3 6989
FID C 8 5204
FID L 13 1734
FID L 14 1733
SNT VIA
FID H 0 1441
FID C 4 3001
FID C 6 2254
FID C 3 6925
FID C 8 5153
FID L 13 1687
FID L 14 1686
SNT VIA
FID H 0 1442
FID C 4 3052
FID C 6 2301
FID C 3 6988
FID C 8 5203
FID L 13 1733
FID L 14 1732
SNT VIA
FID H 0 1443
FID C 4 3002
FID C 6 2255
FID C 3 6926
FID C 8 5154
FID L 13 1688
FID L 14 1687
SNT VIA
FID H 0 1444
FID C 4 2550
FID C 6 1872
FID C 3 6115
FID C 8 4475
FID L 13 1273
FID L 14 1272
SNT VIA
FID H 0 1445
FID C 4 3051
FID C 6 2300
FID C 3 6987
FID C 8 5202
FID L 13 1732
FID L 14 1731
SNT VIA
FID H 0 1446
FID C 4 3003
FID C 6 2256
FID C 3 6927
FID C 8 5155
FID L 13 1689
FID L 14 1688
SNT VIA
FID H 0 1447
FID C 4 3035
FID C 6 2284
FID C 3 6971
FID C 8 5186
FID L 13 1716
FID L 14 1715
SNT VIA
FID H 0 1448
FID C 4 3040
FID C 6 2289
FID C 3 6976
FID C 8 5191
FID L 13 1721
FID L 14 1720
SNT VIA
FID H 0 1449
FID C 4 2963
FID C 6 2223
FID C 3 6877
FID C 8 5122
FID L 13 1656
FID L 14 1655
SNT VIA
FID H 0 1450
FID C 4 3034
FID C 6 2283
FID C 3 6970
FID C 8 5185
FID L 13 1715
FID L 14 1714
SNT VIA
FID H 0 1451
FID C 4 3041
FID C 6 2290
FID C 3 6977
FID C 8 5192
FID L 13 1722
FID L 14 1721
SNT VIA
FID H 0 1452
FID C 4 2892
FID C 6 2152
FID C 3 6806
FID C 8 5051
FID L 13 1585
FID L 14 1584
SNT VIA
FID H 0 1453
FID C 4 3033
FID C 6 2282
FID C 3 6969
FID C 8 5184
FID L 13 1714
FID L 14 1713
SNT VIA
FID H 0 1454
FID C 4 3042
FID C 6 2291
FID C 3 6978
FID C 8 5193
FID L 13 1723
FID L 14 1722
SNT VIA
FID H 0 1455
FID C 4 3032
FID C 6 2281
FID C 3 6968
FID C 8 5183
FID L 13 1713
FID L 14 1712
SNT VIA
FID H 0 1456
FID C 4 3043
FID C 6 2292
FID C 3 6979
FID C 8 5194
FID L 13 1724
FID L 14 1723
SNT VIA
FID H 0 1457
FID C 4 3044
FID C 6 2293
FID C 3 6980
FID C 8 5195
FID L 13 1725
FID L 14 1724
SNT VIA
FID H 0 1458
FID C 4 3050
FID C 6 2299
FID C 3 6986
FID C 8 5201
FID L 13 1731
FID L 14 1730
SNT VIA
FID H 0 1459
FID C 4 3049
FID C 6 2298
FID C 3 6985
FID C 8 5200
FID L 13 1730
FID L 14 1729
SNT VIA
FID H 0 1460
FID C 4 3048
FID C 6 2297
FID C 3 6984
FID C 8 5199
FID L 13 1729
FID L 14 1728
SNT VIA
FID H 0 1461
FID C 4 3047
FID C 6 2296
FID C 3 6983
FID C 8 5198
FID L 13 1728
FID L 14 1727
SNT VIA
FID H 0 1462
FID C 4 3046
FID C 6 2295
FID C 3 6982
FID C 8 5197
FID L 13 1727
FID L 14 1726
SNT VIA
FID H 0 1463
FID C 4 3045
FID C 6 2294
FID C 3 6981
FID C 8 5196
FID L 13 1726
FID L 14 1725
SNT VIA
FID H 0 1464
FID C 4 3031
FID C 6 2280
FID C 3 6967
FID C 8 5182
FID L 13 1712
FID L 14 1711
SNT VIA
FID H 0 1465
FID C 4 3026
FID C 6 2275
FID C 3 6962
FID C 8 5177
FID L 13 1707
FID L 14 1706
SNT VIA
FID H 0 1466
FID C 4 3037
FID C 6 2286
FID C 3 6973
FID C 8 5188
FID L 13 1718
FID L 14 1717
SNT VIA
FID H 0 1467
FID C 4 3090
FID C 6 2338
FID C 3 7026
FID C 8 5241
FID L 13 1769
FID L 14 1768
SNT VIA
FID H 0 1468
FID C 4 3027
FID C 6 2276
FID C 3 6963
FID C 8 5178
FID L 13 1708
FID L 14 1707
SNT VIA
FID H 0 1469
FID C 4 3038
FID C 6 2287
FID C 3 6974
FID C 8 5189
FID L 13 1719
FID L 14 1718
SNT VIA
FID H 0 1470
FID C 4 3089
FID C 6 2337
FID C 3 7025
FID C 8 5240
FID L 13 1768
FID L 14 1767
SNT VIA
FID H 0 1471
FID C 4 3028
FID C 6 2277
FID C 3 6964
FID C 8 5179
FID L 13 1709
FID L 14 1708
SNT VIA
FID H 0 1472
FID C 4 3088
FID C 6 2336
FID C 3 7024
FID C 8 5239
FID L 13 1767
FID L 14 1766
SNT VIA
FID H 0 1473
FID C 4 3029
FID C 6 2278
FID C 3 6965
FID C 8 5180
FID L 13 1710
FID L 14 1709
SNT VIA
FID H 0 1474
FID C 4 3039
FID C 6 2288
FID C 3 6975
FID C 8 5190
FID L 13 1720
FID L 14 1719
SNT VIA
FID H 0 1475
FID C 4 3087
FID C 6 2335
FID C 3 7023
FID C 8 5238
FID L 13 1766
FID L 14 1765
SNT VIA
FID H 0 1476
FID C 4 3030
FID C 6 2279
FID C 3 6966
FID C 8 5181
FID L 13 1711
FID L 14 1710
SNT VIA
FID H 0 1477
FID C 4 3075
FID C 6 2324
FID C 3 7011
FID C 8 5227
FID L 13 1755
FID L 14 1754
SNT VIA
FID H 0 1478
FID C 4 3085
FID C 6 2333
FID C 3 7021
FID C 8 5236
FID L 13 1764
FID L 14 1763
SNT VIA
FID H 0 1479
FID C 4 3086
FID C 6 2334
FID C 3 7022
FID C 8 5237
FID L 13 1765
FID L 14 1764
SNT VIA
FID H 0 1480
FID C 4 3081
FID C 6 2329
FID C 3 7017
FID C 8 5232
FID L 13 1760
FID L 14 1759
SNT VIA
FID H 0 1481
FID C 4 3082
FID C 6 2330
FID C 3 7018
FID C 8 5233
FID L 13 1761
FID L 14 1760
SNT VIA
FID H 0 1482
FID C 4 3083
FID C 6 2331
FID C 3 7019
FID C 8 5234
FID L 13 1762
FID L 14 1761
SNT VIA
FID H 0 1483
FID C 4 3084
FID C 6 2332
FID C 3 7020
FID C 8 5235
FID L 13 1763
FID L 14 1762
SNT VIA
FID H 0 1484
FID C 4 3079
FID C 6 2327
FID C 3 7015
FID C 8 5230
FID L 13 1758
FID L 14 1757
SNT VIA
FID H 0 1485
FID C 4 3074
FID C 6 2323
FID C 3 7010
FID C 8 5226
FID L 13 1754
FID L 14 1753
SNT VIA
FID H 0 1486
FID C 4 3080
FID C 6 2328
FID C 3 7016
FID C 8 5231
FID L 13 1759
FID L 14 1758
SNT VIA
FID H 0 1487
FID C 4 2436
FID C 6 1748
FID C 3 5924
FID C 8 4290
FID L 13 1178
FID L 14 1177
SNT VIA
FID H 0 1488
FID C 4 2962
FID C 6 2222
FID C 3 6876
FID C 8 5121
FID L 13 1655
FID L 14 1654
SNT VIA
FID H 0 1489
FID C 4 3073
FID C 6 2322
FID C 3 7009
FID C 8 5225
FID L 13 1753
FID L 14 1752
SNT VIA
FID H 0 1490
FID C 4 3076
FID C 6 2325
FID C 3 7012
FID C 8 5228
FID L 13 1756
FID L 14 1755
SNT VIA
FID H 0 1491
FID C 4 2893
FID C 6 2153
FID C 3 6807
FID C 8 5052
FID L 13 1586
FID L 14 1585
SNT VIA
FID H 0 1492
FID C 4 3072
FID C 6 2321
FID C 3 7008
FID C 8 5224
FID L 13 1752
FID L 14 1751
SNT VIA
FID H 0 1493
FID C 4 3071
FID C 6 2320
FID C 3 7007
FID C 8 5223
FID L 13 1751
FID L 14 1750
SNT VIA
FID H 0 1494
FID C 4 3062
FID C 6 2311
FID C 3 6998
FID C 8 5214
FID L 13 1742
FID L 14 1741
SNT VIA
FID H 0 1495
FID C 4 2434
FID C 6 1746
FID C 3 5922
FID C 8 4288
FID L 13 1176
FID L 14 1175
SNT VIA
FID H 0 1496
FID C 4 2435
FID C 6 1747
FID C 3 5923
FID C 8 4289
FID L 13 1177
FID L 14 1176
SNT VIA
FID H 0 1497
FID C 4 3061
FID C 6 2310
FID C 3 6997
FID C 8 5213
FID L 13 1741
FID L 14 1740
SNT VIA
FID H 0 1498
FID C 4 3060
FID C 6 2309
FID C 3 6996
FID C 8 5212
FID L 13 1740
FID L 14 1739
SNT VIA
FID H 0 1499
FID C 4 3059
FID C 6 2308
FID C 3 6995
FID C 8 5211
FID L 13 1739
FID L 14 1738
SNT VIA
FID H 0 1500
FID C 4 2432
FID C 6 1744
FID C 3 5919
FID C 8 4285
FID L 13 1175
FID L 14 1174
SNT VIA
FID H 0 1501
FID C 4 3056
FID C 6 2305
FID C 3 6992
FID C 8 5207
FID L 13 1737
FID L 14 1736
SNT VIA
FID H 0 1502
FID C 4 3055
FID C 6 2304
FID C 3 6991
FID C 8 5206
FID L 13 1736
FID L 14 1735
SNT VIA
FID H 0 1503
FID C 4 3115
FID C 6 2365
FID C 3 7051
FID C 8 5270
FID L 13 1793
FID L 14 1792
SNT VIA
FID H 0 1504
FID C 4 2430
FID C 6 1743
FID C 3 5915
FID C 8 4284
FID L 13 1174
FID L 14 1173
SNT VIA
FID H 0 1505
FID C 4 2961
FID C 6 2221
FID C 3 6875
FID C 8 5120
FID L 13 1654
FID L 14 1653
SNT VIA
FID H 0 1506
FID C 4 3114
FID C 6 2364
FID C 3 7050
FID C 8 5269
FID L 13 1792
FID L 14 1791
SNT VIA
FID H 0 1507
FID C 4 2894
FID C 6 2154
FID C 3 6808
FID C 8 5053
FID L 13 1587
FID L 14 1586
SNT VIA
FID H 0 1508
FID C 4 3112
FID C 6 2359
FID C 3 7048
FID C 8 5262
FID L 13 1790
FID L 14 1789
SNT VIA
FID H 0 1509
FID C 4 3113
FID C 6 2363
FID C 3 7049
FID C 8 5268
FID L 13 1791
FID L 14 1790
SNT VIA
FID H 0 1510
FID C 4 3070
FID C 6 2319
FID C 3 7006
FID C 8 5222
FID L 13 1750
FID L 14 1749
SNT VIA
FID H 0 1511
FID C 4 3104
FID C 6 2352
FID C 3 7040
FID C 8 5255
FID L 13 1783
FID L 14 1782
SNT VIA
FID H 0 1512
FID C 4 3103
FID C 6 2351
FID C 3 7039
FID C 8 5254
FID L 13 1782
FID L 14 1781
SNT VIA
FID H 0 1513
FID C 4 3111
FID C 6 2358
FID C 3 7047
FID C 8 5261
FID L 13 1789
FID L 14 1788
SNT VIA
FID H 0 1514
FID C 4 3102
FID C 6 2350
FID C 3 7038
FID C 8 5253
FID L 13 1781
FID L 14 1780
SNT VIA
FID H 0 1515
FID C 4 3109
FID C 6 2357
FID C 3 7045
FID C 8 5260
FID L 13 1788
FID L 14 1787
SNT VIA
FID H 0 1516
FID C 4 3101
FID C 6 2349
FID C 3 7037
FID C 8 5252
FID L 13 1780
FID L 14 1779
SNT VIA
FID H 0 1517
FID C 4 3098
FID C 6 2346
FID C 3 7034
FID C 8 5249
FID L 13 1777
FID L 14 1776
SNT VIA
FID H 0 1518
FID C 4 3097
FID C 6 2345
FID C 3 7033
FID C 8 5248
FID L 13 1776
FID L 14 1775
SNT VIA
FID H 0 1519
FID C 4 2471
FID C 6 1782
FID C 3 5976
FID C 8 4339
FID L 13 1204
FID L 14 1203
SNT VIA
FID H 0 1520
FID C 4 3096
FID C 6 2344
FID C 3 7032
FID C 8 5247
FID L 13 1775
FID L 14 1774
SNT VIA
FID H 0 1521
FID C 4 3095
FID C 6 2343
FID C 3 7031
FID C 8 5246
FID L 13 1774
FID L 14 1773
SNT VIA
FID H 0 1522
FID C 4 2469
FID C 6 1780
FID C 3 5974
FID C 8 4337
FID L 13 1202
FID L 14 1201
SNT VIA
FID H 0 1523
FID C 4 2470
FID C 6 1781
FID C 3 5975
FID C 8 4338
FID L 13 1203
FID L 14 1202
SNT VIA
FID H 0 1524
FID C 4 2468
FID C 6 1779
FID C 3 5973
FID C 8 4336
FID L 13 1201
FID L 14 1200
SNT VIA
FID H 0 1525
FID C 4 2960
FID C 6 2220
FID C 3 6874
FID C 8 5119
FID L 13 1653
FID L 14 1652
SNT VIA
FID H 0 1526
FID C 4 3094
FID C 6 2342
FID C 3 7030
FID C 8 5245
FID L 13 1773
FID L 14 1772
SNT VIA
FID H 0 1527
FID C 4 2464
FID C 6 1776
FID C 3 5966
FID C 8 4332
FID L 13 1199
FID L 14 1198
SNT VIA
FID H 0 1528
FID C 4 2895
FID C 6 2155
FID C 3 6809
FID C 8 5054
FID L 13 1588
FID L 14 1587
SNT VIA
FID H 0 1529
FID C 4 3093
FID C 6 2341
FID C 3 7029
FID C 8 5244
FID L 13 1772
FID L 14 1771
SNT VIA
FID H 0 1530
FID C 4 3092
FID C 6 2340
FID C 3 7028
FID C 8 5243
FID L 13 1771
FID L 14 1770
SNT VIA
FID H 0 1531
FID C 4 2461
FID C 6 1773
FID C 3 5962
FID C 8 4327
FID L 13 1197
FID L 14 1196
SNT VIA
FID H 0 1532
FID C 4 2466
FID C 6 1777
FID C 3 5970
FID C 8 4333
FID L 13 1200
FID L 14 1199
SNT VIA
FID H 0 1533
FID C 4 3091
FID C 6 2339
FID C 3 7027
FID C 8 5242
FID L 13 1770
FID L 14 1769
SNT VIA
FID H 0 1534
FID C 4 2938
FID C 6 2198
FID C 3 6852
FID C 8 5097
FID L 13 1631
FID L 14 1630
SNT VIA
FID H 0 1535
FID C 4 2450
FID C 6 1763
FID C 3 5944
FID C 8 4313
FID L 13 1189
FID L 14 1188
SNT VIA
FID H 0 1536
FID C 4 2459
FID C 6 1770
FID C 3 5960
FID C 8 4322
FID L 13 1195
FID L 14 1194
SNT VIA
FID H 0 1537
FID C 4 2460
FID C 6 1772
FID C 3 5961
FID C 8 4326
FID L 13 1196
FID L 14 1195
SNT VIA
FID H 0 1538
FID C 4 2455
FID C 6 1767
FID C 3 5952
FID C 8 4317
FID L 13 1193
FID L 14 1192
SNT VIA
FID H 0 1539
FID C 4 2937
FID C 6 2197
FID C 3 6851
FID C 8 5096
FID L 13 1630
FID L 14 1629
SNT VIA
FID H 0 1540
FID C 4 2936
FID C 6 2196
FID C 3 6850
FID C 8 5095
FID L 13 1629
FID L 14 1628
SNT VIA
FID H 0 1541
FID C 4 2457
FID C 6 1768
FID C 3 5956
FID C 8 4318
FID L 13 1194
FID L 14 1193
SNT VIA
FID H 0 1542
FID C 4 2935
FID C 6 2195
FID C 3 6849
FID C 8 5094
FID L 13 1628
FID L 14 1627
SNT VIA
FID H 0 1543
FID C 4 2452
FID C 6 1765
FID C 3 5946
FID C 8 4315
FID L 13 1191
FID L 14 1190
SNT VIA
FID H 0 1544
FID C 4 2934
FID C 6 2194
FID C 3 6848
FID C 8 5093
FID L 13 1627
FID L 14 1626
SNT VIA
FID H 0 1545
FID C 4 2649
FID C 6 1958
FID C 3 6290
FID C 8 4599
FID L 13 1345
FID L 14 1344
SNT VIA
FID H 0 1546
FID C 4 2451
FID C 6 1764
FID C 3 5945
FID C 8 4314
FID L 13 1190
FID L 14 1189
SNT VIA
FID H 0 1547
FID C 4 2448
FID C 6 1760
FID C 3 5942
FID C 8 4308
FID L 13 1187
FID L 14 1186
SNT VIA
FID H 0 1548
FID C 4 2449
FID C 6 1762
FID C 3 5943
FID C 8 4312
FID L 13 1188
FID L 14 1187
SNT VIA
FID H 0 1549
FID C 4 2506
FID C 6 1817
FID C 3 6016
FID C 8 4378
FID L 13 1237
FID L 14 1236
SNT VIA
FID H 0 1550
FID C 4 3224
FID C 6 2471
FID C 3 7181
FID C 8 5393
FID L 13 1895
FID L 14 1894
SNT VIA
FID H 0 1551
FID C 4 2959
FID C 6 2219
FID C 3 6873
FID C 8 5118
FID L 13 1652
FID L 14 1651
SNT VIA
FID H 0 1552
FID C 4 3225
FID C 6 2472
FID C 3 7182
FID C 8 5394
FID L 13 1896
FID L 14 1895
SNT VIA
FID H 0 1553
FID C 4 2422
FID C 6 1735
FID C 3 5905
FID C 8 4273
FID L 13 1168
FID L 14 1167
SNT VIA
FID H 0 1554
FID C 4 2421
FID C 6 1734
FID C 3 5904
FID C 8 4272
FID L 13 1167
FID L 14 1166
SNT VIA
FID H 0 1555
FID C 4 3570
FID C 6 2773
FID C 3 7656
FID C 8 5745
FID L 13 2107
FID L 14 2106
SNT VIA
FID H 0 1556
FID C 4 2648
FID C 6 1957
FID C 3 6289
FID C 8 4598
FID L 13 1344
FID L 14 1343
SNT VIA
FID H 0 1557
FID C 4 2954
FID C 6 2214
FID C 3 6868
FID C 8 5113
FID L 13 1647
FID L 14 1646
SNT VIA
FID H 0 1558
FID C 4 2444
FID C 6 1758
FID C 3 5934
FID C 8 4306
FID L 13 1185
FID L 14 1184
SNT VIA
FID H 0 1559
FID C 4 2504
FID C 6 1815
FID C 3 6014
FID C 8 4376
FID L 13 1235
FID L 14 1234
SNT VIA
FID H 0 1560
FID C 4 3226
FID C 6 2473
FID C 3 7183
FID C 8 5395
FID L 13 1897
FID L 14 1896
SNT VIA
FID H 0 1561
FID C 4 3227
FID C 6 2474
FID C 3 7184
FID C 8 5396
FID L 13 1898
FID L 14 1897
SNT VIA
FID H 0 1562
FID C 4 2442
FID C 6 1756
FID C 3 5930
FID C 8 4302
FID L 13 1184
FID L 14 1183
SNT VIA
FID H 0 1563
FID C 4 2446
FID C 6 1759
FID C 3 5938
FID C 8 4307
FID L 13 1186
FID L 14 1185
SNT VIA
FID H 0 1564
FID C 4 2505
FID C 6 1816
FID C 3 6015
FID C 8 4377
FID L 13 1236
FID L 14 1235
SNT VIA
FID H 0 1565
FID C 4 3228
FID C 6 2475
FID C 3 7185
FID C 8 5397
FID L 13 1899
FID L 14 1898
SNT VIA
FID H 0 1566
FID C 4 2502
FID C 6 1812
FID C 3 6012
FID C 8 4371
FID L 13 1233
FID L 14 1232
SNT VIA
FID H 0 1567
FID C 4 2501
FID C 6 1811
FID C 3 6011
FID C 8 4370
FID L 13 1232
FID L 14 1231
SNT VIA
FID H 0 1568
FID C 4 3229
FID C 6 2476
FID C 3 7186
FID C 8 5398
FID L 13 1900
FID L 14 1899
SNT VIA
FID H 0 1569
FID C 4 3230
FID C 6 2477
FID C 3 7187
FID C 8 5399
FID L 13 1901
FID L 14 1900
SNT VIA
FID H 0 1570
FID C 4 2503
FID C 6 1813
FID C 3 6013
FID C 8 4372
FID L 13 1234
FID L 14 1233
SNT VIA
FID H 0 1571
FID C 4 3231
FID C 6 2478
FID C 3 7188
FID C 8 5400
FID L 13 1902
FID L 14 1901
SNT VIA
FID H 0 1572
FID C 4 2498
FID C 6 1809
FID C 3 6005
FID C 8 4368
FID L 13 1230
FID L 14 1229
SNT VIA
FID H 0 1573
FID C 4 3621
FID C 6 2804
FID C 3 7718
FID C 8 5779
FID L 13 2134
FID L 14 2133
SNT VIA
FID H 0 1574
FID C 4 3232
FID C 6 2479
FID C 3 7189
FID C 8 5401
FID L 13 1903
FID L 14 1902
SNT VIA
FID H 0 1575
FID C 4 3233
FID C 6 2480
FID C 3 7190
FID C 8 5402
FID L 13 1904
FID L 14 1903
SNT VIA
FID H 0 1576
FID C 4 2493
FID C 6 1804
FID C 3 6000
FID C 8 4363
FID L 13 1225
FID L 14 1224
SNT VIA
FID H 0 1577
FID C 4 2494
FID C 6 1805
FID C 3 6001
FID C 8 4364
FID L 13 1226
FID L 14 1225
SNT VIA
FID H 0 1578
FID C 4 2440
FID C 6 1753
FID C 3 5928
FID C 8 4297
FID L 13 1182
FID L 14 1181
SNT VIA
FID H 0 1579
FID C 4 3234
FID C 6 2481
FID C 3 7191
FID C 8 5403
FID L 13 1905
FID L 14 1904
SNT VIA
FID H 0 1580
FID C 4 2495
FID C 6 1806
FID C 3 6002
FID C 8 4365
FID L 13 1227
FID L 14 1226
SNT VIA
FID H 0 1581
FID C 4 3622
FID C 6 2806
FID C 3 7719
FID C 8 5782
FID L 13 2135
FID L 14 2134
SNT VIA
FID H 0 1582
FID C 4 2953
FID C 6 2213
FID C 3 6867
FID C 8 5112
FID L 13 1646
FID L 14 1645
SNT VIA
FID H 0 1583
FID C 4 3235
FID C 6 2482
FID C 3 7192
FID C 8 5404
FID L 13 1906
FID L 14 1905
SNT VIA
FID H 0 1584
FID C 4 2496
FID C 6 1807
FID C 3 6003
FID C 8 4366
FID L 13 1228
FID L 14 1227
SNT VIA
FID H 0 1585
FID C 4 2955
FID C 6 2215
FID C 3 6869
FID C 8 5114
FID L 13 1648
FID L 14 1647
SNT VIA
FID H 0 1586
FID C 4 3236
FID C 6 2483
FID C 3 7193
FID C 8 5405
FID L 13 1907
FID L 14 1906
SNT VIA
FID H 0 1587
FID C 4 2441
FID C 6 1754
FID C 3 5929
FID C 8 4298
FID L 13 1183
FID L 14 1182
SNT VIA
FID H 0 1588
FID C 4 2497
FID C 6 1808
FID C 3 6004
FID C 8 4367
FID L 13 1229
FID L 14 1228
SNT VIA
FID H 0 1589
FID C 4 3237
FID C 6 2484
FID C 3 7194
FID C 8 5406
FID L 13 1908
FID L 14 1907
SNT VIA
FID H 0 1590
FID C 4 2489
FID C 6 1800
FID C 3 5996
FID C 8 4359
FID L 13 1221
FID L 14 1220
SNT VIA
FID H 0 1591
FID C 4 3238
FID C 6 2485
FID C 3 7195
FID C 8 5407
FID L 13 1909
FID L 14 1908
SNT VIA
FID H 0 1592
FID C 4 2492
FID C 6 1803
FID C 3 5999
FID C 8 4362
FID L 13 1224
FID L 14 1223
SNT VIA
FID H 0 1593
FID C 4 2485
FID C 6 1796
FID C 3 5992
FID C 8 4355
FID L 13 1217
FID L 14 1216
SNT VIA
FID H 0 1594
FID C 4 2484
FID C 6 1795
FID C 3 5991
FID C 8 4354
FID L 13 1216
FID L 14 1215
SNT VIA
FID H 0 1595
FID C 4 2488
FID C 6 1799
FID C 3 5995
FID C 8 4358
FID L 13 1220
FID L 14 1219
SNT VIA
FID H 0 1596
FID C 4 3239
FID C 6 2486
FID C 3 7196
FID C 8 5408
FID L 13 1910
FID L 14 1909
SNT VIA
FID H 0 1597
FID C 4 2491
FID C 6 1802
FID C 3 5998
FID C 8 4361
FID L 13 1223
FID L 14 1222
SNT VIA
FID H 0 1598
FID C 4 3240
FID C 6 2487
FID C 3 7197
FID C 8 5409
FID L 13 1911
FID L 14 1910
SNT VIA
FID H 0 1599
FID C 4 2438
FID C 6 1750
FID C 3 5926
FID C 8 4292
FID L 13 1180
FID L 14 1179
SNT VIA
FID H 0 1600
FID C 4 3128
FID C 6 2378
FID C 3 7066
FID C 8 5285
FID L 13 1806
FID L 14 1805
SNT VIA
FID H 0 1601
FID C 4 2490
FID C 6 1801
FID C 3 5997
FID C 8 4360
FID L 13 1222
FID L 14 1221
SNT VIA
FID H 0 1602
FID C 4 2487
FID C 6 1798
FID C 3 5994
FID C 8 4357
FID L 13 1219
FID L 14 1218
SNT VIA
FID H 0 1603
FID C 4 2486
FID C 6 1797
FID C 3 5993
FID C 8 4356
FID L 13 1218
FID L 14 1217
SNT VIA
FID H 0 1604
FID C 4 3241
FID C 6 2488
FID C 3 7198
FID C 8 5410
FID L 13 1912
FID L 14 1911
SNT VIA
FID H 0 1605
FID C 4 2483
FID C 6 1794
FID C 3 5990
FID C 8 4353
FID L 13 1215
FID L 14 1214
SNT VIA
FID H 0 1606
FID C 4 3242
FID C 6 2489
FID C 3 7199
FID C 8 5411
FID L 13 1913
FID L 14 1912
SNT VIA
FID H 0 1607
FID C 4 2482
FID C 6 1793
FID C 3 5989
FID C 8 4352
FID L 13 1214
FID L 14 1213
SNT VIA
FID H 0 1608
FID C 4 3591
FID C 6 2778
FID C 3 7681
FID C 8 5751
FID L 13 2109
FID L 14 2108
SNT VIA
FID H 0 1609
FID C 4 3612
FID C 6 2797
FID C 3 7706
FID C 8 5770
FID L 13 2128
FID L 14 2127
SNT VIA
FID H 0 1610
FID C 4 2713
FID C 6 2003
FID C 3 6447
FID C 8 4679
FID L 13 1384
FID L 14 1383
SNT VIA
FID H 0 1611
FID C 4 3243
FID C 6 2490
FID C 3 7200
FID C 8 5412
FID L 13 1914
FID L 14 1913
SNT VIA
FID H 0 1612
FID C 4 2481
FID C 6 1792
FID C 3 5988
FID C 8 4351
FID L 13 1213
FID L 14 1212
SNT VIA
FID H 0 1613
FID C 4 2477
FID C 6 1788
FID C 3 5984
FID C 8 4347
FID L 13 1209
FID L 14 1208
SNT VIA
FID H 0 1614
FID C 4 2478
FID C 6 1789
FID C 3 5985
FID C 8 4348
FID L 13 1210
FID L 14 1209
SNT VIA
FID H 0 1615
FID C 4 3244
FID C 6 2491
FID C 3 7201
FID C 8 5413
FID L 13 1915
FID L 14 1914
SNT VIA
FID H 0 1616
FID C 4 2480
FID C 6 1791
FID C 3 5987
FID C 8 4350
FID L 13 1212
FID L 14 1211
SNT VIA
FID H 0 1617
FID C 4 2952
FID C 6 2212
FID C 3 6866
FID C 8 5111
FID L 13 1645
FID L 14 1644
SNT VIA
FID H 0 1618
FID C 4 3245
FID C 6 2492
FID C 3 7202
FID C 8 5414
FID L 13 1916
FID L 14 1915
SNT VIA
FID H 0 1619
FID C 4 2437
FID C 6 1749
FID C 3 5925
FID C 8 4291
FID L 13 1179
FID L 14 1178
SNT VIA
FID H 0 1620
FID C 4 3129
FID C 6 2379
FID C 3 7067
FID C 8 5286
FID L 13 1807
FID L 14 1806
SNT VIA
FID H 0 1621
FID C 4 2479
FID C 6 1790
FID C 3 5986
FID C 8 4349
FID L 13 1211
FID L 14 1210
SNT VIA
FID H 0 1622
FID C 4 2956
FID C 6 2216
FID C 3 6870
FID C 8 5115
FID L 13 1649
FID L 14 1648
SNT VIA
FID H 0 1623
FID C 4 3246
FID C 6 2493
FID C 3 7203
FID C 8 5415
FID L 13 1917
FID L 14 1916
SNT VIA
FID H 0 1624
FID C 4 2527
FID C 6 1838
FID C 3 6054
FID C 8 4403
FID L 13 1257
FID L 14 1256
SNT VIA
FID H 0 1625
FID C 4 2539
FID C 6 1846
FID C 3 6091
FID C 8 4413
FID L 13 1264
FID L 14 1263
SNT VIA
FID H 0 1626
FID C 4 3247
FID C 6 2494
FID C 3 7204
FID C 8 5416
FID L 13 1918
FID L 14 1917
SNT VIA
FID H 0 1627
FID C 4 2538
FID C 6 1845
FID C 3 6090
FID C 8 4412
FID L 13 1263
FID L 14 1262
SNT VIA
FID H 0 1628
FID C 4 2529
FID C 6 1841
FID C 3 6056
FID C 8 4408
FID L 13 1259
FID L 14 1258
SNT VIA
FID H 0 1629
FID C 4 2526
FID C 6 1837
FID C 3 6050
FID C 8 4402
FID L 13 1256
FID L 14 1255
SNT VIA
FID H 0 1630
FID C 4 3248
FID C 6 2495
FID C 3 7205
FID C 8 5417
FID L 13 1919
FID L 14 1918
SNT VIA
FID H 0 1631
FID C 4 2537
FID C 6 1844
FID C 3 6089
FID C 8 4411
FID L 13 1262
FID L 14 1261
SNT VIA
FID H 0 1632
FID C 4 3249
FID C 6 2496
FID C 3 7206
FID C 8 5418
FID L 13 1920
FID L 14 1919
SNT VIA
FID H 0 1633
FID C 4 2528
FID C 6 1839
FID C 3 6055
FID C 8 4404
FID L 13 1258
FID L 14 1257
SNT VIA
FID H 0 1634
FID C 4 2536
FID C 6 1843
FID C 3 6088
FID C 8 4410
FID L 13 1261
FID L 14 1260
SNT VIA
FID H 0 1635
FID C 4 3250
FID C 6 2497
FID C 3 7207
FID C 8 5419
FID L 13 1921
FID L 14 1920
SNT VIA
FID H 0 1636
FID C 4 2513
FID C 6 1824
FID C 3 6028
FID C 8 4385
FID L 13 1244
FID L 14 1243
SNT VIA
FID H 0 1637
FID C 4 3251
FID C 6 2498
FID C 3 7208
FID C 8 5420
FID L 13 1922
FID L 14 1921
SNT VIA
FID H 0 1638
FID C 4 2512
FID C 6 1823
FID C 3 6027
FID C 8 4384
FID L 13 1243
FID L 14 1242
SNT VIA
FID H 0 1639
FID C 4 2508
FID C 6 1819
FID C 3 6018
FID C 8 4380
FID L 13 1239
FID L 14 1238
SNT VIA
FID H 0 1640
FID C 4 3252
FID C 6 2499
FID C 3 7209
FID C 8 5421
FID L 13 1923
FID L 14 1922
SNT VIA
FID H 0 1641
FID C 4 2511
FID C 6 1822
FID C 3 6026
FID C 8 4383
FID L 13 1242
FID L 14 1241
SNT VIA
FID H 0 1642
FID C 4 3253
FID C 6 2500
FID C 3 7210
FID C 8 5422
FID L 13 1924
FID L 14 1923
SNT VIA
FID H 0 1643
FID C 4 2510
FID C 6 1821
FID C 3 6025
FID C 8 4382
FID L 13 1241
FID L 14 1240
SNT VIA
FID H 0 1644
FID C 4 2507
FID C 6 1818
FID C 3 6017
FID C 8 4379
FID L 13 1238
FID L 14 1237
SNT VIA
FID H 0 1645
FID C 4 2931
FID C 6 2191
FID C 3 6845
FID C 8 5090
FID L 13 1624
FID L 14 1623
SNT VIA
FID H 0 1646
FID C 4 2654
FID C 6 1961
FID C 3 6316
FID C 8 4610
FID L 13 1348
FID L 14 1347
SNT VIA
FID H 0 1647
FID C 4 2653
FID C 6 1960
FID C 3 6315
FID C 8 4609
FID L 13 1347
FID L 14 1346
SNT VIA
FID H 0 1648
FID C 4 2924
FID C 6 2184
FID C 3 6838
FID C 8 5083
FID L 13 1617
FID L 14 1616
SNT VIA
FID H 0 1649
FID C 4 2923
FID C 6 2183
FID C 3 6837
FID C 8 5082
FID L 13 1616
FID L 14 1615
SNT VIA
FID H 0 1650
FID C 4 2930
FID C 6 2190
FID C 3 6844
FID C 8 5089
FID L 13 1623
FID L 14 1622
SNT VIA
FID H 0 1651
FID C 4 2922
FID C 6 2182
FID C 3 6836
FID C 8 5081
FID L 13 1615
FID L 14 1614
SNT VIA
FID H 0 1652
FID C 4 2658
FID C 6 1965
FID C 3 6320
FID C 8 4614
FID L 13 1352
FID L 14 1351
SNT VIA
FID H 0 1653
FID C 4 2657
FID C 6 1964
FID C 3 6319
FID C 8 4613
FID L 13 1351
FID L 14 1350
SNT VIA
FID H 0 1654
FID C 4 2656
FID C 6 1963
FID C 3 6318
FID C 8 4612
FID L 13 1350
FID L 14 1349
SNT VIA
FID H 0 1655
FID C 4 2655
FID C 6 1962
FID C 3 6317
FID C 8 4611
FID L 13 1349
FID L 14 1348
SNT VIA
FID H 0 1656
FID C 4 2929
FID C 6 2189
FID C 3 6843
FID C 8 5088
FID L 13 1622
FID L 14 1621
SNT VIA
FID H 0 1657
FID C 4 2921
FID C 6 2181
FID C 3 6835
FID C 8 5080
FID L 13 1614
FID L 14 1613
SNT VIA
FID H 0 1658
FID C 4 2920
FID C 6 2180
FID C 3 6834
FID C 8 5079
FID L 13 1613
FID L 14 1612
SNT VIA
FID H 0 1659
FID C 4 2919
FID C 6 2179
FID C 3 6833
FID C 8 5078
FID L 13 1612
FID L 14 1611
SNT VIA
FID H 0 1660
FID C 4 2918
FID C 6 2178
FID C 3 6832
FID C 8 5077
FID L 13 1611
FID L 14 1610
SNT VIA
FID H 0 1661
FID C 4 2917
FID C 6 2177
FID C 3 6831
FID C 8 5076
FID L 13 1610
FID L 14 1609
SNT VIA
FID H 0 1662
FID C 4 2916
FID C 6 2176
FID C 3 6830
FID C 8 5075
FID L 13 1609
FID L 14 1608
SNT VIA
FID H 0 1663
FID C 4 2915
FID C 6 2175
FID C 3 6829
FID C 8 5074
FID L 13 1608
FID L 14 1607
SNT VIA
FID H 0 1664
FID C 4 2914
FID C 6 2174
FID C 3 6828
FID C 8 5073
FID L 13 1607
FID L 14 1606
SNT VIA
FID H 0 1665
FID C 4 2913
FID C 6 2173
FID C 3 6827
FID C 8 5072
FID L 13 1606
FID L 14 1605
SNT VIA
FID H 0 1666
FID C 4 2912
FID C 6 2172
FID C 3 6826
FID C 8 5071
FID L 13 1605
FID L 14 1604
SNT VIA
FID H 0 1667
FID C 4 2928
FID C 6 2188
FID C 3 6842
FID C 8 5087
FID L 13 1621
FID L 14 1620
SNT VIA
FID H 0 1668
FID C 4 2911
FID C 6 2171
FID C 3 6825
FID C 8 5070
FID L 13 1604
FID L 14 1603
SNT VIA
FID H 0 1669
FID C 4 2910
FID C 6 2170
FID C 3 6824
FID C 8 5069
FID L 13 1603
FID L 14 1602
SNT VIA
FID H 0 1670
FID C 4 2909
FID C 6 2169
FID C 3 6823
FID C 8 5068
FID L 13 1602
FID L 14 1601
SNT VIA
FID H 0 1671
FID C 4 2908
FID C 6 2168
FID C 3 6822
FID C 8 5067
FID L 13 1601
FID L 14 1600
SNT VIA
FID H 0 1672
FID C 4 2907
FID C 6 2167
FID C 3 6821
FID C 8 5066
FID L 13 1600
FID L 14 1599
SNT VIA
FID H 0 1673
FID C 4 2906
FID C 6 2166
FID C 3 6820
FID C 8 5065
FID L 13 1599
FID L 14 1598
SNT VIA
FID H 0 1674
FID C 4 2905
FID C 6 2165
FID C 3 6819
FID C 8 5064
FID L 13 1598
FID L 14 1597
SNT VIA
FID H 0 1675
FID C 4 2904
FID C 6 2164
FID C 3 6818
FID C 8 5063
FID L 13 1597
FID L 14 1596
SNT VIA
FID H 0 1676
FID C 4 2903
FID C 6 2163
FID C 3 6817
FID C 8 5062
FID L 13 1596
FID L 14 1595
SNT VIA
FID H 0 1677
FID C 4 2902
FID C 6 2162
FID C 3 6816
FID C 8 5061
FID L 13 1595
FID L 14 1594
SNT VIA
FID H 0 1678
FID C 4 2927
FID C 6 2187
FID C 3 6841
FID C 8 5086
FID L 13 1620
FID L 14 1619
SNT VIA
FID H 0 1679
FID C 4 2901
FID C 6 2161
FID C 3 6815
FID C 8 5060
FID L 13 1594
FID L 14 1593
SNT VIA
FID H 0 1680
FID C 4 2900
FID C 6 2160
FID C 3 6814
FID C 8 5059
FID L 13 1593
FID L 14 1592
SNT VIA
FID H 0 1681
FID C 4 2899
FID C 6 2159
FID C 3 6813
FID C 8 5058
FID L 13 1592
FID L 14 1591
SNT VIA
FID H 0 1682
FID C 4 2898
FID C 6 2158
FID C 3 6812
FID C 8 5057
FID L 13 1591
FID L 14 1590
SNT VIA
FID H 0 1683
FID C 4 2926
FID C 6 2186
FID C 3 6840
FID C 8 5085
FID L 13 1619
FID L 14 1618
SNT VIA
FID H 0 1684
FID C 4 2925
FID C 6 2185
FID C 3 6839
FID C 8 5084
FID L 13 1618
FID L 14 1617
SNT VIA
FID H 0 1685
FID C 4 3254
FID C 6 2501
FID C 3 7211
FID C 8 5423
FID L 13 1925
FID L 14 1924
SNT VIA
FID H 0 1686
FID C 4 2419
FID C 6 1732
FID C 3 5902
FID C 8 4270
FID L 13 1165
FID L 14 1164
SNT VIA
FID H 0 1687
FID C 4 2951
FID C 6 2211
FID C 3 6865
FID C 8 5110
FID L 13 1644
FID L 14 1643
SNT VIA
FID H 0 1688
FID C 4 3255
FID C 6 2502
FID C 3 7212
FID C 8 5424
FID L 13 1926
FID L 14 1925
SNT VIA
FID H 0 1689
FID C 4 2418
FID C 6 1731
FID C 3 5901
FID C 8 4269
FID L 13 1164
FID L 14 1163
SNT VIA
FID H 0 1690
FID C 4 2957
FID C 6 2217
FID C 3 6871
FID C 8 5116
FID L 13 1650
FID L 14 1649
SNT VIA
FID H 0 1691
FID C 4 2412
FID C 6 1725
FID C 3 5886
FID C 8 4263
FID L 13 1158
FID L 14 1157
SNT VIA
FID H 0 1692
FID C 4 3256
FID C 6 2503
FID C 3 7213
FID C 8 5425
FID L 13 1927
FID L 14 1926
SNT VIA
FID H 0 1693
FID C 4 2413
FID C 6 1726
FID C 3 5894
FID C 8 4264
FID L 13 1159
FID L 14 1158
SNT VIA
FID H 0 1694
FID C 4 2417
FID C 6 1730
FID C 3 5900
FID C 8 4268
FID L 13 1163
FID L 14 1162
SNT VIA
FID H 0 1695
FID C 4 3257
FID C 6 2504
FID C 3 7214
FID C 8 5426
FID L 13 1928
FID L 14 1927
SNT VIA
FID H 0 1696
FID C 4 2416
FID C 6 1729
FID C 3 5899
FID C 8 4267
FID L 13 1162
FID L 14 1161
SNT VIA
FID H 0 1697
FID C 4 2415
FID C 6 1728
FID C 3 5898
FID C 8 4266
FID L 13 1161
FID L 14 1160
SNT VIA
FID H 0 1698
FID C 4 3258
FID C 6 2505
FID C 3 7215
FID C 8 5427
FID L 13 1929
FID L 14 1928
SNT VIA
FID H 0 1699
FID C 4 3223
FID C 6 2470
FID C 3 7180
FID C 8 5392
FID L 13 1894
FID L 14 1893
SNT VIA
FID H 0 1700
FID C 4 3259
FID C 6 2506
FID C 3 7216
FID C 8 5428
FID L 13 1930
FID L 14 1929
SNT VIA
FID H 0 1701
FID C 4 3222
FID C 6 2469
FID C 3 7179
FID C 8 5391
FID L 13 1893
FID L 14 1892
SNT VIA
FID H 0 1702
FID C 4 3260
FID C 6 2507
FID C 3 7217
FID C 8 5429
FID L 13 1931
FID L 14 1930
SNT VIA
FID H 0 1703
FID C 4 3221
FID C 6 2468
FID C 3 7178
FID C 8 5390
FID L 13 1892
FID L 14 1891
SNT VIA
FID H 0 1704
FID C 4 3261
FID C 6 2508
FID C 3 7218
FID C 8 5430
FID L 13 1932
FID L 14 1931
SNT VIA
FID H 0 1705
FID C 4 3220
FID C 6 2467
FID C 3 7177
FID C 8 5389
FID L 13 1891
FID L 14 1890
SNT VIA
FID H 0 1706
FID C 4 3262
FID C 6 2509
FID C 3 7219
FID C 8 5431
FID L 13 1933
FID L 14 1932
SNT VIA
FID H 0 1707
FID C 4 3219
FID C 6 2466
FID C 3 7176
FID C 8 5388
FID L 13 1890
FID L 14 1889
SNT VIA
FID H 0 1708
FID C 4 3126
FID C 6 2376
FID C 3 7064
FID C 8 5283
FID L 13 1804
FID L 14 1803
SNT VIA
FID H 0 1709
FID C 4 3263
FID C 6 2510
FID C 3 7220
FID C 8 5432
FID L 13 1934
FID L 14 1933
SNT VIA
FID H 0 1710
FID C 4 3218
FID C 6 2465
FID C 3 7175
FID C 8 5387
FID L 13 1889
FID L 14 1888
SNT VIA
FID H 0 1711
FID C 4 3568
FID C 6 2771
FID C 3 7654
FID C 8 5741
FID L 13 2105
FID L 14 2104
SNT VIA
FID H 0 1712
FID C 4 2897
FID C 6 2157
FID C 3 6811
FID C 8 5056
FID L 13 1590
FID L 14 1589
SNT VIA
FID H 0 1713
FID C 4 3264
FID C 6 2511
FID C 3 7221
FID C 8 5433
FID L 13 1935
FID L 14 1934
SNT VIA
FID H 0 1714
FID C 4 3217
FID C 6 2464
FID C 3 7174
FID C 8 5386
FID L 13 1888
FID L 14 1887
SNT VIA
FID H 0 1715
FID C 4 3641
FID C 6 2821
FID C 3 7747
FID C 8 5800
FID L 13 2148
FID L 14 2147
SNT VIA
FID H 0 1716
FID C 4 3642
FID C 6 2823
FID C 3 7748
FID C 8 5803
FID L 13 2149
FID L 14 2148
SNT VIA
FID H 0 1717
FID C 4 2950
FID C 6 2210
FID C 3 6864
FID C 8 5109
FID L 13 1643
FID L 14 1642
SNT VIA
FID H 0 1718
FID C 4 3569
FID C 6 2772
FID C 3 7655
FID C 8 5742
FID L 13 2106
FID L 14 2105
SNT VIA
FID H 0 1719
FID C 4 3127
FID C 6 2377
FID C 3 7065
FID C 8 5284
FID L 13 1805
FID L 14 1804
SNT VIA
FID H 0 1720
FID C 4 3265
FID C 6 2512
FID C 3 7222
FID C 8 5434
FID L 13 1936
FID L 14 1935
SNT VIA
FID H 0 1721
FID C 4 3216
FID C 6 2463
FID C 3 7173
FID C 8 5385
FID L 13 1887
FID L 14 1886
SNT VIA
FID H 0 1722
FID C 4 3605
FID C 6 2791
FID C 3 7696
FID C 8 5764
FID L 13 2122
FID L 14 2121
SNT VIA
FID H 0 1723
FID C 4 2958
FID C 6 2218
FID C 3 6872
FID C 8 5117
FID L 13 1651
FID L 14 1650
SNT VIA
FID H 0 1724
FID C 4 3266
FID C 6 2513
FID C 3 7223
FID C 8 5435
FID L 13 1937
FID L 14 1936
SNT VIA
FID H 0 1725
FID C 4 3215
FID C 6 2462
FID C 3 7172
FID C 8 5384
FID L 13 1886
FID L 14 1885
SNT VIA
FID H 0 1726
FID C 4 2652
FID C 6 1959
FID C 3 6314
FID C 8 4606
FID L 13 1346
FID L 14 1345
SNT VIA
FID H 0 1727
FID C 4 3267
FID C 6 2514
FID C 3 7224
FID C 8 5436
FID L 13 1938
FID L 14 1937
SNT VIA
FID H 0 1728
FID C 4 3214
FID C 6 2461
FID C 3 7171
FID C 8 5383
FID L 13 1885
FID L 14 1884
SNT VIA
FID H 0 1729
FID C 4 3268
FID C 6 2515
FID C 3 7225
FID C 8 5437
FID L 13 1939
FID L 14 1938
SNT VIA
FID H 0 1730
FID C 4 3213
FID C 6 2460
FID C 3 7170
FID C 8 5382
FID L 13 1884
FID L 14 1883
SNT VIA
FID H 0 1731
FID C 4 3269
FID C 6 2516
FID C 3 7226
FID C 8 5438
FID L 13 1940
FID L 14 1939
SNT VIA
FID H 0 1732
FID C 4 2548
FID C 6 1870
FID C 3 6113
FID C 8 4473
FID L 13 1271
FID L 14 1270
SNT VIA
FID H 0 1733
FID C 4 3212
FID C 6 2459
FID C 3 7169
FID C 8 5381
FID L 13 1883
FID L 14 1882
SNT VIA
FID H 0 1734
FID C 4 3270
FID C 6 2517
FID C 3 7227
FID C 8 5439
FID L 13 1941
FID L 14 1940
SNT VIA
FID H 0 1735
FID C 4 3211
FID C 6 2458
FID C 3 7168
FID C 8 5380
FID L 13 1882
FID L 14 1881
SNT VIA
FID H 0 1736
FID C 4 3271
FID C 6 2518
FID C 3 7228
FID C 8 5440
FID L 13 1942
FID L 14 1941
SNT VIA
FID H 0 1737
FID C 4 3210
FID C 6 2457
FID C 3 7167
FID C 8 5379
FID L 13 1881
FID L 14 1880
SNT VIA
FID H 0 1738
FID C 4 3272
FID C 6 2519
FID C 3 7229
FID C 8 5441
FID L 13 1943
FID L 14 1942
SNT VIA
FID H 0 1739
FID C 4 3209
FID C 6 2456
FID C 3 7166
FID C 8 5378
FID L 13 1880
FID L 14 1879
SNT VIA
FID H 0 1740
FID C 4 3273
FID C 6 2520
FID C 3 7230
FID C 8 5442
FID L 13 1944
FID L 14 1943
SNT VIA
FID H 0 1741
FID C 4 3208
FID C 6 2455
FID C 3 7165
FID C 8 5377
FID L 13 1879
FID L 14 1878
SNT VIA
FID H 0 1742
FID C 4 2932
FID C 6 2192
FID C 3 6846
FID C 8 5091
FID L 13 1625
FID L 14 1624
SNT VIA
FID H 0 1743
FID C 4 3274
FID C 6 2521
FID C 3 7231
FID C 8 5443
FID L 13 1945
FID L 14 1944
SNT VIA
FID H 0 1744
FID C 4 3207
FID C 6 2454
FID C 3 7164
FID C 8 5376
FID L 13 1878
FID L 14 1877
SNT VIA
FID H 0 1745
FID C 4 2975
FID C 6 2234
FID C 3 6889
FID C 8 5133
FID L 13 1667
FID L 14 1666
SNT VIA
FID H 0 1746
FID C 4 3275
FID C 6 2522
FID C 3 7232
FID C 8 5444
FID L 13 1946
FID L 14 1945
SNT VIA
FID H 0 1747
FID C 4 3206
FID C 6 2453
FID C 3 7163
FID C 8 5375
FID L 13 1877
FID L 14 1876
SNT VIA
FID H 0 1748
FID C 4 2947
FID C 6 2207
FID C 3 6861
FID C 8 5106
FID L 13 1640
FID L 14 1639
SNT VIA
FID H 0 1749
FID C 4 3276
FID C 6 2523
FID C 3 7233
FID C 8 5445
FID L 13 1947
FID L 14 1946
SNT VIA
FID H 0 1750
FID C 4 3205
FID C 6 2452
FID C 3 7162
FID C 8 5374
FID L 13 1876
FID L 14 1875
SNT VIA
FID H 0 1751
FID C 4 3277
FID C 6 2524
FID C 3 7234
FID C 8 5446
FID L 13 1948
FID L 14 1947
SNT VIA
FID H 0 1752
FID C 4 3204
FID C 6 2451
FID C 3 7161
FID C 8 5373
FID L 13 1875
FID L 14 1874
SNT VIA
FID H 0 1753
FID C 4 3278
FID C 6 2525
FID C 3 7235
FID C 8 5447
FID L 13 1949
FID L 14 1948
SNT VIA
FID H 0 1754
FID C 4 3203
FID C 6 2450
FID C 3 7160
FID C 8 5372
FID L 13 1874
FID L 14 1873
SNT VIA
FID H 0 1755
FID C 4 3279
FID C 6 2526
FID C 3 7236
FID C 8 5448
FID L 13 1950
FID L 14 1949
SNT VIA
FID H 0 1756
FID C 4 3202
FID C 6 2449
FID C 3 7159
FID C 8 5371
FID L 13 1873
FID L 14 1872
SNT VIA
FID H 0 1757
FID C 4 3280
FID C 6 2527
FID C 3 7237
FID C 8 5449
FID L 13 1951
FID L 14 1950
SNT VIA
FID H 0 1758
FID C 4 3201
FID C 6 2448
FID C 3 7158
FID C 8 5370
FID L 13 1872
FID L 14 1871
SNT VIA
FID H 0 1759
FID C 4 3281
FID C 6 2528
FID C 3 7238
FID C 8 5450
FID L 13 1952
FID L 14 1951
SNT VIA
FID H 0 1760
FID C 4 3200
FID C 6 2447
FID C 3 7157
FID C 8 5369
FID L 13 1871
FID L 14 1870
SNT VIA
FID H 0 1761
FID C 4 3282
FID C 6 2529
FID C 3 7239
FID C 8 5451
FID L 13 1953
FID L 14 1952
SNT VIA
FID H 0 1762
FID C 4 3199
FID C 6 2446
FID C 3 7156
FID C 8 5368
FID L 13 1870
FID L 14 1869
SNT VIA
FID H 0 1763
FID C 4 3283
FID C 6 2530
FID C 3 7240
FID C 8 5452
FID L 13 1954
FID L 14 1953
SNT VIA
FID H 0 1764
FID C 4 3198
FID C 6 2445
FID C 3 7155
FID C 8 5367
FID L 13 1869
FID L 14 1868
SNT VIA
FID H 0 1765
FID C 4 3284
FID C 6 2531
FID C 3 7241
FID C 8 5453
FID L 13 1955
FID L 14 1954
SNT VIA
FID H 0 1766
FID C 4 3197
FID C 6 2444
FID C 3 7154
FID C 8 5366
FID L 13 1868
FID L 14 1867
SNT VIA
FID H 0 1767
FID C 4 2974
FID C 6 2233
FID C 3 6888
FID C 8 5132
FID L 13 1666
FID L 14 1665
SNT VIA
FID H 0 1768
FID C 4 3285
FID C 6 2532
FID C 3 7242
FID C 8 5454
FID L 13 1956
FID L 14 1955
SNT VIA
FID H 0 1769
FID C 4 3196
FID C 6 2443
FID C 3 7153
FID C 8 5365
FID L 13 1867
FID L 14 1866
SNT VIA
FID H 0 1770
FID C 4 2948
FID C 6 2208
FID C 3 6862
FID C 8 5107
FID L 13 1641
FID L 14 1640
SNT VIA
FID H 0 1771
FID C 4 3286
FID C 6 2533
FID C 3 7243
FID C 8 5455
FID L 13 1957
FID L 14 1956
SNT VIA
FID H 0 1772
FID C 4 3195
FID C 6 2442
FID C 3 7152
FID C 8 5364
FID L 13 1866
FID L 14 1865
SNT VIA
FID H 0 1773
FID C 4 3287
FID C 6 2534
FID C 3 7244
FID C 8 5456
FID L 13 1958
FID L 14 1957
SNT VIA
FID H 0 1774
FID C 4 3194
FID C 6 2441
FID C 3 7151
FID C 8 5363
FID L 13 1865
FID L 14 1864
SNT VIA
FID H 0 1775
FID C 4 3288
FID C 6 2535
FID C 3 7245
FID C 8 5457
FID L 13 1959
FID L 14 1958
SNT VIA
FID H 0 1776
FID C 4 3193
FID C 6 2440
FID C 3 7150
FID C 8 5362
FID L 13 1864
FID L 14 1863
SNT VIA
FID H 0 1777
FID C 4 3289
FID C 6 2536
FID C 3 7246
FID C 8 5458
FID L 13 1960
FID L 14 1959
SNT VIA
FID H 0 1778
FID C 4 3192
FID C 6 2439
FID C 3 7149
FID C 8 5361
FID L 13 1863
FID L 14 1862
SNT VIA
FID H 0 1779
FID C 4 3290
FID C 6 2537
FID C 3 7247
FID C 8 5459
FID L 13 1961
FID L 14 1960
SNT VIA
FID H 0 1780
FID C 4 3191
FID C 6 2438
FID C 3 7148
FID C 8 5360
FID L 13 1862
FID L 14 1861
SNT VIA
FID H 0 1781
FID C 4 3291
FID C 6 2538
FID C 3 7248
FID C 8 5460
FID L 13 1962
FID L 14 1961
SNT VIA
FID H 0 1782
FID C 4 3190
FID C 6 2437
FID C 3 7147
FID C 8 5359
FID L 13 1861
FID L 14 1860
SNT VIA
FID H 0 1783
FID C 4 2949
FID C 6 2209
FID C 3 6863
FID C 8 5108
FID L 13 1642
FID L 14 1641
SNT VIA
FID H 0 1784
FID C 4 2943
FID C 6 2203
FID C 3 6857
FID C 8 5102
FID L 13 1636
FID L 14 1635
SNT VIA
FID H 0 1785
FID C 4 2944
FID C 6 2204
FID C 3 6858
FID C 8 5103
FID L 13 1637
FID L 14 1636
SNT VIA
FID H 0 1786
FID C 4 2945
FID C 6 2205
FID C 3 6859
FID C 8 5104
FID L 13 1638
FID L 14 1637
SNT VIA
FID H 0 1787
FID C 4 2946
FID C 6 2206
FID C 3 6860
FID C 8 5105
FID L 13 1639
FID L 14 1638
SNT VIA
FID H 0 1788
FID C 4 2939
FID C 6 2199
FID C 3 6853
FID C 8 5098
FID L 13 1632
FID L 14 1631
SNT VIA
FID H 0 1789
FID C 4 3292
FID C 6 2539
FID C 3 7249
FID C 8 5461
FID L 13 1963
FID L 14 1962
SNT VIA
FID H 0 1790
FID C 4 3189
FID C 6 2436
FID C 3 7146
FID C 8 5358
FID L 13 1860
FID L 14 1859
SNT VIA
FID H 0 1791
FID C 4 2940
FID C 6 2200
FID C 3 6854
FID C 8 5099
FID L 13 1633
FID L 14 1632
SNT VIA
FID H 0 1792
FID C 4 3293
FID C 6 2540
FID C 3 7250
FID C 8 5462
FID L 13 1964
FID L 14 1963
SNT VIA
FID H 0 1793
FID C 4 3188
FID C 6 2435
FID C 3 7145
FID C 8 5357
FID L 13 1859
FID L 14 1858
SNT VIA
FID H 0 1794
FID C 4 3294
FID C 6 2541
FID C 3 7251
FID C 8 5463
FID L 13 1965
FID L 14 1964
SNT VIA
FID H 0 1795
FID C 4 3187
FID C 6 2434
FID C 3 7144
FID C 8 5356
FID L 13 1858
FID L 14 1857
SNT VIA
FID H 0 1796
FID C 4 2973
FID C 6 2232
FID C 3 6887
FID C 8 5131
FID L 13 1665
FID L 14 1664
SNT VIA
FID H 0 1797
FID C 4 3295
FID C 6 2542
FID C 3 7252
FID C 8 5464
FID L 13 1966
FID L 14 1965
SNT VIA
FID H 0 1798
FID C 4 3186
FID C 6 2433
FID C 3 7143
FID C 8 5355
FID L 13 1857
FID L 14 1856
SNT VIA
FID H 0 1799
FID C 4 3692
FID C 6 2851
FID C 3 7808
FID C 8 5840
FID L 13 2172
FID L 14 2171
SNT VIA
FID H 0 1800
FID C 4 3296
FID C 6 2543
FID C 3 7253
FID C 8 5465
FID L 13 1967
FID L 14 1966
SNT VIA
FID H 0 1801
FID C 4 3185
FID C 6 2432
FID C 3 7142
FID C 8 5354
FID L 13 1856
FID L 14 1855
SNT VIA
FID H 0 1802
FID C 4 3297
FID C 6 2544
FID C 3 7254
FID C 8 5466
FID L 13 1968
FID L 14 1967
SNT VIA
FID H 0 1803
FID C 4 3184
FID C 6 2431
FID C 3 7141
FID C 8 5353
FID L 13 1855
FID L 14 1854
SNT VIA
FID H 0 1804
FID C 4 3298
FID C 6 2545
FID C 3 7255
FID C 8 5467
FID L 13 1969
FID L 14 1968
SNT VIA
FID H 0 1805
FID C 4 3183
FID C 6 2430
FID C 3 7140
FID C 8 5352
FID L 13 1854
FID L 14 1853
SNT VIA
FID H 0 1806
FID C 4 2941
FID C 6 2201
FID C 3 6855
FID C 8 5100
FID L 13 1634
FID L 14 1633
SNT VIA
FID H 0 1807
FID C 4 3299
FID C 6 2546
FID C 3 7256
FID C 8 5468
FID L 13 1970
FID L 14 1969
SNT VIA
FID H 0 1808
FID C 4 3182
FID C 6 2429
FID C 3 7139
FID C 8 5351
FID L 13 1853
FID L 14 1852
SNT VIA
FID H 0 1809
FID C 4 3300
FID C 6 2547
FID C 3 7257
FID C 8 5469
FID L 13 1971
FID L 14 1970
SNT VIA
FID H 0 1810
FID C 4 3181
FID C 6 2428
FID C 3 7138
FID C 8 5350
FID L 13 1852
FID L 14 1851
SNT VIA
FID H 0 1811
FID C 4 3301
FID C 6 2548
FID C 3 7258
FID C 8 5470
FID L 13 1972
FID L 14 1971
SNT VIA
FID H 0 1812
FID C 4 3180
FID C 6 2427
FID C 3 7137
FID C 8 5349
FID L 13 1851
FID L 14 1850
SNT VIA
FID H 0 1813
FID C 4 3302
FID C 6 2549
FID C 3 7259
FID C 8 5471
FID L 13 1973
FID L 14 1972
SNT VIA
FID H 0 1814
FID C 4 3179
FID C 6 2426
FID C 3 7136
FID C 8 5348
FID L 13 1850
FID L 14 1849
SNT VIA
FID H 0 1815
FID C 4 3303
FID C 6 2550
FID C 3 7260
FID C 8 5472
FID L 13 1974
FID L 14 1973
SNT VIA
FID H 0 1816
FID C 4 3178
FID C 6 2425
FID C 3 7135
FID C 8 5347
FID L 13 1849
FID L 14 1848
SNT VIA
FID H 0 1817
FID C 4 3304
FID C 6 2551
FID C 3 7261
FID C 8 5473
FID L 13 1975
FID L 14 1974
SNT VIA
FID H 0 1818
FID C 4 3177
FID C 6 2424
FID C 3 7134
FID C 8 5346
FID L 13 1848
FID L 14 1847
SNT VIA
FID H 0 1819
FID C 4 2972
FID C 6 2231
FID C 3 6886
FID C 8 5130
FID L 13 1664
FID L 14 1663
SNT VIA
FID H 0 1820
FID C 4 3305
FID C 6 2552
FID C 3 7262
FID C 8 5474
FID L 13 1976
FID L 14 1975
SNT VIA
FID H 0 1821
FID C 4 3176
FID C 6 2423
FID C 3 7133
FID C 8 5345
FID L 13 1847
FID L 14 1846
SNT VIA
FID H 0 1822
FID C 4 3306
FID C 6 2553
FID C 3 7263
FID C 8 5475
FID L 13 1977
FID L 14 1976
SNT VIA
FID H 0 1823
FID C 4 3175
FID C 6 2422
FID C 3 7132
FID C 8 5344
FID L 13 1846
FID L 14 1845
SNT VIA
FID H 0 1824
FID C 4 3307
FID C 6 2554
FID C 3 7264
FID C 8 5476
FID L 13 1978
FID L 14 1977
SNT VIA
FID H 0 1825
FID C 4 3174
FID C 6 2421
FID C 3 7131
FID C 8 5343
FID L 13 1845
FID L 14 1844
SNT VIA
FID H 0 1826
FID C 4 2942
FID C 6 2202
FID C 3 6856
FID C 8 5101
FID L 13 1635
FID L 14 1634
SNT VIA
FID H 0 1827
FID C 4 3308
FID C 6 2555
FID C 3 7265
FID C 8 5477
FID L 13 1979
FID L 14 1978
SNT VIA
FID H 0 1828
FID C 4 3173
FID C 6 2420
FID C 3 7130
FID C 8 5342
FID L 13 1844
FID L 14 1843
SNT VIA
FID H 0 1829
FID C 4 3124
FID C 6 2374
FID C 3 7062
FID C 8 5281
FID L 13 1802
FID L 14 1801
SNT VIA
FID H 0 1830
FID C 4 3125
FID C 6 2375
FID C 3 7063
FID C 8 5282
FID L 13 1803
FID L 14 1802
SNT VIA
FID H 0 1831
FID C 4 3309
FID C 6 2556
FID C 3 7266
FID C 8 5478
FID L 13 1980
FID L 14 1979
SNT VIA
FID H 0 1832
FID C 4 3172
FID C 6 2419
FID C 3 7129
FID C 8 5341
FID L 13 1843
FID L 14 1842
SNT VIA
FID H 0 1833
FID C 4 3310
FID C 6 2557
FID C 3 7267
FID C 8 5479
FID L 13 1981
FID L 14 1980
SNT VIA
FID H 0 1834
FID C 4 3171
FID C 6 2418
FID C 3 7128
FID C 8 5340
FID L 13 1842
FID L 14 1841
SNT VIA
FID H 0 1835
FID C 4 3311
FID C 6 2558
FID C 3 7268
FID C 8 5480
FID L 13 1982
FID L 14 1981
SNT VIA
FID H 0 1836
FID C 4 3170
FID C 6 2417
FID C 3 7127
FID C 8 5339
FID L 13 1841
FID L 14 1840
SNT VIA
FID H 0 1837
FID C 4 3312
FID C 6 2559
FID C 3 7269
FID C 8 5481
FID L 13 1983
FID L 14 1982
SNT VIA
FID H 0 1838
FID C 4 3313
FID C 6 2560
FID C 3 7270
FID C 8 5482
FID L 13 1984
FID L 14 1983
SNT VIA
FID H 0 1839
FID C 4 3314
FID C 6 2561
FID C 3 7271
FID C 8 5483
FID L 13 1985
FID L 14 1984
SNT VIA
FID H 0 1840
FID C 4 2971
FID C 6 2230
FID C 3 6885
FID C 8 5129
FID L 13 1663
FID L 14 1662
SNT VIA
FID H 0 1841
FID C 4 3315
FID C 6 2562
FID C 3 7272
FID C 8 5484
FID L 13 1986
FID L 14 1985
SNT VIA
FID H 0 1842
FID C 4 3316
FID C 6 2563
FID C 3 7273
FID C 8 5485
FID L 13 1987
FID L 14 1986
SNT VIA
FID H 0 1843
FID C 4 3169
FID C 6 2416
FID C 3 7126
FID C 8 5338
FID L 13 1840
FID L 14 1839
SNT VIA
FID H 0 1844
FID C 4 3317
FID C 6 2564
FID C 3 7274
FID C 8 5486
FID L 13 1988
FID L 14 1987
SNT VIA
FID H 0 1845
FID C 4 3168
FID C 6 2415
FID C 3 7125
FID C 8 5337
FID L 13 1839
FID L 14 1838
SNT VIA
FID H 0 1846
FID C 4 2966
FID C 6 2225
FID C 3 6880
FID C 8 5124
FID L 13 1658
FID L 14 1657
SNT VIA
FID H 0 1847
FID C 4 3156
FID C 6 2403
FID C 3 7113
FID C 8 5325
FID L 13 1827
FID L 14 1826
SNT VIA
FID H 0 1848
FID C 4 3155
FID C 6 2402
FID C 3 7112
FID C 8 5324
FID L 13 1826
FID L 14 1825
SNT VIA
FID H 0 1849
FID C 4 2559
FID C 6 1881
FID C 3 6149
FID C 8 4496
FID L 13 1282
FID L 14 1281
SNT VIA
FID H 0 1850
FID C 4 2558
FID C 6 1880
FID C 3 6148
FID C 8 4495
FID L 13 1281
FID L 14 1280
SNT VIA
FID H 0 1851
FID C 4 2557
FID C 6 1879
FID C 3 6147
FID C 8 4494
FID L 13 1280
FID L 14 1279
SNT VIA
FID H 0 1852
FID C 4 2556
FID C 6 1878
FID C 3 6146
FID C 8 4493
FID L 13 1279
FID L 14 1278
SNT VIA
FID H 0 1853
FID C 4 2555
FID C 6 1877
FID C 3 6145
FID C 8 4492
FID L 13 1278
FID L 14 1277
SNT VIA
FID H 0 1854
FID C 4 2554
FID C 6 1876
FID C 3 6144
FID C 8 4491
FID L 13 1277
FID L 14 1276
SNT VIA
FID H 0 1855
FID C 4 2553
FID C 6 1875
FID C 3 6143
FID C 8 4490
FID L 13 1276
FID L 14 1275
SNT VIA
FID H 0 1856
FID C 4 2552
FID C 6 1874
FID C 3 6142
FID C 8 4489
FID L 13 1275
FID L 14 1274
SNT VIA
FID H 0 1857
FID C 4 2551
FID C 6 1873
FID C 3 6141
FID C 8 4488
FID L 13 1274
FID L 14 1273
SNT VIA
FID H 0 1858
FID C 4 3154
FID C 6 2401
FID C 3 7111
FID C 8 5323
FID L 13 1825
FID L 14 1824
SNT VIA
FID H 0 1859
FID C 4 3153
FID C 6 2400
FID C 3 7110
FID C 8 5322
FID L 13 1824
FID L 14 1823
SNT VIA
FID H 0 1860
FID C 4 3152
FID C 6 2399
FID C 3 7109
FID C 8 5321
FID L 13 1823
FID L 14 1822
SNT VIA
FID H 0 1861
FID C 4 3151
FID C 6 2398
FID C 3 7108
FID C 8 5320
FID L 13 1822
FID L 14 1821
SNT VIA
FID H 0 1862
FID C 4 3150
FID C 6 2397
FID C 3 7107
FID C 8 5319
FID L 13 1821
FID L 14 1820
SNT VIA
FID H 0 1863
FID C 4 3149
FID C 6 2396
FID C 3 7106
FID C 8 5318
FID L 13 1820
FID L 14 1819
SNT VIA
FID H 0 1864
FID C 4 3148
FID C 6 2395
FID C 3 7105
FID C 8 5317
FID L 13 1819
FID L 14 1818
SNT VIA
FID H 0 1865
FID C 4 3147
FID C 6 2394
FID C 3 7104
FID C 8 5316
FID L 13 1818
FID L 14 1817
SNT VIA
FID H 0 1866
FID C 4 3146
FID C 6 2393
FID C 3 7103
FID C 8 5315
FID L 13 1817
FID L 14 1816
SNT VIA
FID H 0 1867
FID C 4 3145
FID C 6 2392
FID C 3 7102
FID C 8 5314
FID L 13 1816
FID L 14 1815
SNT VIA
FID H 0 1868
FID C 4 3349
FID C 6 2596
FID C 3 7306
FID C 8 5518
FID L 13 2020
FID L 14 2019
SNT VIA
FID H 0 1869
FID C 4 3348
FID C 6 2595
FID C 3 7305
FID C 8 5517
FID L 13 2019
FID L 14 2018
SNT VIA
FID H 0 1870
FID C 4 3347
FID C 6 2594
FID C 3 7304
FID C 8 5516
FID L 13 2018
FID L 14 2017
SNT VIA
FID H 0 1871
FID C 4 3346
FID C 6 2593
FID C 3 7303
FID C 8 5515
FID L 13 2017
FID L 14 2016
SNT VIA
FID H 0 1872
FID C 4 3345
FID C 6 2592
FID C 3 7302
FID C 8 5514
FID L 13 2016
FID L 14 2015
SNT VIA
FID H 0 1873
FID C 4 3344
FID C 6 2591
FID C 3 7301
FID C 8 5513
FID L 13 2015
FID L 14 2014
SNT VIA
FID H 0 1874
FID C 4 3343
FID C 6 2590
FID C 3 7300
FID C 8 5512
FID L 13 2014
FID L 14 2013
SNT VIA
FID H 0 1875
FID C 4 3342
FID C 6 2589
FID C 3 7299
FID C 8 5511
FID L 13 2013
FID L 14 2012
SNT VIA
FID H 0 1876
FID C 4 3341
FID C 6 2588
FID C 3 7298
FID C 8 5510
FID L 13 2012
FID L 14 2011
SNT VIA
FID H 0 1877
FID C 4 3340
FID C 6 2587
FID C 3 7297
FID C 8 5509
FID L 13 2011
FID L 14 2010
SNT VIA
FID H 0 1878
FID C 4 3339
FID C 6 2586
FID C 3 7296
FID C 8 5508
FID L 13 2010
FID L 14 2009
SNT VIA
FID H 0 1879
FID C 4 3338
FID C 6 2585
FID C 3 7295
FID C 8 5507
FID L 13 2009
FID L 14 2008
SNT VIA
FID H 0 1880
FID C 4 3337
FID C 6 2584
FID C 3 7294
FID C 8 5506
FID L 13 2008
FID L 14 2007
SNT VIA
FID H 0 1881
FID C 4 3336
FID C 6 2583
FID C 3 7293
FID C 8 5505
FID L 13 2007
FID L 14 2006
SNT VIA
FID H 0 1882
FID C 4 3335
FID C 6 2582
FID C 3 7292
FID C 8 5504
FID L 13 2006
FID L 14 2005
SNT VIA
FID H 0 1883
FID C 4 3334
FID C 6 2581
FID C 3 7291
FID C 8 5503
FID L 13 2005
FID L 14 2004
SNT VIA
FID H 0 1884
FID C 4 3333
FID C 6 2580
FID C 3 7290
FID C 8 5502
FID L 13 2004
FID L 14 2003
SNT VIA
FID H 0 1885
FID C 4 3332
FID C 6 2579
FID C 3 7289
FID C 8 5501
FID L 13 2003
FID L 14 2002
SNT VIA
FID H 0 1886
FID C 4 3331
FID C 6 2578
FID C 3 7288
FID C 8 5500
FID L 13 2002
FID L 14 2001
SNT VIA
FID H 0 1887
FID C 4 3330
FID C 6 2577
FID C 3 7287
FID C 8 5499
FID L 13 2001
FID L 14 2000
SNT VIA
FID H 0 1888
FID C 4 3329
FID C 6 2576
FID C 3 7286
FID C 8 5498
FID L 13 2000
FID L 14 1999
SNT VIA
FID H 0 1889
FID C 4 3328
FID C 6 2575
FID C 3 7285
FID C 8 5497
FID L 13 1999
FID L 14 1998
SNT VIA
FID H 0 1890
FID C 4 3327
FID C 6 2574
FID C 3 7284
FID C 8 5496
FID L 13 1998
FID L 14 1997
SNT VIA
FID H 0 1891
FID C 4 3326
FID C 6 2573
FID C 3 7283
FID C 8 5495
FID L 13 1997
FID L 14 1996
SNT VIA
FID H 0 1892
FID C 4 3325
FID C 6 2572
FID C 3 7282
FID C 8 5494
FID L 13 1996
FID L 14 1995
SNT VIA
FID H 0 1893
FID C 4 3324
FID C 6 2571
FID C 3 7281
FID C 8 5493
FID L 13 1995
FID L 14 1994
SNT VIA
FID H 0 1894
FID C 4 3323
FID C 6 2570
FID C 3 7280
FID C 8 5492
FID L 13 1994
FID L 14 1993
SNT VIA
FID H 0 1895
FID C 4 3322
FID C 6 2569
FID C 3 7279
FID C 8 5491
FID L 13 1993
FID L 14 1992
SNT VIA
FID H 0 1896
FID C 4 3321
FID C 6 2568
FID C 3 7278
FID C 8 5490
FID L 13 1992
FID L 14 1991
SNT VIA
FID H 0 1897
FID C 4 3320
FID C 6 2567
FID C 3 7277
FID C 8 5489
FID L 13 1991
FID L 14 1990
SNT VIA
FID H 0 1898
FID C 4 3319
FID C 6 2566
FID C 3 7276
FID C 8 5488
FID L 13 1990
FID L 14 1989
SNT VIA
FID H 0 1899
FID C 4 3318
FID C 6 2565
FID C 3 7275
FID C 8 5487
FID L 13 1989
FID L 14 1988
SNT VIA
FID H 0 1900
FID C 4 3167
FID C 6 2414
FID C 3 7124
FID C 8 5336
FID L 13 1838
FID L 14 1837
SNT VIA
FID H 0 1901
FID C 4 3166
FID C 6 2413
FID C 3 7123
FID C 8 5335
FID L 13 1837
FID L 14 1836
SNT VIA
FID H 0 1902
FID C 4 3165
FID C 6 2412
FID C 3 7122
FID C 8 5334
FID L 13 1836
FID L 14 1835
SNT VIA
FID H 0 1903
FID C 4 3164
FID C 6 2411
FID C 3 7121
FID C 8 5333
FID L 13 1835
FID L 14 1834
SNT VIA
FID H 0 1904
FID C 4 3163
FID C 6 2410
FID C 3 7120
FID C 8 5332
FID L 13 1834
FID L 14 1833
SNT VIA
FID H 0 1905
FID C 4 3162
FID C 6 2409
FID C 3 7119
FID C 8 5331
FID L 13 1833
FID L 14 1832
SNT VIA
FID H 0 1906
FID C 4 3161
FID C 6 2408
FID C 3 7118
FID C 8 5330
FID L 13 1832
FID L 14 1831
SNT VIA
FID H 0 1907
FID C 4 3160
FID C 6 2407
FID C 3 7117
FID C 8 5329
FID L 13 1831
FID L 14 1830
SNT VIA
FID H 0 1908
FID C 4 3159
FID C 6 2406
FID C 3 7116
FID C 8 5328
FID L 13 1830
FID L 14 1829
SNT VIA
FID H 0 1909
FID C 4 3158
FID C 6 2405
FID C 3 7115
FID C 8 5327
FID L 13 1829
FID L 14 1828
SNT VIA
FID H 0 1910
FID C 4 3157
FID C 6 2404
FID C 3 7114
FID C 8 5326
FID L 13 1828
FID L 14 1827
SNT VIA
FID H 0 1911
FID C 4 2989
FID C 6 2246
FID C 3 6905
FID C 8 5145
FID L 13 1679
FID L 14 1678
SNT VIA
FID H 0 1912
FID C 4 2693
FID C 6 1992
FID C 3 6406
FID C 8 4667
FID L 13 1374
FID L 14 1373
SNT VIA
FID H 0 1913
FID C 4 2987
FID C 6 2244
FID C 3 6903
FID C 8 5143
FID L 13 1677
FID L 14 1676
SNT VIA
FID H 0 1914
FID C 4 2967
FID C 6 2226
FID C 3 6881
FID C 8 5125
FID L 13 1659
FID L 14 1658
SNT VIA
FID H 0 1915
FID C 4 2986
FID C 6 2243
FID C 3 6902
FID C 8 5142
FID L 13 1676
FID L 14 1675
SNT VIA
FID H 0 1916
FID C 4 2968
FID C 6 2227
FID C 3 6882
FID C 8 5126
FID L 13 1660
FID L 14 1659
SNT VIA
FID H 0 1917
FID C 4 2985
FID C 6 2242
FID C 3 6901
FID C 8 5141
FID L 13 1675
FID L 14 1674
SNT VIA
FID H 0 1918
FID C 4 2694
FID C 6 1993
FID C 3 6407
FID C 8 4668
FID L 13 1375
FID L 14 1374
SNT VIA
FID H 0 1919
FID C 4 2969
FID C 6 2228
FID C 3 6883
FID C 8 5127
FID L 13 1661
FID L 14 1660
SNT VIA
FID H 0 1920
FID C 4 2990
FID C 6 2247
FID C 3 6906
FID C 8 5146
FID L 13 1680
FID L 14 1679
SNT VIA
FID H 0 1921
FID C 4 2984
FID C 6 2241
FID C 3 6900
FID C 8 5140
FID L 13 1674
FID L 14 1673
SNT VIA
FID H 0 1922
FID C 4 2970
FID C 6 2229
FID C 3 6884
FID C 8 5128
FID L 13 1662
FID L 14 1661
SNT VIA
FID H 0 1923
FID C 4 2896
FID C 6 2156
FID C 3 6810
FID C 8 5055
FID L 13 1589
FID L 14 1588
SNT VIA
FID H 0 1924
FID C 4 3008
FID C 6 2261
FID C 3 6932
FID C 8 5160
FID L 13 1694
FID L 14 1693
SNT VIA
FID H 0 1925
FID C 4 2980
FID C 6 2237
FID C 3 6896
FID C 8 5136
FID L 13 1670
FID L 14 1669
SNT VIA
FID H 0 1926
FID C 4 3014
FID C 6 2267
FID C 3 6938
FID C 8 5167
FID L 13 1700
FID L 14 1699
SNT VIA
FID H 0 1927
FID C 4 3019
FID C 6 2270
FID C 3 6947
FID C 8 5170
FID L 13 1703
FID L 14 1702
SNT VIA
FID H 0 1928
FID C 4 2933
FID C 6 2193
FID C 3 6847
FID C 8 5092
FID L 13 1626
FID L 14 1625
SNT VIA
FID H 0 1929
FID C 4 3007
FID C 6 2260
FID C 3 6931
FID C 8 5159
FID L 13 1693
FID L 14 1692
SNT VIA
FID H 0 1930
FID C 4 2981
FID C 6 2238
FID C 3 6897
FID C 8 5137
FID L 13 1671
FID L 14 1670
SNT VIA
FID H 0 1931
FID C 4 3006
FID C 6 2259
FID C 3 6930
FID C 8 5158
FID L 13 1692
FID L 14 1691
SNT VIA
FID H 0 1932
FID C 4 2982
FID C 6 2239
FID C 3 6898
FID C 8 5138
FID L 13 1672
FID L 14 1671
SNT VIA
FID H 0 1933
FID C 4 3005
FID C 6 2258
FID C 3 6929
FID C 8 5157
FID L 13 1691
FID L 14 1690
SNT VIA
FID H 0 1934
FID C 4 2983
FID C 6 2240
FID C 3 6899
FID C 8 5139
FID L 13 1673
FID L 14 1672
SNT VIA
FID H 0 2143
FID C 3 6683
FID C 8 4876
FID L 13 1492
FID L 14 1491
SNT VIA
FID H 0 2144
FID C 3 6681
FID C 8 4874
FID L 13 1490
FID L 14 1489
SNT VIA
FID H 0 2145
FID C 3 6682
FID C 8 4875
FID L 13 1491
FID L 14 1490
SNT VIA
FID H 0 2173
FID C 4 3011
FID C 6 2264
FID C 3 6935
FID C 8 5163
FID L 13 1697
FID L 14 1696
SNT VIA
FID H 0 2262
FID C 4 2530
FID C 6 1842
FID C 3 6062
FID C 8 4409
FID L 13 1260
FID L 14 1259
SNT VIA
FID H 0 2263
FID C 4 2509
FID C 6 1820
FID C 3 6024
FID C 8 4381
FID L 13 1240
FID L 14 1239
SNT VIA
FID H 0 2329
FID C 4 3652
FID C 6 2828
FID C 3 7761
FID C 8 5808
FID L 13 2154
FID L 14 2153
SNT VIA
FID H 0 2330
FID C 4 2608
FID C 6 1927
FID C 3 6232
FID C 8 4554
FID L 13 1321
FID L 14 1320
SNT VIA
FID H 0 2388
FID C 3 6745
FID C 8 4938
FID L 13 1554
FID L 14 1553
SNT VIA
FID H 0 2389
FID C 3 6743
FID C 8 4936
FID L 13 1552
FID L 14 1551
SNT VIA
FID H 0 2390
FID C 3 6742
FID C 8 4935
FID L 13 1551
FID L 14 1550
SNT VIA
FID H 0 2391
FID C 3 6739
FID C 8 4932
FID L 13 1548
FID L 14 1547
SNT VIA
FID H 0 2392
FID C 3 6733
FID C 8 4926
FID L 13 1542
FID L 14 1541
SNT VIA
FID H 0 2393
FID C 3 6729
FID C 8 4922
FID L 13 1538
FID L 14 1537
SNT VIA
FID H 0 2394
FID C 3 6722
FID C 8 4915
FID L 13 1531
FID L 14 1530
SNT VIA
FID H 0 2395
FID C 3 6714
FID C 8 4907
FID L 13 1523
FID L 14 1522
SNT VIA
FID H 0 2396
FID C 3 6744
FID C 8 4937
FID L 13 1553
FID L 14 1552
SNT VIA
FID H 0 2397
FID C 3 6724
FID C 8 4917
FID L 13 1533
FID L 14 1532
SNT VIA
FID H 0 2398
FID C 3 6715
FID C 8 4908
FID L 13 1524
FID L 14 1523
SNT VIA
FID H 0 2399
FID C 3 6713
FID C 8 4906
FID L 13 1522
FID L 14 1521
SNT VIA
FID H 0 2400
FID C 3 6741
FID C 8 4934
FID L 13 1550
FID L 14 1549
SNT VIA
FID H 0 2401
FID C 3 6732
FID C 8 4925
FID L 13 1541
FID L 14 1540
SNT VIA
FID H 0 2402
FID C 3 6723
FID C 8 4916
FID L 13 1532
FID L 14 1531
SNT VIA
FID H 0 2403
FID C 3 6716
FID C 8 4909
FID L 13 1525
FID L 14 1524
SNT VIA
FID H 0 2404
FID C 3 6712
FID C 8 4905
FID L 13 1521
FID L 14 1520
SNT VIA
FID H 0 2405
FID C 3 6711
FID C 8 4904
FID L 13 1520
FID L 14 1519
SNT VIA
FID H 0 2406
FID C 3 6738
FID C 8 4931
FID L 13 1547
FID L 14 1546
SNT VIA
FID H 0 2407
FID C 3 6721
FID C 8 4914
FID L 13 1530
FID L 14 1529
SNT VIA
FID H 0 2408
FID C 3 6718
FID C 8 4911
FID L 13 1527
FID L 14 1526
SNT VIA
FID H 0 2409
FID C 3 6710
FID C 8 4903
FID L 13 1519
FID L 14 1518
SNT VIA
FID H 0 2410
FID C 3 6709
FID C 8 4902
FID L 13 1518
FID L 14 1517
SNT VIA
FID H 0 2411
FID C 3 6740
FID C 8 4933
FID L 13 1549
FID L 14 1548
SNT VIA
FID H 0 2412
FID C 3 6736
FID C 8 4929
FID L 13 1545
FID L 14 1544
SNT VIA
FID H 0 2413
FID C 3 6728
FID C 8 4921
FID L 13 1537
FID L 14 1536
SNT VIA
FID H 0 2414
FID C 3 6756
FID C 8 4949
FID L 13 1565
FID L 14 1564
SNT VIA
FID H 0 2415
FID C 3 6708
FID C 8 4901
FID L 13 1517
FID L 14 1516
SNT VIA
FID H 0 2416
FID C 3 6727
FID C 8 4920
FID L 13 1536
FID L 14 1535
SNT VIA
FID H 0 2417
FID C 3 6755
FID C 8 4948
FID L 13 1564
FID L 14 1563
SNT VIA
FID H 0 2418
FID C 3 6707
FID C 8 4900
FID L 13 1516
FID L 14 1515
SNT VIA
FID H 0 2419
FID C 3 6706
FID C 8 4899
FID L 13 1515
FID L 14 1514
SNT VIA
FID H 0 2420
FID C 3 6705
FID C 8 4898
FID L 13 1514
FID L 14 1513
SNT VIA
FID H 0 2421
FID C 3 6737
FID C 8 4930
FID L 13 1546
FID L 14 1545
SNT VIA
FID H 0 2422
FID C 3 6735
FID C 8 4928
FID L 13 1544
FID L 14 1543
SNT VIA
FID H 0 2423
FID C 3 6731
FID C 8 4924
FID L 13 1540
FID L 14 1539
SNT VIA
FID H 0 2424
FID C 3 6720
FID C 8 4913
FID L 13 1529
FID L 14 1528
SNT VIA
FID H 0 2425
FID C 3 6717
FID C 8 4910
FID L 13 1526
FID L 14 1525
SNT VIA
FID H 0 2426
FID C 3 6704
FID C 8 4897
FID L 13 1513
FID L 14 1512
SNT VIA
FID H 0 2427
FID C 3 6703
FID C 8 4896
FID L 13 1512
FID L 14 1511
SNT VIA
FID H 0 2428
FID C 3 6734
FID C 8 4927
FID L 13 1543
FID L 14 1542
SNT VIA
FID H 0 2429
FID C 3 6726
FID C 8 4919
FID L 13 1535
FID L 14 1534
SNT VIA
FID H 0 2430
FID C 3 6754
FID C 8 4947
FID L 13 1563
FID L 14 1562
SNT VIA
FID H 0 2431
FID C 3 6702
FID C 8 4895
FID L 13 1511
FID L 14 1510
SNT VIA
FID H 0 2432
FID C 3 6730
FID C 8 4923
FID L 13 1539
FID L 14 1538
SNT VIA
FID H 0 2433
FID C 3 6719
FID C 8 4912
FID L 13 1528
FID L 14 1527
SNT VIA
FID H 0 2434
FID C 3 6753
FID C 8 4946
FID L 13 1562
FID L 14 1561
SNT VIA
FID H 0 2435
FID C 3 6700
FID C 8 4893
FID L 13 1509
FID L 14 1508
SNT VIA
FID H 0 2436
FID C 3 6699
FID C 8 4892
FID L 13 1508
FID L 14 1507
SNT VIA
FID H 0 2437
FID C 3 6701
FID C 8 4894
FID L 13 1510
FID L 14 1509
SNT VIA
FID H 0 2438
FID C 3 6725
FID C 8 4918
FID L 13 1534
FID L 14 1533
SNT VIA
FID H 0 2439
FID C 3 6752
FID C 8 4945
FID L 13 1561
FID L 14 1560
SNT VIA
FID H 0 2440
FID C 3 6696
FID C 8 4889
FID L 13 1505
FID L 14 1504
SNT VIA
FID H 0 2441
FID C 3 6695
FID C 8 4888
FID L 13 1504
FID L 14 1503
SNT VIA
FID H 0 2442
FID C 3 6697
FID C 8 4890
FID L 13 1506
FID L 14 1505
SNT VIA
FID H 0 2443
FID C 3 6698
FID C 8 4891
FID L 13 1507
FID L 14 1506
SNT VIA
FID H 0 2444
FID C 3 6692
FID C 8 4885
FID L 13 1501
FID L 14 1500
SNT VIA
FID H 0 2445
FID C 3 6694
FID C 8 4887
FID L 13 1503
FID L 14 1502
SNT VIA
FID H 0 2446
FID C 3 6693
FID C 8 4886
FID L 13 1502
FID L 14 1501
SNT VIA
FID H 0 2447
FID C 3 6766
FID C 8 4959
FID L 13 1575
FID L 14 1574
SNT VIA
FID H 0 2448
FID C 3 6751
FID C 8 4944
FID L 13 1560
FID L 14 1559
SNT VIA
FID H 0 2449
FID C 3 6690
FID C 8 4883
FID L 13 1499
FID L 14 1498
SNT VIA
FID H 0 2450
FID C 3 6689
FID C 8 4882
FID L 13 1498
FID L 14 1497
SNT VIA
FID H 0 2451
FID C 3 6691
FID C 8 4884
FID L 13 1500
FID L 14 1499
SNT VIA
FID H 0 2452
FID C 3 6769
FID C 8 4962
FID L 13 1578
FID L 14 1577
SNT VIA
FID H 0 2453
FID C 3 6750
FID C 8 4943
FID L 13 1559
FID L 14 1558
SNT VIA
FID H 0 2454
FID C 3 6688
FID C 8 4881
FID L 13 1497
FID L 14 1496
SNT VIA
FID H 0 2455
FID C 3 6687
FID C 8 4880
FID L 13 1496
FID L 14 1495
SNT VIA
FID H 0 2456
FID C 3 6771
FID C 8 4964
FID L 13 1580
FID L 14 1579
SNT VIA
FID H 0 2457
FID C 3 6765
FID C 8 4958
FID L 13 1574
FID L 14 1573
SNT VIA
FID H 0 2458
FID C 3 6761
FID C 8 4954
FID L 13 1570
FID L 14 1569
SNT VIA
FID H 0 2459
FID C 3 6773
FID C 8 4966
FID L 13 1582
FID L 14 1581
SNT VIA
FID H 0 2460
FID C 3 6767
FID C 8 4960
FID L 13 1576
FID L 14 1575
SNT VIA
FID H 0 2461
FID C 3 6763
FID C 8 4956
FID L 13 1572
FID L 14 1571
SNT VIA
FID H 0 2462
FID C 3 6749
FID C 8 4942
FID L 13 1558
FID L 14 1557
SNT VIA
FID H 0 2463
FID C 3 6774
FID C 8 4967
FID L 13 1583
FID L 14 1582
SNT VIA
FID H 0 2464
FID C 3 6770
FID C 8 4963
FID L 13 1579
FID L 14 1578
SNT VIA
FID H 0 2465
FID C 3 6764
FID C 8 4957
FID L 13 1573
FID L 14 1572
SNT VIA
FID H 0 2466
FID C 3 6748
FID C 8 4941
FID L 13 1557
FID L 14 1556
SNT VIA
FID H 0 2467
FID C 3 6686
FID C 8 4879
FID L 13 1495
FID L 14 1494
SNT VIA
FID H 0 2468
FID C 3 6760
FID C 8 4953
FID L 13 1569
FID L 14 1568
SNT VIA
FID H 0 2469
FID C 3 6685
FID C 8 4878
FID L 13 1494
FID L 14 1493
SNT VIA
FID H 0 2470
FID C 3 6768
FID C 8 4961
FID L 13 1577
FID L 14 1576
SNT VIA
FID H 0 2471
FID C 3 6747
FID C 8 4940
FID L 13 1556
FID L 14 1555
SNT VIA
FID H 0 2472
FID C 3 6772
FID C 8 4965
FID L 13 1581
FID L 14 1580
SNT VIA
FID H 0 2473
FID C 3 6758
FID C 8 4951
FID L 13 1567
FID L 14 1566
SNT VIA
FID H 0 2474
FID C 3 6775
FID C 8 4968
FID L 13 1584
FID L 14 1583
SNT VIA
FID H 0 2475
FID C 3 6759
FID C 8 4952
FID L 13 1568
FID L 14 1567
SNT VIA
FID H 0 2476
FID C 3 6684
FID C 8 4877
FID L 13 1493
FID L 14 1492
SNT VIA
FID H 0 2477
FID C 3 6762
FID C 8 4955
FID L 13 1571
FID L 14 1570
SNT VIA
FID H 0 2478
FID C 3 6746
FID C 8 4939
FID L 13 1555
FID L 14 1554
SNT VIA
FID H 0 2479
FID C 3 6757
FID C 8 4950
FID L 13 1566
FID L 14 1565
SNT VIA
FID H 0 2589
FID C 4 3417
FID C 6 2671
FID C 3 7396
FID C 8 5620
FID L 13 2066
FID L 14 2065
SNT VIA
FID H 0 2590
FID C 4 2604
FID C 6 1924
FID C 3 6227
FID C 8 4551
FID L 13 1318
FID L 14 1317
SNT PLN S C 0
FID C 3 5864
SNT TRC
FID C 3 5866
SNT PLN S C 0
FID C 3 5871
SNT TRC
FID C 3 5873
FID C 3 5874
FID C 3 5875
SNT TRC
FID C 8 4250
FID C 8 4251
SNT TRC
FID C 8 4252
FID C 8 4253
FID C 8 4254
SNT PLN S C 0
FID C 3 5876
SNT PLN S C 0
FID C 3 5877
SNT PLN S C 0
FID C 3 5878
SNT PLN S C 0
FID C 3 5879
SNT PLN S C 0
SNT PLN S C 0
SNT PLN S C 0
SNT PLN S C 0
SNT PLN S C 0
FID C 8 4255
SNT PLN S C 0
FID C 8 4256
SNT PLN S C 0
FID C 3 5880
SNT PLN S C 0
FID C 8 4257
SNT TRC
FID C 3 5887
FID C 3 5888
FID C 3 5889
FID C 3 5890
FID C 3 5891
FID C 3 5892
FID C 3 5893
SNT TRC
FID C 3 5896
FID C 3 5897
SNT TRC
FID C 8 4277
SNT TRC
FID C 8 4280
FID C 8 4281
SNT TRC
FID C 3 5911
SNT TRC
FID C 3 5912
SNT TRC
FID C 3 5916
FID C 3 5917
SNT TRC
FID C 8 4286
SNT TRC
FID C 3 5920
SNT TRC
FID C 8 4294
FID C 8 4295
SNT TRC
FID C 8 4299
FID C 8 4300
SNT TRC
FID C 3 5931
FID C 3 5932
SNT TRC
FID C 8 4303
FID C 8 4304
SNT TRC
FID C 3 5935
FID C 3 5936
SNT TRC
FID C 3 5939
FID C 3 5940
SNT TRC
FID C 8 4309
FID C 8 4310
SNT TRC
FID C 3 5948
FID C 3 5949
FID C 3 5950
SNT TRC
FID C 3 5953
FID C 3 5954
SNT TRC
FID C 8 4319
FID C 8 4320
SNT TRC
FID C 3 5957
FID C 3 5958
SNT TRC
FID C 8 4323
FID C 8 4324
SNT TRC
FID C 3 5964
SNT TRC
FID C 8 4329
FID C 8 4330
SNT TRC
FID C 3 5967
FID C 3 5968
SNT TRC
FID C 8 4334
SNT TRC
FID C 3 5971
SNT TRC
FID C 3 5977
FID C 3 5978
SNT TRC
FID C 8 4340
FID C 8 4341
SNT TRC
FID C 3 6007
FID C 3 6008
FID C 3 6009
SNT TRC
FID C 8 4373
FID C 8 4374
SNT TRC
FID C 3 6019
FID C 3 6020
SNT TRC
FID C 3 6021
FID C 3 6022
FID C 3 6023
SNT TRC
FID C 3 6038
FID C 3 6039
FID C 3 6040
FID C 3 6041
FID C 3 6042
SNT TRC
FID C 3 6043
FID C 3 6044
FID C 3 6045
FID C 3 6046
SNT TRC
FID C 8 4396
FID C 8 4397
SNT TRC
FID C 8 4398
FID C 8 4399
SNT TRC
FID C 3 6051
FID C 3 6052
FID C 3 6053
SNT TRC
FID C 8 4405
FID C 8 4406
SNT TRC
FID C 3 6057
FID C 3 6058
FID C 3 6059
FID C 3 6060
FID C 3 6061
SNT TRC
FID C 3 6063
FID C 3 6064
FID C 3 6065
SNT TRC
FID C 3 6066
SNT TRC
FID C 3 6067
FID C 3 6068
FID C 3 6069
SNT TRC
FID C 3 6071
FID C 3 6072
SNT TRC
FID C 3 6073
FID C 3 6074
FID C 3 6075
FID C 3 6076
FID C 3 6077
SNT TRC
FID C 3 6078
FID C 3 6079
SNT TRC
FID C 3 6082
FID C 3 6083
SNT TRC
FID C 3 6084
SNT TRC
FID C 3 6086
SNT TRC
FID C 3 6097
FID C 3 6098
FID C 3 6099
SNT TRC
FID C 8 4419
FID C 8 4420
SNT TRC
FID C 8 4423
FID C 8 4424
SNT TRC
FID C 3 6101
FID C 3 6102
SNT TRC
FID C 8 4425
FID C 8 4426
SNT TRC
FID C 8 4427
FID C 8 4428
SNT TRC
FID C 8 4430
FID C 8 4431
SNT TRC
FID C 8 4433
FID C 8 4434
SNT TRC
FID C 8 4436
FID C 8 4437
SNT TRC
FID C 8 4438
FID C 8 4439
SNT TRC
FID C 8 4440
FID C 8 4441
SNT TRC
FID C 8 4443
FID C 8 4444
SNT TRC
FID C 8 4447
SNT TRC
FID C 8 4449
SNT TRC
FID C 8 4451
SNT TRC
FID C 3 6103
FID C 3 6104
FID C 3 6105
SNT TRC
FID C 3 6106
SNT TRC
FID C 3 6107
SNT TRC
FID C 3 6109
FID C 3 6110
SNT TRC
FID C 8 4452
FID C 8 4453
SNT TRC
FID C 8 4455
FID C 8 4456
FID C 8 4457
SNT TRC
FID C 8 4460
SNT TRC
FID C 8 4461
FID C 8 4462
SNT TRC
FID C 8 4465
SNT TRC
FID C 8 4467
FID C 8 4468
SNT TRC
FID C 8 4471
FID C 8 4472
SNT TRC
FID C 3 6112
SNT TRC
FID C 3 6116
FID C 3 6117
SNT PLN S C 0
FID C 3 6118
SNT PLN S C 0
FID C 3 6119
SNT PLN S C 0
FID C 3 6120
SNT TRC
FID C 3 6121
FID C 3 6122
FID C 3 6123
FID C 3 6124
SNT PLN S C 0
FID C 3 6125
SNT PLN S C 0
FID C 3 6126
SNT PLN S C 0
FID C 3 6127
SNT PLN S C 0
FID C 8 4476
SNT PLN S C 0
FID C 3 6128
SNT PLN S C 0
FID C 3 6129
SNT PLN S C 0
FID C 3 6130
SNT PLN S C 0
FID C 3 6131
SNT PLN S C 0
FID C 3 6132
SNT PLN S C 0
FID C 8 4477
SNT PLN S C 0
FID C 3 6133
SNT PLN S C 0
FID C 8 4478
SNT PLN S C 0
FID C 3 6134
SNT PLN S C 0
FID C 3 6135
SNT PLN S C 0
FID C 8 4479
SNT PLN S C 0
FID C 8 4480
SNT PLN S C 0
FID C 8 4481
SNT PLN S C 0
FID C 8 4482
SNT PLN S C 0
FID C 8 4483
SNT PLN S C 0
FID C 3 6136
SNT PLN S C 0
FID C 8 4484
SNT PLN S C 0
FID C 3 6137
SNT PLN S C 0
FID C 3 6138
SNT PLN S C 0
FID C 8 4485
SNT PLN S C 0
FID C 3 6139
SNT PLN S C 0
FID C 8 4486
SNT PLN S C 0
FID C 8 4487
SNT PLN S C 0
FID C 3 6140
SNT TRC
FID C 3 6178
FID C 3 6179
SNT TRC
FID C 3 6181
FID C 3 6182
SNT TRC
FID C 3 6185
FID C 3 6186
SNT TRC
FID C 3 6187
FID C 3 6188
FID C 3 6189
FID C 3 6190
SNT TRC
FID C 8 4525
FID C 8 4526
SNT TRC
FID C 3 6191
FID C 3 6192
FID C 3 6193
SNT TRC
FID C 3 6194
FID C 3 6195
SNT TRC
FID C 8 4529
FID C 8 4530
SNT TRC
FID C 8 4532
FID C 8 4533
SNT TRC
FID C 8 4534
SNT TRC
FID C 3 6199
SNT TRC
FID C 3 6200
SNT TRC
FID C 3 6201
SNT TRC
FID C 3 6204
FID C 3 6205
SNT TRC
FID C 3 6206
FID C 3 6207
SNT TRC
FID C 3 6208
FID C 3 6209
SNT TRC
FID C 3 6210
SNT TRC
FID C 3 6213
SNT TRC
FID C 8 4544
FID C 8 4545
SNT TRC
FID C 3 6216
SNT TRC
FID C 3 6217
SNT TRC
FID C 3 6220
FID C 3 6221
FID C 3 6222
FID C 3 6223
SNT TRC
FID C 8 4547
FID C 8 4548
FID C 8 4549
SNT TRC
FID C 3 6236
FID C 3 6237
SNT TRC
FID C 3 6239
FID C 3 6240
SNT TRC
FID C 3 6242
FID C 3 6243
SNT TRC
FID C 3 6244
FID C 3 6245
SNT TRC
FID C 8 4567
FID C 8 4568
SNT TRC
FID C 8 4570
SNT TRC
FID C 8 4571
SNT TRC
FID C 3 6264
SNT TRC
FID C 3 6266
SNT TRC
FID C 3 6279
SNT TRC
FID C 8 4580
FID C 8 4581
SNT TRC
FID C 8 4583
FID C 8 4584
SNT TRC
FID C 8 4586
FID C 8 4587
SNT TRC
FID C 8 4590
SNT TRC
FID C 8 4592
FID C 8 4593
SNT TRC
FID C 8 4595
SNT TRC
FID C 3 6283
FID C 3 6284
SNT TRC
FID C 3 6286
FID C 3 6287
SNT TRC
FID C 8 4600
FID C 8 4601
FID C 8 4602
SNT TRC
FID C 8 4603
FID C 8 4604
SNT TRC
FID C 8 4605
SNT TRC
FID C 3 6291
SNT TRC
FID C 3 6292
FID C 3 6293
FID C 3 6294
FID C 3 6295
SNT TRC
FID C 3 6296
SNT TRC
FID C 3 6297
SNT TRC
FID C 3 6298
FID C 3 6299
SNT TRC
FID C 3 6300
FID C 3 6301
FID C 3 6302
SNT TRC
FID C 3 6303
FID C 3 6304
FID C 3 6305
FID C 3 6306
SNT TRC
FID C 3 6307
FID C 3 6308
FID C 3 6309
FID C 3 6310
FID C 3 6311
SNT TRC
FID C 8 4607
SNT TRC
FID C 8 4608
SNT TRC
FID C 3 6321
SNT TRC
FID C 8 4615
SNT TRC
FID C 8 4616
FID C 8 4617
SNT TRC
FID C 3 6322
FID C 3 6323
FID C 3 6324
SNT TRC
FID C 3 6325
FID C 3 6326
SNT TRC
FID C 3 6327
FID C 3 6328
FID C 3 6329
SNT TRC
FID C 3 6330
SNT TRC
FID C 3 6331
FID C 3 6332
FID C 3 6333
SNT TRC
FID C 3 6336
SNT TRC
FID C 3 6339
FID C 3 6340
SNT TRC
FID C 8 4622
SNT TRC
FID C 3 6343
SNT TRC
FID C 8 4623
SNT TRC
FID C 3 6344
SNT TRC
FID C 8 4624
SNT TRC
FID C 8 4625
SNT TRC
FID C 3 6345
FID C 3 6346
FID C 3 6347
SNT TRC
FID C 8 4626
SNT TRC
FID C 8 4627
FID C 8 4628
SNT TRC
FID C 8 4632
FID C 8 4633
FID C 8 4634
FID C 8 4635
SNT TRC
FID C 8 4636
FID C 8 4637
FID C 8 4638
SNT TRC
FID C 3 6350
FID C 3 6351
SNT TRC
FID C 3 6353
SNT TRC
FID C 8 4640
FID C 8 4641
FID C 8 4642
FID C 8 4643
SNT TRC
FID C 8 4644
FID C 8 4645
FID C 8 4646
SNT TRC
FID C 3 6354
FID C 3 6355
SNT TRC
FID C 3 6358
FID C 3 6359
FID C 3 6360
SNT TRC
FID C 3 6363
SNT TRC
FID C 3 6365
FID C 3 6366
SNT TRC
FID C 3 6369
FID C 3 6370
SNT TRC
FID C 3 6374
SNT TRC
FID C 3 6376
FID C 3 6377
FID C 3 6378
FID C 3 6379
FID C 3 6380
SNT TRC
FID C 3 6381
FID C 3 6382
FID C 3 6383
SNT TRC
FID C 3 6384
FID C 3 6385
SNT TRC
FID C 3 6387
SNT TRC
FID C 3 6388
FID C 3 6389
FID C 3 6390
SNT TRC
FID C 3 6392
SNT TRC
FID C 8 4663
FID C 8 4664
SNT TRC
FID C 3 6402
SNT TRC
FID C 3 6411
SNT TRC
FID C 3 6412
SNT TRC
FID C 3 6415
SNT PLN S C 0
FID C 3 6416
SNT TRC
FID C 3 6417
FID C 3 6418
SNT TRC
FID C 3 6420
FID C 3 6421
FID C 3 6422
SNT TRC
FID C 8 4671
SNT TRC
FID C 3 6424
SNT TRC
FID C 3 6427
FID C 3 6428
SNT TRC
FID C 3 6429
SNT TRC
FID C 3 6430
SNT TRC
FID C 3 6434
FID C 3 6435
FID C 3 6436
SNT TRC
FID C 3 6437
SNT TRC
FID C 3 6439
SNT TRC
FID C 3 6444
FID C 3 6445
SNT TRC
FID C 3 6449
SNT TRC
FID C 3 6453
SNT TRC
FID C 8 4684
FID C 8 4685
SNT TRC
FID C 8 4687
SNT TRC
FID C 8 4689
FID C 8 4690
SNT TRC
FID C 8 4692
FID C 8 4693
SNT TRC
FID C 8 4694
FID C 8 4695
SNT TRC
FID C 3 6454
FID C 3 6455
FID C 3 6456
FID C 3 6457
SNT TRC
FID C 3 6458
FID C 3 6459
SNT TRC
FID C 3 6460
FID C 3 6461
SNT TRC
FID C 8 4698
SNT TRC
FID C 3 6467
FID C 3 6468
SNT TRC
FID C 3 6469
FID C 3 6470
SNT TRC
FID C 8 4708
FID C 8 4709
SNT TRC
FID C 3 6471
FID C 3 6472
SNT TRC
FID C 3 6477
FID C 3 6478
SNT TRC
FID C 3 6484
FID C 3 6485
SNT TRC
FID C 3 6489
SNT TRC
FID C 3 6493
SNT TRC
FID C 8 4729
FID C 8 4730
SNT TRC
FID C 3 6498
SNT TRC
FID C 8 4731
SNT TRC
FID C 8 4733
FID C 8 4734
SNT TRC
FID C 3 6500
FID C 3 6501
FID C 3 6502
SNT TRC
FID C 8 4735
SNT TRC
FID C 8 4736
SNT TRC
FID C 8 4739
SNT TRC
FID C 8 4740
SNT TRC
FID C 8 4742
SNT TRC
FID C 8 4744
SNT TRC
FID C 8 4746
SNT TRC
FID C 8 4748
SNT TRC
FID C 8 4750
SNT TRC
FID C 8 4753
SNT TRC
FID C 3 6505
FID C 3 6506
FID C 3 6507
SNT TRC
FID C 8 4756
FID C 8 4757
SNT TRC
FID C 3 6513
SNT TRC
FID C 3 6516
SNT TRC
FID C 8 4760
FID C 8 4761
SNT TRC
FID C 3 6519
SNT TRC
FID C 8 4767
SNT TRC
FID C 8 4770
SNT TRC
FID C 3 6530
SNT TRC
FID C 3 6543
SNT TRC
FID C 3 6546
SNT TRC
FID C 3 6549
SNT TRC
FID C 3 6551
SNT TRC
FID C 3 6552
SNT TRC
FID C 3 6554
SNT TRC
FID C 3 6559
FID C 3 6560
SNT TRC
FID C 3 6563
SNT TRC
FID C 3 6572
SNT TRC
FID C 3 6574
SNT TRC
FID C 3 6577
SNT TRC
FID C 3 6578
SNT TRC
FID C 3 6580
SNT TRC
FID C 3 6582
SNT TRC
FID C 3 6585
SNT TRC
FID C 3 6587
FID C 3 6588
FID C 3 6589
SNT TRC
FID C 3 6590
SNT TRC
FID C 3 6591
FID C 3 6592
FID C 3 6593
FID C 3 6594
SNT TRC
FID C 3 6595
SNT TRC
FID C 3 6596
FID C 3 6597
SNT TRC
FID C 8 4797
SNT TRC
FID C 8 4798
FID C 8 4799
SNT TRC
FID C 8 4810
FID C 8 4811
SNT TRC
FID C 8 4812
SNT TRC
FID C 8 4815
SNT TRC
FID C 3 6615
SNT TRC
FID C 3 6622
SNT TRC
FID C 3 6629
SNT TRC
FID C 3 6631
SNT TRC
FID C 8 4835
SNT TRC
FID C 8 4837
FID C 8 4838
FID C 8 4839
SNT TRC
FID C 8 4850
FID C 8 4851
SNT TRC
FID C 3 6651
FID C 3 6652
SNT TRC
FID C 3 6664
FID C 3 6665
SNT TRC
FID C 3 6667
FID C 3 6668
FID C 3 6669
SNT TRC
FID C 8 4969
FID C 8 4970
SNT TRC
FID C 8 4971
FID C 8 4972
SNT TRC
FID C 8 4973
FID C 8 4974
SNT TRC
FID C 3 6776
FID C 3 6777
SNT TRC
FID C 8 4975
FID C 8 4976
SNT TRC
FID C 8 4977
FID C 8 4978
SNT TRC
FID C 8 4979
FID C 8 4980
SNT TRC
FID C 8 4981
FID C 8 4982
SNT TRC
FID C 8 4983
FID C 8 4984
SNT TRC
FID C 8 4985
FID C 8 4986
SNT TRC
FID C 8 4987
FID C 8 4988
SNT TRC
FID C 8 4989
FID C 8 4990
SNT TRC
FID C 8 4991
FID C 8 4992
SNT TRC
FID C 8 4993
FID C 8 4994
SNT TRC
FID C 8 4995
FID C 8 4996
SNT TRC
FID C 8 4997
FID C 8 4998
SNT TRC
FID C 8 4999
FID C 8 5000
SNT TRC
FID C 8 5001
FID C 8 5002
FID C 8 5003
SNT TRC
FID C 8 5004
FID C 8 5005
SNT TRC
FID C 8 5006
FID C 8 5007
SNT TRC
FID C 8 5008
FID C 8 5009
FID C 8 5010
SNT TRC
FID C 8 5011
FID C 8 5012
SNT TRC
FID C 8 5013
FID C 8 5014
SNT TRC
FID C 8 5015
SNT TRC
FID C 8 5016
FID C 8 5017
SNT TRC
FID C 8 5018
FID C 8 5019
SNT TRC
FID C 8 5020
FID C 8 5021
SNT TRC
FID C 8 5022
FID C 8 5023
SNT TRC
FID C 8 5024
FID C 8 5025
SNT TRC
FID C 8 5026
FID C 8 5027
SNT TRC
FID C 8 5028
FID C 8 5029
SNT TRC
FID C 8 5030
FID C 8 5031
SNT TRC
FID C 8 5032
FID C 8 5033
SNT TRC
FID C 8 5034
FID C 8 5035
SNT TRC
FID C 8 5036
FID C 8 5037
SNT TRC
FID C 8 5038
FID C 8 5039
SNT TRC
FID C 8 5040
FID C 8 5041
SNT TRC
FID C 8 5042
SNT TRC
FID C 8 5043
FID C 8 5044
SNT TRC
FID C 3 6778
FID C 3 6779
FID C 3 6780
SNT TRC
FID C 3 6781
FID C 3 6782
SNT TRC
FID C 3 6783
FID C 3 6784
SNT PLN S C 0
FID C 3 6785
SNT PLN S C 0
FID C 8 5045
SNT PLN S C 0
FID C 3 6786
SNT PLN S C 0
FID C 3 6787
SNT PLN S C 0
FID C 8 5046
SNT PLN S C 0
FID C 8 5047
SNT PLN S C 0
FID C 3 6788
SNT PLN S C 0
FID C 8 5048
SNT PLN S C 0
FID C 3 6789
SNT PLN S C 0
FID C 8 5049
SNT TRC
FID C 3 6891
FID C 3 6892
SNT TRC
FID C 3 6907
SNT TRC
FID C 3 6910
FID C 3 6911
FID C 3 6912
FID C 3 6913
SNT TRC
FID C 3 6915
SNT TRC
FID C 3 6918
SNT TRC
FID C 3 6921
SNT TRC
FID C 8 5164
SNT TRC
FID C 3 6942
FID C 3 6943
FID C 3 6944
FID C 3 6945
SNT TRC
FID C 3 6948
FID C 3 6949
FID C 3 6950
SNT TRC
FID C 8 5172
FID C 8 5173
SNT TRC
FID C 3 6953
FID C 3 6954
SNT TRC
FID C 3 6957
FID C 3 6958
FID C 3 6959
SNT TRC
FID C 8 5209
SNT TRC
FID C 8 5263
SNT TRC
FID C 8 5265
SNT PLN S C 0
FID C 3 7052
SNT PLN S C 0
FID C 8 5271
SNT PLN S C 0
FID C 8 5272
SNT PLN S C 0
FID C 3 7053
SNT TRC
FID C 8 5287
FID C 8 5288
SNT TRC
FID C 8 5292
SNT TRC
FID C 8 5294
SNT TRC
FID C 3 7072
SNT TRC
FID C 3 7073
SNT TRC
FID C 3 7076
SNT TRC
FID C 3 7077
FID C 3 7078
SNT TRC
FID C 3 7079
SNT TRC
FID C 3 7080
FID C 3 7081
FID C 3 7082
FID C 3 7083
SNT TRC
FID C 8 5298
FID C 8 5299
SNT TRC
FID C 8 5300
FID C 8 5301
SNT TRC
FID C 3 7084
FID C 3 7085
FID C 3 7086
SNT PLN S C 0
FID C 8 5307
SNT PLN S C 0
FID C 8 5308
SNT PLN S C 0
FID C 8 5309
SNT PLN S C 0
FID C 8 5310
SNT PLN S C 0
FID C 8 5311
SNT PLN S C 0
FID C 3 7096
SNT PLN S C 0
FID C 3 7097
SNT PLN S C 0
FID C 3 7098
SNT PLN S C 0
FID C 3 7099
SNT PLN S C 0
FID C 8 5312
SNT PLN S C 0
FID C 3 7100
SNT PLN S C 0
FID C 3 7101
SNT PLN S C 0
FID C 8 5313
SNT TRC
FID C 8 5520
SNT TRC
FID C 8 5525
SNT TRC
FID C 8 5527
FID C 8 5528
SNT TRC
FID C 8 5530
FID C 8 5531
FID C 8 5532
SNT TRC
FID C 3 7313
SNT TRC
FID C 8 5540
SNT TRC
FID C 8 5546
SNT TRC
FID C 8 5549
FID C 8 5550
FID C 8 5551
SNT TRC
FID C 3 7320
FID C 3 7321
SNT TRC
FID C 3 7333
FID C 3 7334
FID C 3 7335
SNT TRC
FID C 3 7338
SNT TRC
FID C 8 5570
SNT TRC
FID C 8 5573
SNT TRC
FID C 3 7348
FID C 3 7349
SNT TRC
FID C 8 5576
SNT TRC
FID C 3 7351
SNT TRC
FID C 3 7352
SNT TRC
FID C 8 5580
SNT TRC
FID C 3 7359
SNT TRC
FID C 8 5585
SNT TRC
FID C 8 5587
SNT TRC
FID C 3 7365
SNT TRC
FID C 8 5591
SNT TRC
FID C 8 5594
SNT TRC
FID C 8 5602
SNT TRC
FID C 3 7380
SNT TRC
FID C 3 7382
FID C 3 7383
SNT TRC
FID C 8 5604
FID C 8 5605
SNT TRC
FID C 8 5606
FID C 8 5607
SNT TRC
FID C 3 7388
FID C 3 7389
SNT TRC
FID C 3 7390
FID C 3 7391
FID C 3 7392
SNT TRC
FID C 8 5616
FID C 8 5617
SNT TRC
FID C 3 7407
FID C 3 7408
FID C 3 7409
FID C 3 7410
SNT TRC
FID C 3 7412
FID C 3 7413
SNT TRC
FID C 3 7416
SNT TRC
FID C 3 7427
SNT TRC
FID C 8 5655
FID C 8 5656
SNT TRC
FID C 3 7455
SNT TRC
FID C 3 7461
FID C 3 7462
SNT TRC
FID C 8 5670
FID C 8 5671
SNT TRC
FID C 3 7464
SNT TRC
FID C 8 5673
FID C 8 5674
FID C 8 5675
SNT TRC
FID C 3 7466
SNT TRC
FID C 3 7467
SNT TRC
FID C 3 7468
SNT TRC
FID C 8 5681
SNT TRC
FID C 8 5684
SNT TRC
FID C 8 5698
FID C 8 5699
SNT TRC
FID C 8 5701
FID C 8 5702
SNT TRC
FID C 8 5708
SNT TRC
FID C 8 5715
SNT TRC
FID C 8 5718
SNT TRC
FID C 8 5720
FID C 8 5721
SNT TRC
FID C 8 5736
SNT TRC
FID C 8 5738
SNT TRC
FID C 8 5740
SNT TRC
FID C 3 7473
SNT TRC
FID C 3 7475
SNT TRC
FID C 3 7477
SNT TRC
FID C 3 7479
SNT TRC
FID C 3 7481
SNT TRC
FID C 3 7483
SNT TRC
FID C 3 7485
SNT TRC
FID C 3 7487
SNT TRC
FID C 3 7489
SNT TRC
FID C 3 7491
SNT TRC
FID C 3 7493
SNT TRC
FID C 3 7495
SNT TRC
FID C 3 7497
SNT TRC
FID C 3 7499
SNT TRC
FID C 3 7501
SNT TRC
FID C 3 7503
SNT TRC
FID C 3 7505
SNT TRC
FID C 3 7507
SNT TRC
FID C 3 7509
SNT TRC
FID C 3 7511
SNT TRC
FID C 3 7513
SNT TRC
FID C 3 7515
SNT TRC
FID C 3 7517
SNT TRC
FID C 3 7519
SNT TRC
FID C 3 7521
SNT TRC
FID C 3 7523
SNT TRC
FID C 3 7525
SNT TRC
FID C 3 7527
SNT TRC
FID C 3 7529
SNT TRC
FID C 3 7531
SNT TRC
FID C 3 7533
SNT TRC
FID C 3 7535
SNT TRC
FID C 3 7537
SNT TRC
FID C 3 7539
SNT TRC
FID C 3 7541
SNT TRC
FID C 3 7543
SNT TRC
FID C 3 7545
SNT TRC
FID C 3 7547
SNT TRC
FID C 3 7549
SNT TRC
FID C 3 7551
SNT TRC
FID C 3 7553
SNT TRC
FID C 3 7555
SNT TRC
FID C 3 7557
SNT TRC
FID C 3 7559
SNT TRC
FID C 3 7561
SNT TRC
FID C 3 7563
SNT TRC
FID C 3 7565
SNT TRC
FID C 3 7567
SNT TRC
FID C 3 7569
SNT TRC
FID C 3 7571
SNT TRC
FID C 3 7573
SNT TRC
FID C 3 7575
SNT TRC
FID C 3 7577
SNT TRC
FID C 3 7579
SNT TRC
FID C 3 7581
SNT TRC
FID C 3 7583
SNT TRC
FID C 3 7585
SNT TRC
FID C 3 7587
SNT TRC
FID C 3 7589
SNT TRC
FID C 3 7591
SNT TRC
FID C 3 7593
SNT TRC
FID C 3 7595
SNT TRC
FID C 3 7597
SNT TRC
FID C 3 7599
SNT TRC
FID C 3 7601
SNT TRC
FID C 3 7603
SNT TRC
FID C 3 7605
SNT TRC
FID C 3 7607
SNT TRC
FID C 3 7609
SNT TRC
FID C 3 7611
SNT TRC
FID C 3 7613
SNT TRC
FID C 3 7615
SNT TRC
FID C 3 7617
SNT TRC
FID C 3 7619
SNT TRC
FID C 3 7621
SNT TRC
FID C 3 7623
SNT TRC
FID C 3 7625
SNT TRC
FID C 3 7627
SNT TRC
FID C 3 7629
SNT TRC
FID C 3 7631
SNT TRC
FID C 3 7633
SNT TRC
FID C 3 7635
SNT TRC
FID C 3 7637
SNT TRC
FID C 3 7639
SNT TRC
FID C 3 7641
SNT TRC
FID C 3 7643
SNT TRC
FID C 3 7645
SNT TRC
FID C 3 7647
SNT TRC
FID C 3 7649
SNT TRC
FID C 3 7651
SNT TRC
FID C 3 7652
FID C 3 7653
SNT PLN S C 0
FID C 8 5743
SNT TRC
FID C 3 7657
SNT TRC
FID C 3 7658
SNT TRC
FID C 3 7662
FID C 3 7663
SNT TRC
FID C 8 5747
SNT TRC
FID C 3 7682
SNT TRC
FID C 3 7701
SNT TRC
FID C 3 7702
FID C 3 7703
SNT TRC
FID C 3 7712
SNT TRC
FID C 3 7715
FID C 3 7716
SNT TRC
FID C 8 5776
FID C 8 5777
SNT TRC
FID C 8 5780
SNT TRC
FID C 3 7721
FID C 3 7722
SNT TRC
FID C 8 5790
SNT TRC
FID C 3 7731
SNT TRC
FID C 3 7733
FID C 3 7734
SNT TRC
FID C 8 5793
FID C 8 5794
SNT TRC
FID C 3 7739
FID C 3 7740
FID C 3 7741
FID C 3 7742
SNT TRC
FID C 8 5801
SNT TRC
FID C 3 7749
SNT TRC
FID C 3 7751
SNT TRC
FID C 3 7753
SNT TRC
FID C 3 7763
FID C 3 7764
SNT TRC
FID C 8 5812
FID C 8 5813
SNT TRC
FID C 8 5825
SNT TRC
FID C 3 7781
SNT PLN S C 0
FID C 8 5831
SNT PLN S C 0
FID C 3 7789
SNT PLN S C 0
FID C 8 5833
SNT TRC
FID C 3 7803
FID C 3 7804
SNT TRC
FID C 8 5836
FID C 8 5837
FID C 8 5838
SNT PLN S C 0
FID C 3 7816
SNT PLN S C 0
FID C 8 5846
SNT TRC
FID C 8 5868
FID C 8 5869
SNT TRC
FID C 8 5872
SNT TRC
FID C 8 5873
SNT TRC
FID C 8 5876
SNT TRC
FID C 8 5879
FID C 8 5880
FID C 8 5881
SNT TRC
FID C 3 7845
SNT TRC
FID C 3 7848
SNT TRC
FID C 8 5885
SNT TRC
FID C 3 7851
SNT TRC
FID C 8 5889
SNT TRC
FID C 8 5891
SNT TRC
FID C 8 5894
SNT TRC
FID C 3 7856
SNT TRC
FID C 3 7858
SNT TRC
FID C 8 5896
SNT TRC
FID C 8 5899
FID C 8 5900
SNT TRC
FID C 8 5902
# NET 3
NET XP12R0V 
SNT TOP T 103 0
FID H 0 178
FID C 6 1485
FID C 3 5413
FID C 8 3815
FID L 11 1258
FID L 12 1258
FID L 14 1039
FID L 15 1258
FID L 16 1258
SNT TOP T 157 0
FID C 4 2161
FID C 5 1286
FID C 3 5412
SNT TOP T 158 0
FID C 4 2151
FID C 5 1282
FID C 3 5398
SNT TOP T 159 0
FID C 4 2165
FID C 5 1288
FID C 3 5417
SNT TOP T 176 1
FID C 4 2182
FID C 5 1299
FID C 3 5436
SNT TOP T 189 12
FID C 4 2166
FID C 5 1289
FID C 3 5420
SNT TOP T 189 13
FID C 4 2167
FID C 5 1290
FID C 3 5421
SNT TOP T 189 14
FID C 4 2168
FID C 5 1291
FID C 3 5422
SNT TOP T 189 15
FID C 4 2169
FID C 5 1292
FID C 3 5423
SNT TOP T 189 16
FID C 4 2170
FID C 5 1293
FID C 3 5424
SNT TOP T 189 17
FID C 4 2171
FID C 5 1294
FID C 3 5425
SNT TOP T 189 18
FID C 4 2172
FID C 5 1295
FID C 3 5426
SNT TOP T 189 19
FID C 4 2173
FID C 5 1296
FID C 3 5427
SNT TOP T 332 0
FID C 4 2156
FID C 5 1284
FID C 3 5406
SNT TOP T 336 0
FID C 4 2154
FID C 5 1283
FID C 3 5401
SNT TOP T 478 0
FID C 4 2177
FID C 5 1297
FID C 3 5431
SNT TOP T 479 0
FID C 4 2181
FID C 5 1298
FID C 3 5435
SNT TOP T 543 0
FID C 4 2157
FID C 5 1285
FID C 3 5408
SNT TOP T 570 0
FID C 4 2150
FID C 5 1281
FID C 3 5397
SNT TOP T 583 0
FID C 4 2162
FID C 5 1287
FID C 3 5414
SNT TOP B 105 1
FID C 6 1488
FID C 7 524
FID C 8 3819
SNT TOP B 321 1
FID C 6 1478
FID C 7 523
FID C 8 3807
SNT VIA
FID H 0 744
FID C 4 2158
FID C 6 1482
FID C 3 5409
FID C 8 3812
FID L 11 1255
FID L 12 1255
FID L 14 1036
FID L 15 1255
FID L 16 1255
SNT VIA
FID H 0 745
FID C 4 2160
FID C 6 1484
FID C 3 5411
FID C 8 3814
FID L 11 1257
FID L 12 1257
FID L 14 1038
FID L 15 1257
FID L 16 1257
SNT VIA
FID H 0 746
FID C 4 2146
FID C 6 1474
FID C 3 5393
FID C 8 3803
FID L 11 1248
FID L 12 1248
FID L 14 1029
FID L 15 1248
FID L 16 1248
SNT VIA
FID H 0 747
FID C 4 2147
FID C 6 1475
FID C 3 5394
FID C 8 3804
FID L 11 1249
FID L 12 1249
FID L 14 1030
FID L 15 1249
FID L 16 1249
SNT VIA
FID H 0 748
FID C 4 2148
FID C 6 1476
FID C 3 5395
FID C 8 3805
FID L 11 1250
FID L 12 1250
FID L 14 1031
FID L 15 1250
FID L 16 1250
SNT VIA
FID H 0 749
FID C 4 2149
FID C 6 1477
FID C 3 5396
FID C 8 3806
FID L 11 1251
FID L 12 1251
FID L 14 1032
FID L 15 1251
FID L 16 1251
SNT VIA
FID H 0 750
FID C 4 2164
FID C 6 1487
FID C 3 5416
FID C 8 3817
FID L 11 1260
FID L 12 1260
FID L 14 1041
FID L 15 1260
FID L 16 1260
SNT VIA
FID H 0 751
FID C 4 2163
FID C 6 1486
FID C 3 5415
FID C 8 3816
FID L 11 1259
FID L 12 1259
FID L 14 1040
FID L 15 1259
FID L 16 1259
SNT VIA
FID H 0 752
FID C 4 2178
FID C 6 1492
FID C 3 5432
FID C 8 3823
FID L 11 1264
FID L 12 1264
FID L 14 1045
FID L 15 1264
FID L 16 1264
SNT VIA
FID H 0 753
FID C 4 2180
FID C 6 1494
FID C 3 5434
FID C 8 3825
FID L 11 1266
FID L 12 1266
FID L 14 1047
FID L 15 1266
FID L 16 1266
SNT VIA
FID H 0 754
FID C 4 2179
FID C 6 1493
FID C 3 5433
FID C 8 3824
FID L 11 1265
FID L 12 1265
FID L 14 1046
FID L 15 1265
FID L 16 1265
SNT VIA
FID H 0 755
FID C 4 2176
FID C 6 1491
FID C 3 5430
FID C 8 3822
FID L 11 1263
FID L 12 1263
FID L 14 1044
FID L 15 1263
FID L 16 1263
SNT VIA
FID H 0 756
FID C 4 2175
FID C 6 1490
FID C 3 5429
FID C 8 3821
FID L 11 1262
FID L 12 1262
FID L 14 1043
FID L 15 1262
FID L 16 1262
SNT VIA
FID H 0 757
FID C 4 2152
FID C 6 1479
FID C 3 5399
FID C 8 3809
FID L 11 1252
FID L 12 1252
FID L 14 1033
FID L 15 1252
FID L 16 1252
SNT VIA
FID H 0 758
FID C 4 2155
FID C 6 1481
FID C 3 5404
FID C 8 3811
FID L 11 1254
FID L 12 1254
FID L 14 1035
FID L 15 1254
FID L 16 1254
SNT VIA
FID H 0 1344
FID C 4 2174
FID C 6 1489
FID C 3 5428
FID C 8 3820
FID L 11 1261
FID L 12 1261
FID L 14 1042
FID L 15 1261
FID L 16 1261
SNT VIA
FID H 0 1345
FID C 4 2153
FID C 6 1480
FID C 3 5400
FID C 8 3810
FID L 11 1253
FID L 12 1253
FID L 14 1034
FID L 15 1253
FID L 16 1253
SNT VIA
FID H 0 2288
FID C 4 2159
FID C 6 1483
FID C 3 5410
FID C 8 3813
FID L 11 1256
FID L 12 1256
FID L 14 1037
FID L 15 1256
FID L 16 1256
SNT PLN S C 0
SNT PLN S C 0
FID C 3 5392
SNT TRC
FID C 8 3808
SNT TRC
FID C 3 5402
FID C 3 5403
SNT TRC
FID C 3 5405
SNT PLN S C 0
FID C 3 5407
SNT PLN S C 0
FID C 3 5418
SNT PLN S C 0
FID C 3 5419
SNT PLN S C 0
FID C 8 3818
# NET 4
NET XP3R3V_VPLL 
SNT TOP T 13 8
FID C 4 226
FID C 5 200
FID C 3 643
SNT TOP B 2 1
FID C 6 62
FID C 7 24
FID C 8 249
SNT TOP B 97 0
FID C 6 60
FID C 7 22
FID C 8 247
SNT TOP B 439 0
FID C 6 61
FID C 7 23
FID C 8 248
SNT VIA
FID H 0 1395
FID C 4 227
FID C 6 63
FID C 3 644
FID C 8 250
FID L 11 179
FID L 12 179
FID L 13 179
FID L 14 179
FID L 15 179
FID L 16 179
SNT PLN S C 0
FID C 8 246
SNT TRC
FID C 3 640
FID C 3 641
FID C 3 642
# NET 5
NET XP3R3V_VPHY 
SNT TOP T 13 3
FID C 4 229
FID C 5 201
FID C 3 649
SNT TOP B 1 1
FID C 6 67
FID C 7 27
FID C 8 260
SNT TOP B 98 0
FID C 6 65
FID C 7 25
FID C 8 258
SNT TOP B 392 0
FID C 6 66
FID C 7 26
FID C 8 259
SNT VIA
FID H 0 1394
FID C 4 228
FID C 6 64
FID C 3 648
FID C 8 257
FID L 11 180
FID L 12 180
FID L 13 180
FID L 14 180
FID L 15 180
FID L 16 180
SNT TRC
FID C 8 251
FID C 8 252
SNT TRC
FID C 3 645
FID C 3 646
FID C 3 647
SNT TRC
FID C 8 253
SNT TRC
FID C 8 254
FID C 8 255
FID C 8 256
# NET 6
NET FPGA_MGTAVTT 
SNT TOP T 170 70
FID C 4 1959
FID C 5 1177
FID C 3 4980
SNT TOP T 170 72
FID C 4 1956
FID C 5 1174
FID C 3 4972
SNT TOP T 170 74
FID C 4 1957
FID C 5 1175
FID C 3 4975
SNT TOP T 170 76
FID C 4 1953
FID C 5 1172
FID C 3 4964
SNT TOP T 170 91
FID C 4 1958
FID C 5 1176
FID C 3 4978
SNT TOP T 170 95
FID C 4 1955
FID C 5 1173
FID C 3 4969
SNT TOP B 31 0
FID C 6 1335
FID C 7 473
FID C 8 3539
SNT TOP B 32 0
FID C 6 1330
FID C 7 469
FID C 8 3525
SNT TOP B 33 0
FID C 6 1337
FID C 7 475
FID C 8 3545
SNT TOP B 34 0
FID C 6 1336
FID C 7 474
FID C 8 3542
SNT TOP B 83 0
FID C 6 1334
FID C 7 472
FID C 8 3537
SNT TOP B 91 0
FID C 6 1342
FID C 7 476
FID C 8 3552
SNT TOP B 123 0
FID C 6 1333
FID C 7 471
FID C 8 3533
SNT TOP B 357 0
FID C 6 1343
FID C 7 477
FID C 8 3553
SNT TOP B 389 0
FID C 6 1331
FID C 7 470
FID C 8 3526
SNT VIA
FID H 0 249
FID C 4 1954
FID C 6 1332
FID C 3 4966
FID C 8 3529
FID L 11 1143
FID L 12 1143
FID L 13 996
FID L 15 1143
FID L 16 1143
SNT VIA
FID H 0 250
FID C 4 1962
FID C 6 1340
FID C 3 4984
FID C 8 3550
FID L 11 1151
FID L 12 1151
FID L 13 1004
FID L 15 1151
FID L 16 1151
SNT VIA
FID H 0 251
FID C 4 1963
FID C 6 1341
FID C 3 4985
FID C 8 3551
FID L 11 1152
FID L 12 1152
FID L 13 1005
FID L 15 1152
FID L 16 1152
SNT VIA
FID H 0 252
FID C 4 1961
FID C 6 1339
FID C 3 4983
FID C 8 3549
FID L 11 1150
FID L 12 1150
FID L 13 1003
FID L 15 1150
FID L 16 1150
SNT VIA
FID H 0 1144
FID C 4 1960
FID C 6 1338
FID C 3 4982
FID C 8 3548
FID L 11 1149
FID L 12 1149
FID L 13 1002
FID L 15 1149
FID L 16 1149
SNT VIA
FID H 0 2356
FID C 3 4979
FID C 8 3547
FID L 11 1148
FID L 12 1148
FID L 13 1001
FID L 15 1148
FID L 16 1148
SNT VIA
FID H 0 2357
FID C 3 4970
FID C 8 3538
FID L 11 1145
FID L 12 1145
FID L 13 998
FID L 15 1145
FID L 16 1145
SNT VIA
FID H 0 2358
FID C 3 4973
FID C 8 3541
FID L 11 1146
FID L 12 1146
FID L 13 999
FID L 15 1146
FID L 16 1146
SNT VIA
FID H 0 2359
FID C 3 4965
FID C 8 3523
FID L 11 1142
FID L 12 1142
FID L 13 995
FID L 15 1142
FID L 16 1142
SNT VIA
FID H 0 2360
FID C 3 4977
FID C 8 3544
FID L 11 1147
FID L 12 1147
FID L 13 1000
FID L 15 1147
FID L 16 1147
SNT VIA
FID H 0 2361
FID C 3 4967
FID C 8 3534
FID L 11 1144
FID L 12 1144
FID L 13 997
FID L 15 1144
FID L 16 1144
SNT PLN S C 0
FID C 8 3522
SNT PLN S C 0
SNT TRC
FID C 3 4963
SNT TRC
FID C 8 3524
SNT TRC
FID C 8 3527
FID C 8 3528
SNT TRC
FID C 8 3530
FID C 8 3531
FID C 8 3532
SNT TRC
FID C 3 4968
SNT TRC
FID C 8 3535
FID C 8 3536
SNT TRC
FID C 3 4971
SNT TRC
FID C 8 3540
SNT TRC
FID C 3 4974
SNT TRC
FID C 8 3543
SNT TRC
FID C 3 4976
SNT TRC
FID C 8 3546
SNT TRC
FID C 3 4981
# NET 7
NET XP1R0V_FPGA_MGTAVCC 
SNT TOP T 150 0
FID C 4 1760
FID C 5 1047
FID C 3 4425
SNT TOP T 170 115
FID C 4 1755
FID C 5 1046
FID C 3 4419
SNT TOP T 170 119
FID C 4 1751
FID C 5 1042
FID C 3 4408
SNT TOP T 170 139
FID C 4 1754
FID C 5 1045
FID C 3 4417
SNT TOP T 170 160
FID C 4 1752
FID C 5 1043
FID C 3 4411
SNT TOP T 170 162
FID C 4 1753
FID C 5 1044
FID C 3 4414
SNT TOP T 475 0
FID C 4 1761
FID C 5 1048
FID C 3 4426
SNT TOP B 22 0
FID C 6 1166
FID C 7 386
FID C 8 3126
SNT TOP B 23 0
FID C 6 1162
FID C 7 382
FID C 8 3111
SNT TOP B 24 0
FID C 6 1164
FID C 7 384
FID C 8 3118
SNT TOP B 25 0
FID C 6 1163
FID C 7 383
FID C 8 3116
SNT TOP B 26 0
FID C 6 1165
FID C 7 385
FID C 8 3122
SNT TOP B 82 0
FID C 6 1161
FID C 7 381
FID C 8 3109
SNT VIA
FID H 0 822
FID C 4 1756
FID C 6 1167
FID C 3 4421
FID C 8 3127
FID L 11 1050
FID L 12 1050
FID L 14 853
FID L 15 1050
FID L 16 1050
SNT VIA
FID H 0 823
FID C 4 1757
FID C 6 1168
FID C 3 4422
FID C 8 3128
FID L 11 1051
FID L 12 1051
FID L 14 854
FID L 15 1051
FID L 16 1051
SNT VIA
FID H 0 824
FID C 4 1759
FID C 6 1170
FID C 3 4424
FID C 8 3130
FID L 11 1053
FID L 12 1053
FID L 14 856
FID L 15 1053
FID L 16 1053
SNT VIA
FID H 0 825
FID C 4 1758
FID C 6 1169
FID C 3 4423
FID C 8 3129
FID L 11 1052
FID L 12 1052
FID L 14 855
FID L 15 1052
FID L 16 1052
SNT VIA
FID H 0 2489
FID C 3 4418
FID C 8 3121
FID L 11 1049
FID L 12 1049
FID L 14 852
FID L 15 1049
FID L 16 1049
SNT VIA
FID H 0 2490
FID C 3 4406
FID C 8 3110
FID L 11 1045
FID L 12 1045
FID L 14 848
FID L 15 1045
FID L 16 1045
SNT VIA
FID H 0 2491
FID C 3 4415
FID C 8 3120
FID L 11 1048
FID L 12 1048
FID L 14 851
FID L 15 1048
FID L 16 1048
SNT VIA
FID H 0 2492
FID C 3 4409
FID C 8 3113
FID L 11 1046
FID L 12 1046
FID L 14 849
FID L 15 1046
FID L 16 1046
SNT VIA
FID H 0 2493
FID C 3 4412
FID C 8 3117
FID L 11 1047
FID L 12 1047
FID L 14 850
FID L 15 1047
FID L 16 1047
SNT PLN S C 0
SNT TRC
FID C 8 3107
FID C 8 3108
SNT TRC
FID C 3 4407
SNT TRC
FID C 8 3112
SNT TRC
FID C 3 4410
SNT TRC
FID C 8 3114
FID C 8 3115
SNT TRC
FID C 3 4413
SNT TRC
FID C 8 3119
SNT TRC
FID C 3 4416
SNT TRC
FID C 3 4420
SNT TRC
FID C 8 3123
FID C 8 3124
SNT TRC
FID C 8 3125
SNT PLN S C 0
FID C 3 4427
# NET 8
NET XP1R8V_FPGA_VCCAUX 
SNT TOP T 156 0
FID C 4 1624
FID C 5 959
FID C 3 4143
SNT TOP T 170 143
FID C 4 1635
FID C 5 966
FID C 3 4168
SNT TOP T 170 209
FID C 4 1634
FID C 5 965
FID C 3 4165
SNT TOP T 170 251
FID C 4 1633
FID C 5 964
FID C 3 4161
SNT TOP T 170 253
FID C 4 1632
FID C 5 963
FID C 3 4158
SNT TOP T 170 297
FID C 4 1631
FID C 5 962
FID C 3 4156
SNT TOP T 170 341
FID C 4 1629
FID C 5 960
FID C 3 4148
SNT TOP T 170 362
FID C 4 1630
FID C 5 961
FID C 3 4152
SNT TOP B 30 0
FID C 6 1082
FID C 7 347
FID C 8 2943
SNT TOP B 60 0
FID C 6 1078
FID C 7 343
FID C 8 2927
SNT TOP B 62 0
FID C 6 1076
FID C 7 341
FID C 8 2921
SNT TOP B 85 0
FID C 6 1080
FID C 7 345
FID C 8 2935
SNT TOP B 87 0
FID C 6 1075
FID C 7 340
FID C 8 2920
SNT TOP B 100 0
FID C 6 1074
FID C 7 339
FID C 8 2914
SNT TOP B 407 0
FID C 6 1079
FID C 7 344
FID C 8 2928
SNT TOP B 408 0
FID C 6 1081
FID C 7 346
FID C 8 2940
SNT TOP B 420 0
FID C 6 1077
FID C 7 342
FID C 8 2926
SNT VIA
FID H 0 853
FID C 4 1628
FID C 6 1073
FID C 3 4147
FID C 8 2913
FID L 11 975
FID L 12 975
FID L 13 877
FID L 15 975
FID L 16 975
SNT VIA
FID H 0 854
FID C 4 1627
FID C 6 1072
FID C 3 4146
FID C 8 2912
FID L 11 974
FID L 12 974
FID L 13 876
FID L 15 974
FID L 16 974
SNT VIA
FID H 0 855
FID C 4 1625
FID C 6 1070
FID C 3 4144
FID C 8 2910
FID L 11 972
FID L 12 972
FID L 13 874
FID L 15 972
FID L 16 972
SNT VIA
FID H 0 1373
FID C 4 1626
FID C 6 1071
FID C 3 4145
FID C 8 2911
FID L 11 973
FID L 12 973
FID L 13 875
FID L 15 973
FID L 16 973
SNT VIA
FID H 0 2511
FID C 3 4166
FID C 8 2944
FID L 11 982
FID L 12 982
FID L 13 884
FID L 15 982
FID L 16 982
SNT VIA
FID H 0 2512
FID C 3 4163
FID C 8 2939
FID L 11 981
FID L 12 981
FID L 13 883
FID L 15 981
FID L 16 981
SNT VIA
FID H 0 2513
FID C 3 4160
FID C 8 2934
FID L 11 980
FID L 12 980
FID L 13 882
FID L 15 980
FID L 16 980
SNT VIA
FID H 0 2514
FID C 3 4159
FID C 8 2933
FID L 11 979
FID L 12 979
FID L 13 881
FID L 15 979
FID L 16 979
SNT VIA
FID H 0 2515
FID C 3 4154
FID C 8 2923
FID L 11 978
FID L 12 978
FID L 13 880
FID L 15 978
FID L 16 978
SNT VIA
FID H 0 2516
FID C 3 4150
FID C 8 2916
FID L 11 976
FID L 12 976
FID L 13 878
FID L 15 976
FID L 16 976
SNT VIA
FID H 0 2517
FID C 3 4151
FID C 8 2917
FID L 11 977
FID L 12 977
FID L 13 879
FID L 15 977
FID L 16 977
SNT PLN S C 0
SNT PLN S C 0
FID C 3 4142
SNT TRC
FID C 3 4149
SNT TRC
FID C 8 2915
SNT TRC
FID C 8 2918
FID C 8 2919
SNT TRC
FID C 3 4153
SNT TRC
FID C 8 2922
SNT TRC
FID C 8 2924
FID C 8 2925
SNT TRC
FID C 3 4155
SNT TRC
FID C 3 4157
SNT TRC
FID C 8 2929
FID C 8 2930
SNT TRC
FID C 8 2931
FID C 8 2932
SNT TRC
FID C 8 2936
SNT TRC
FID C 3 4162
SNT TRC
FID C 8 2937
FID C 8 2938
SNT TRC
FID C 3 4164
SNT TRC
FID C 8 2941
FID C 8 2942
SNT TRC
FID C 3 4167
# NET 9
NET XP2R5V_FPGA 
SNT TOP T 59 0
FID H 0 183
FID C 6 1057
FID C 3 4097
FID C 8 2894
FID L 11 961
FID L 12 961
FID L 13 863
FID L 15 961
FID L 16 961
SNT TOP T 117 0
FID C 4 1603
FID C 5 946
FID C 3 4106
SNT TOP T 117 1
FID C 4 1598
FID C 5 943
FID C 3 4101
SNT TOP T 170 28
FID C 4 1574
FID C 5 926
FID C 3 4030
SNT TOP T 170 47
FID C 4 1577
FID C 5 929
FID C 3 4039
SNT TOP T 170 88
FID C 4 1585
FID C 5 937
FID C 3 4063
SNT TOP T 170 155
FID C 4 1584
FID C 5 936
FID C 3 4060
SNT TOP T 170 203
FID C 4 1576
FID C 5 928
FID C 3 4036
SNT TOP T 170 222
FID C 4 1583
FID C 5 935
FID C 3 4057
SNT TOP T 170 289
FID C 4 1582
FID C 5 934
FID C 3 4054
SNT TOP T 170 308
FID C 4 1581
FID C 5 933
FID C 3 4051
SNT TOP T 170 356
FID C 4 1580
FID C 5 932
FID C 3 4048
SNT TOP T 170 375
FID C 4 1579
FID C 5 931
FID C 3 4045
SNT TOP T 170 423
FID C 4 1575
FID C 5 927
FID C 3 4033
SNT TOP T 170 442
FID C 4 1578
FID C 5 930
FID C 3 4042
SNT TOP T 249 1
FID C 4 1590
FID C 5 939
FID C 3 4076
SNT TOP T 250 1
FID C 4 1591
FID C 5 940
FID C 3 4078
SNT TOP T 428 0
FID C 4 1597
FID C 5 942
FID C 3 4100
SNT TOP T 473 0
FID C 4 1595
FID C 5 941
FID C 3 4089
SNT TOP T 491 0
FID C 4 1586
FID C 5 938
FID C 3 4069
SNT TOP T 492 0
FID C 4 1600
FID C 5 945
FID C 3 4103
SNT TOP T 554 0
FID C 4 1599
FID C 5 944
FID C 3 4102
SNT TOP B 27 0
FID C 6 1044
FID C 7 331
FID C 8 2864
SNT TOP B 42 0
FID C 6 1043
FID C 7 330
FID C 8 2860
SNT TOP B 43 0
FID C 6 1034
FID C 7 321
FID C 8 2831
SNT TOP B 44 0
FID C 6 1035
FID C 7 322
FID C 8 2832
SNT TOP B 45 0
FID C 6 1042
FID C 7 329
FID C 8 2858
SNT TOP B 47 0
FID C 6 1041
FID C 7 328
FID C 8 2855
SNT TOP B 52 0
FID C 6 1039
FID C 7 326
FID C 8 2847
SNT TOP B 53 0
FID C 6 1040
FID C 7 327
FID C 8 2851
SNT TOP B 66 0
FID C 6 1032
FID C 7 319
FID C 8 2821
SNT TOP B 77 0
FID C 6 1037
FID C 7 324
FID C 8 2838
SNT TOP B 78 0
FID C 6 1036
FID C 7 323
FID C 8 2836
SNT TOP B 88 0
FID C 6 1038
FID C 7 325
FID C 8 2843
SNT TOP B 89 0
FID C 6 1033
FID C 7 320
FID C 8 2826
SNT TOP B 165 1
FID C 6 1064
FID C 7 337
FID C 8 2902
SNT TOP B 176 1
FID C 6 1050
FID C 7 334
FID C 8 2878
SNT TOP B 177 1
FID C 6 1051
FID C 7 335
FID C 8 2880
SNT TOP B 324 1
FID C 6 1066
FID C 7 338
FID C 8 2906
SNT TOP B 355 0
FID C 6 1054
FID C 7 336
FID C 8 2891
SNT TOP B 365 0
FID C 6 1046
FID C 7 333
FID C 8 2874
SNT TOP B 388 0
FID C 6 1045
FID C 7 332
FID C 8 2866
SNT VIA
FID H 0 859
FID C 4 1607
FID C 6 1063
FID C 3 4110
FID C 10 2630
FID C 8 2900
FID L 11 967
FID L 12 967
FID L 13 869
FID L 14 791
FID L 15 967
FID L 16 967
SNT VIA
FID H 0 860
FID C 4 1606
FID C 6 1062
FID C 3 4109
FID C 10 2629
FID C 8 2899
FID L 11 966
FID L 12 966
FID L 13 868
FID L 14 790
FID L 15 966
FID L 16 966
SNT VIA
FID H 0 861
FID C 4 1593
FID C 6 1053
FID C 3 4080
FID C 8 2885
FID L 11 958
FID L 12 958
FID L 13 860
FID L 15 958
FID L 16 958
SNT VIA
FID H 0 862
FID C 4 1594
FID C 6 1055
FID C 3 4081
FID C 8 2892
FID L 11 959
FID L 12 959
FID L 13 861
FID L 15 959
FID L 16 959
SNT VIA
FID H 0 863
FID C 4 1605
FID C 6 1061
FID C 3 4108
FID C 9 2017
FID C 8 2898
FID L 11 965
FID L 12 965
FID L 13 867
FID L 14 789
FID L 15 965
FID L 16 965
SNT VIA
FID H 0 864
FID C 4 1592
FID C 6 1052
FID C 3 4079
FID C 8 2884
FID L 11 957
FID L 12 957
FID L 13 859
FID L 15 957
FID L 16 957
SNT VIA
FID H 0 865
FID C 4 1589
FID C 6 1049
FID C 3 4075
FID C 8 2877
FID L 11 956
FID L 12 956
FID L 13 858
FID L 15 956
FID L 16 956
SNT VIA
FID H 0 866
FID C 4 1588
FID C 6 1048
FID C 3 4071
FID C 8 2876
FID L 11 955
FID L 12 955
FID L 13 857
FID L 15 955
FID L 16 955
SNT VIA
FID H 0 867
FID C 4 1587
FID C 6 1047
FID C 3 4070
FID C 8 2875
FID L 11 954
FID L 12 954
FID L 13 856
FID L 15 954
FID L 16 954
SNT VIA
FID H 0 868
FID C 4 1602
FID C 6 1059
FID C 3 4105
FID C 9 2016
FID C 8 2896
FID L 11 963
FID L 12 963
FID L 13 865
FID L 15 963
FID L 16 963
SNT VIA
FID H 0 869
FID C 4 1604
FID C 6 1060
FID C 3 4107
FID C 8 2897
FID L 11 964
FID L 12 964
FID L 13 866
FID L 15 964
FID L 16 964
SNT VIA
FID H 0 870
FID C 4 1601
FID C 6 1058
FID C 3 4104
FID C 8 2895
FID L 11 962
FID L 12 962
FID L 13 864
FID L 15 962
FID L 16 962
SNT VIA
FID H 0 871
FID C 4 1608
FID C 6 1065
FID C 3 4111
FID C 9 2018
FID C 8 2905
FID L 11 968
FID L 12 968
FID L 13 870
FID L 14 792
FID L 15 968
FID L 16 968
SNT VIA
FID H 0 872
FID C 4 1596
FID C 6 1056
FID C 3 4096
FID C 9 1986
FID C 8 2893
FID L 11 960
FID L 12 960
FID L 13 862
FID L 14 788
FID L 15 960
FID L 16 960
SNT VIA
FID H 0 2518
FID C 3 4062
FID C 8 2869
FID L 11 953
FID L 12 953
FID L 13 855
FID L 15 953
FID L 16 953
SNT VIA
FID H 0 2519
FID C 3 4059
FID C 8 2865
FID L 11 952
FID L 12 952
FID L 13 854
FID L 15 952
FID L 16 952
SNT VIA
FID H 0 2520
FID C 3 4035
FID C 8 2829
FID L 11 944
FID L 12 944
FID L 13 846
FID L 15 944
FID L 16 944
SNT VIA
FID H 0 2521
FID C 3 4056
FID C 8 2859
FID L 11 951
FID L 12 951
FID L 13 853
FID L 15 951
FID L 16 951
SNT VIA
FID H 0 2522
FID C 3 4053
FID C 8 2852
FID L 11 950
FID L 12 950
FID L 13 852
FID L 15 950
FID L 16 950
SNT VIA
FID H 0 2523
FID C 3 4050
FID C 8 2848
FID L 11 949
FID L 12 949
FID L 13 851
FID L 15 949
FID L 16 949
SNT VIA
FID H 0 2524
FID C 3 4047
FID C 8 2844
FID L 11 948
FID L 12 948
FID L 13 850
FID L 15 948
FID L 16 948
SNT VIA
FID H 0 2525
FID C 3 4044
FID C 8 2840
FID L 11 947
FID L 12 947
FID L 13 849
FID L 15 947
FID L 16 947
SNT VIA
FID H 0 2526
FID C 3 4032
FID C 8 2823
FID L 11 943
FID L 12 943
FID L 13 845
FID L 15 943
FID L 16 943
SNT VIA
FID H 0 2527
FID C 3 4041
FID C 8 2837
FID L 11 946
FID L 12 946
FID L 13 848
FID L 15 946
FID L 16 946
SNT VIA
FID H 0 2528
FID C 3 4029
FID C 8 2820
FID L 11 942
FID L 12 942
FID L 13 844
FID L 15 942
FID L 16 942
SNT VIA
FID H 0 2529
FID C 3 4038
FID C 8 2833
FID L 11 945
FID L 12 945
FID L 13 847
FID L 15 945
FID L 16 945
SNT PLN S C 0
SNT TRC
FID C 8 2822
SNT TRC
FID C 3 4031
SNT TRC
FID C 8 2824
FID C 8 2825
SNT TRC
FID C 3 4034
SNT TRC
FID C 8 2827
FID C 8 2828
SNT TRC
FID C 8 2830
SNT TRC
FID C 3 4037
SNT TRC
FID C 8 2834
FID C 8 2835
SNT TRC
FID C 3 4040
SNT TRC
FID C 8 2839
SNT TRC
FID C 3 4043
SNT TRC
FID C 8 2841
FID C 8 2842
SNT TRC
FID C 3 4046
SNT TRC
FID C 8 2845
FID C 8 2846
SNT TRC
FID C 3 4049
SNT TRC
FID C 8 2849
FID C 8 2850
SNT TRC
FID C 3 4052
SNT TRC
FID C 8 2853
FID C 8 2854
SNT TRC
FID C 8 2856
FID C 8 2857
SNT TRC
FID C 3 4055
SNT TRC
FID C 8 2861
SNT TRC
FID C 3 4058
SNT TRC
FID C 8 2862
FID C 8 2863
SNT TRC
FID C 3 4061
SNT TRC
FID C 8 2867
FID C 8 2868
SNT TRC
FID C 3 4064
SNT TRC
FID C 3 4065
FID C 3 4066
SNT TRC
FID C 8 2870
FID C 8 2871
SNT TRC
FID C 8 2872
FID C 8 2873
SNT TRC
FID C 3 4067
FID C 3 4068
SNT TRC
FID C 3 4072
FID C 3 4073
FID C 3 4074
SNT TRC
FID C 3 4077
SNT TRC
FID C 8 2879
SNT TRC
FID C 8 2881
FID C 8 2882
FID C 8 2883
SNT TRC
FID C 8 2886
FID C 8 2887
SNT TRC
FID C 8 2888
FID C 8 2889
FID C 8 2890
SNT TRC
FID C 3 4082
FID C 3 4083
FID C 3 4084
SNT TRC
FID C 3 4085
FID C 3 4086
FID C 3 4087
FID C 3 4088
SNT TRC
FID C 9 1974
FID C 9 1975
FID C 9 1976
FID C 9 1977
FID C 9 1978
FID C 9 1979
FID C 9 1980
SNT TRC
FID C 3 4090
FID C 3 4091
FID C 3 4092
FID C 3 4093
FID C 3 4094
SNT PLN S C 0
FID C 3 4095
SNT TRC
FID C 10 2619
FID C 10 2620
FID C 10 2621
FID C 10 2622
FID C 10 2623
FID C 10 2624
FID C 10 2625
FID C 10 2626
FID C 10 2627
FID C 10 2628
SNT TRC
FID C 9 1981
FID C 9 1982
FID C 9 1983
FID C 9 1984
FID C 9 1985
SNT TRC
FID C 9 1987
FID C 9 1988
FID C 9 1989
FID C 9 1990
FID C 9 1991
FID C 9 1992
FID C 9 1993
FID C 9 1994
FID C 9 1995
FID C 9 1996
FID C 9 1997
FID C 9 1998
FID C 9 1999
FID C 9 2000
FID C 9 2001
FID C 9 2002
FID C 9 2003
FID C 9 2004
FID C 9 2005
FID C 9 2006
FID C 9 2007
FID C 9 2008
FID C 9 2009
FID C 9 2010
FID C 9 2011
FID C 9 2012
FID C 9 2013
FID C 9 2014
FID C 9 2015
SNT TRC
FID C 3 4098
FID C 3 4099
SNT TRC
FID C 8 2901
SNT TRC
FID C 8 2903
FID C 8 2904
# NET 10
NET XP1R0V_FPGA_VCCINT 
SNT TOP T 153 0
FID C 4 1737
FID C 5 1035
FID C 3 4387
SNT TOP T 170 205
FID C 4 1734
FID C 5 1032
FID C 3 4379
SNT TOP T 170 207
FID C 4 1724
FID C 5 1022
FID C 3 4349
SNT TOP T 170 226
FID C 4 1736
FID C 5 1034
FID C 3 4385
SNT TOP T 170 228
FID C 4 1735
FID C 5 1033
FID C 3 4382
SNT TOP T 170 230
FID C 4 1725
FID C 5 1023
FID C 3 4352
SNT TOP T 170 249
FID C 4 1733
FID C 5 1031
FID C 3 4376
SNT TOP T 170 270
FID C 4 1732
FID C 5 1030
FID C 3 4373
SNT TOP T 170 274
FID C 4 1723
FID C 5 1021
FID C 3 4346
SNT TOP T 170 293
FID C 4 1731
FID C 5 1029
FID C 3 4370
SNT TOP T 170 314
FID C 4 1729
FID C 5 1027
FID C 3 4364
SNT TOP T 170 318
FID C 4 1722
FID C 5 1020
FID C 3 4343
SNT TOP T 170 337
FID C 4 1730
FID C 5 1028
FID C 3 4367
SNT TOP T 170 339
FID C 4 1721
FID C 5 1019
FID C 3 4340
SNT TOP T 170 358
FID C 4 1728
FID C 5 1026
FID C 3 4361
SNT TOP T 170 360
FID C 4 1727
FID C 5 1025
FID C 3 4358
SNT TOP T 170 381
FID C 4 1726
FID C 5 1024
FID C 3 4355
SNT TOP T 170 383
FID C 4 1720
FID C 5 1018
FID C 3 4337
SNT TOP T 171 0
FID C 4 1743
FID C 5 1039
FID C 3 4393
SNT TOP T 172 0
FID C 4 1740
FID C 5 1036
FID C 3 4390
SNT TOP T 173 0
FID C 4 1742
FID C 5 1038
FID C 3 4392
SNT TOP T 486 0
FID C 4 1741
FID C 5 1037
FID C 3 4391
SNT TOP B 29 0
FID C 6 1140
FID C 7 368
FID C 8 3045
SNT TOP B 36 0
FID C 6 1149
FID C 7 377
FID C 8 3076
SNT TOP B 37 0
FID C 6 1152
FID C 7 380
FID C 8 3086
SNT TOP B 38 0
FID C 6 1139
FID C 7 367
FID C 8 3042
SNT TOP B 39 0
FID C 6 1150
FID C 7 378
FID C 8 3080
SNT TOP B 40 0
FID C 6 1148
FID C 7 376
FID C 8 3073
SNT TOP B 41 0
FID C 6 1151
FID C 7 379
FID C 8 3085
SNT TOP B 46 0
FID C 6 1144
FID C 7 372
FID C 8 3059
SNT TOP B 61 0
FID C 6 1146
FID C 7 374
FID C 8 3066
SNT TOP B 67 0
FID C 6 1137
FID C 7 365
FID C 8 3035
SNT TOP B 68 0
FID C 6 1143
FID C 7 371
FID C 8 3056
SNT TOP B 69 0
FID C 6 1142
FID C 7 370
FID C 8 3053
SNT TOP B 70 0
FID C 6 1141
FID C 7 369
FID C 8 3051
SNT TOP B 71 0
FID C 6 1136
FID C 7 364
FID C 8 3030
SNT TOP B 76 0
FID C 6 1145
FID C 7 373
FID C 8 3062
SNT TOP B 409 0
FID C 6 1147
FID C 7 375
FID C 8 3070
SNT TOP B 421 0
FID C 6 1138
FID C 7 366
FID C 8 3041
SNT VIA
FID H 0 827
FID C 4 1745
FID C 6 1156
FID C 3 4395
FID C 8 3090
FID L 11 1040
FID L 12 1040
FID L 14 843
FID L 15 1040
FID L 16 1040
SNT VIA
FID H 0 828
FID C 4 1746
FID C 6 1157
FID C 3 4396
FID C 8 3091
FID L 11 1041
FID L 12 1041
FID L 14 844
FID L 15 1041
FID L 16 1041
SNT VIA
FID H 0 829
FID C 4 1739
FID C 6 1154
FID C 3 4389
FID C 8 3088
FID L 11 1038
FID L 12 1038
FID L 14 841
FID L 15 1038
FID L 16 1038
SNT VIA
FID H 0 830
FID C 4 1738
FID C 6 1153
FID C 3 4388
FID C 8 3087
FID L 11 1037
FID L 12 1037
FID L 14 840
FID L 15 1037
FID L 16 1037
SNT VIA
FID H 0 1367
FID C 4 1744
FID C 6 1155
FID C 3 4394
FID C 8 3089
FID L 11 1039
FID L 12 1039
FID L 13 913
FID L 14 842
FID L 15 1039
FID L 16 1039
SNT VIA
FID H 0 2494
FID C 3 4377
FID C 8 3074
FID L 11 1034
FID L 12 1034
FID L 14 837
FID L 15 1034
FID L 16 1034
SNT VIA
FID H 0 2495
FID C 3 4347
FID C 8 3046
FID L 11 1024
FID L 12 1024
FID L 14 827
FID L 15 1024
FID L 16 1024
SNT VIA
FID H 0 2496
FID C 3 4383
FID C 8 3081
FID L 11 1036
FID L 12 1036
FID L 14 839
FID L 15 1036
FID L 16 1036
SNT VIA
FID H 0 2497
FID C 3 4380
FID C 8 3077
FID L 11 1035
FID L 12 1035
FID L 14 838
FID L 15 1035
FID L 16 1035
SNT VIA
FID H 0 2498
FID C 3 4350
FID C 8 3047
FID L 11 1025
FID L 12 1025
FID L 14 828
FID L 15 1025
FID L 16 1025
SNT VIA
FID H 0 2499
FID C 3 4374
FID C 8 3071
FID L 11 1033
FID L 12 1033
FID L 14 836
FID L 15 1033
FID L 16 1033
SNT VIA
FID H 0 2500
FID C 3 4371
FID C 8 3067
FID L 11 1032
FID L 12 1032
FID L 14 835
FID L 15 1032
FID L 16 1032
SNT VIA
FID H 0 2501
FID C 3 4344
FID C 8 3037
FID L 11 1023
FID L 12 1023
FID L 14 826
FID L 15 1023
FID L 16 1023
SNT VIA
FID H 0 2502
FID C 3 4368
FID C 8 3063
FID L 11 1031
FID L 12 1031
FID L 14 834
FID L 15 1031
FID L 16 1031
SNT VIA
FID H 0 2503
FID C 3 4362
FID C 8 3057
FID L 11 1029
FID L 12 1029
FID L 14 832
FID L 15 1029
FID L 16 1029
SNT VIA
FID H 0 2504
FID C 3 4341
FID C 8 3036
FID L 11 1022
FID L 12 1022
FID L 14 825
FID L 15 1022
FID L 16 1022
SNT VIA
FID H 0 2505
FID C 3 4365
FID C 8 3060
FID L 11 1030
FID L 12 1030
FID L 14 833
FID L 15 1030
FID L 16 1030
SNT VIA
FID H 0 2506
FID C 3 4338
FID C 8 3033
FID L 11 1021
FID L 12 1021
FID L 14 824
FID L 15 1021
FID L 16 1021
SNT VIA
FID H 0 2507
FID C 3 4359
FID C 8 3054
FID L 11 1028
FID L 12 1028
FID L 14 831
FID L 15 1028
FID L 16 1028
SNT VIA
FID H 0 2508
FID C 3 4356
FID C 8 3049
FID L 11 1027
FID L 12 1027
FID L 14 830
FID L 15 1027
FID L 16 1027
SNT VIA
FID H 0 2509
FID C 3 4353
FID C 8 3048
FID L 11 1026
FID L 12 1026
FID L 14 829
FID L 15 1026
FID L 16 1026
SNT VIA
FID H 0 2510
FID C 3 4335
FID C 8 3029
FID L 11 1020
FID L 12 1020
FID L 14 823
FID L 15 1020
FID L 16 1020
SNT PLN S C 0
SNT TRC
FID C 3 4336
SNT TRC
FID C 8 3031
FID C 8 3032
SNT TRC
FID C 3 4339
SNT TRC
FID C 8 3034
SNT TRC
FID C 3 4342
SNT TRC
FID C 8 3038
FID C 8 3039
SNT TRC
FID C 8 3040
SNT TRC
FID C 3 4345
SNT TRC
FID C 8 3043
FID C 8 3044
SNT TRC
FID C 3 4348
SNT TRC
FID C 3 4351
SNT TRC
FID C 3 4354
SNT TRC
FID C 8 3050
SNT TRC
FID C 3 4357
SNT TRC
FID C 8 3052
SNT TRC
FID C 3 4360
SNT TRC
FID C 8 3055
SNT TRC
FID C 3 4363
SNT TRC
FID C 8 3058
SNT TRC
FID C 3 4366
SNT TRC
FID C 8 3061
SNT TRC
FID C 8 3064
FID C 8 3065
SNT TRC
FID C 3 4369
SNT TRC
FID C 8 3068
FID C 8 3069
SNT TRC
FID C 3 4372
SNT TRC
FID C 3 4375
SNT TRC
FID C 8 3072
SNT TRC
FID C 3 4378
SNT TRC
FID C 8 3075
SNT TRC
FID C 8 3078
FID C 8 3079
SNT TRC
FID C 3 4381
SNT TRC
FID C 8 3082
FID C 8 3083
SNT TRC
FID C 8 3084
SNT TRC
FID C 3 4384
SNT PLN S C 0
FID C 3 4386
# NET 11
NET UNNAMED_516_CAPACITOR_I29_1 
SNT TOP T 283 0
FID C 4 2214
FID C 5 1317
FID C 3 5478
SNT TOP T 348 1
FID C 4 2216
FID C 5 1318
FID C 3 5483
SNT TOP T 454 0
FID C 4 2217
FID C 5 1319
FID C 3 5487
SNT VIA
FID H 0 1312
FID C 4 2215
FID C 6 1526
FID C 3 5480
FID C 8 3893
FID L 11 1281
FID L 12 1281
FID L 13 1092
FID L 14 1062
FID L 15 1281
FID L 16 1281
SNT TRC
FID C 3 5479
SNT TRC
FID C 3 5481
FID C 3 5482
SNT TRC
FID C 3 5484
FID C 3 5485
FID C 3 5486
# NET 12
NET XP5R0V_FB_R_TO_AGND 
SNT TOP T 180 13
FID C 4 2029
FID C 5 1220
FID C 3 5162
SNT TOP T 283 1
FID C 4 2026
FID C 5 1218
FID C 3 5157
SNT TOP T 454 1
FID C 4 2028
FID C 5 1219
FID C 3 5161
SNT TOP B 110 0
FID C 6 1389
FID C 7 498
FID C 8 3662
SNT TOP B 112 1
FID C 6 1391
FID C 7 499
FID C 8 3666
SNT VIA
FID H 0 2301
FID C 4 2027
FID C 6 1390
FID C 3 5158
FID C 8 3663
FID L 11 1186
FID L 12 1186
FID L 13 1039
FID L 14 978
FID L 15 1186
FID L 16 1186
SNT TRC
FID C 3 5152
FID C 3 5153
FID C 3 5154
SNT TRC
FID C 3 5155
FID C 3 5156
SNT TRC
FID C 8 3660
FID C 8 3661
SNT TRC
FID C 3 5159
FID C 3 5160
SNT TRC
FID C 8 3664
FID C 8 3665
# NET 13
NET XP5R0V 
SNT TOP T 9 0
FID C 4 2050
FID C 5 1230
FID C 3 5200
SNT TOP T 102 0
FID H 0 187
FID C 6 1420
FID C 3 5211
FID C 8 3712
FID L 11 1207
FID L 12 1207
FID L 13 1049
FID L 14 999
FID L 15 1207
FID L 16 1207
SNT TOP T 154 0
FID C 4 2046
FID C 5 1229
FID C 3 5194
SNT TOP T 184 1
FID C 4 2067
FID C 5 1236
FID C 3 5220
SNT TOP T 348 0
FID C 4 2065
FID C 5 1235
FID C 3 5218
SNT TOP T 483 0
FID C 4 2063
FID C 5 1234
FID C 3 5215
SNT TOP T 484 0
FID C 4 2062
FID C 5 1233
FID C 3 5214
SNT TOP T 485 0
FID C 4 2061
FID C 5 1232
FID C 3 5213
SNT TOP T 545 0
FID C 4 2060
FID C 5 1231
FID C 3 5212
SNT TOP T 564 0
FID C 4 2045
FID C 5 1228
FID C 3 5193
SNT TOP B 93 1
FID C 6 1414
FID C 7 508
FID C 8 3705
SNT TOP B 320 1
FID C 6 1406
FID C 7 506
FID C 8 3695
SNT TOP B 414 0
FID C 6 1413
FID C 7 507
FID C 8 3704
SNT VIA
FID H 0 1040
FID C 4 2064
FID C 6 1421
FID C 3 5216
FID C 10 3251
FID C 8 3713
FID L 11 1208
FID L 12 1208
FID L 13 1050
FID L 14 1000
FID L 15 1208
FID L 16 1208
SNT VIA
FID H 0 1041
FID C 4 2051
FID C 6 1409
FID C 3 5201
FID C 8 3699
FID L 11 1198
FID L 12 1198
FID L 14 990
FID L 15 1198
FID L 16 1198
SNT VIA
FID H 0 1042
FID C 4 2049
FID C 6 1408
FID C 3 5199
FID C 8 3698
FID L 11 1197
FID L 12 1197
FID L 14 989
FID L 15 1197
FID L 16 1197
SNT VIA
FID H 0 1043
FID C 4 2068
FID C 6 1423
FID C 3 5221
FID C 8 3715
FID L 11 1210
FID L 12 1210
FID L 13 1052
FID L 14 1002
FID L 15 1210
FID L 16 1210
SNT VIA
FID H 0 1044
FID C 4 2066
FID C 6 1422
FID C 3 5219
FID C 10 3252
FID C 8 3714
FID L 11 1209
FID L 12 1209
FID L 13 1051
FID L 14 1001
FID L 15 1209
FID L 16 1209
SNT VIA
FID H 0 1045
FID C 4 2069
FID C 6 1424
FID C 3 5222
FID C 8 3716
FID L 11 1211
FID L 12 1211
FID L 13 1053
FID L 14 1003
FID L 15 1211
FID L 16 1211
SNT VIA
FID H 0 1046
FID C 4 2059
FID C 6 1419
FID C 3 5210
FID C 8 3711
FID L 11 1206
FID L 12 1206
FID L 13 1048
FID L 14 998
FID L 15 1206
FID L 16 1206
SNT VIA
FID H 0 1047
FID C 4 2058
FID C 6 1418
FID C 3 5208
FID C 8 3710
FID L 11 1205
FID L 12 1205
FID L 14 997
FID L 15 1205
FID L 16 1205
SNT VIA
FID H 0 1048
FID C 4 2057
FID C 6 1417
FID C 3 5207
FID C 8 3709
FID L 11 1204
FID L 12 1204
FID L 14 996
FID L 15 1204
FID L 16 1204
SNT VIA
FID H 0 1049
FID C 4 2056
FID C 6 1416
FID C 3 5206
FID C 8 3708
FID L 11 1203
FID L 12 1203
FID L 14 995
FID L 15 1203
FID L 16 1203
SNT VIA
FID H 0 1050
FID C 4 2055
FID C 6 1415
FID C 3 5205
FID C 8 3707
FID L 11 1202
FID L 12 1202
FID L 14 994
FID L 15 1202
FID L 16 1202
SNT VIA
FID H 0 1051
FID C 4 2054
FID C 6 1412
FID C 3 5204
FID C 8 3703
FID L 11 1201
FID L 12 1201
FID L 14 993
FID L 15 1201
FID L 16 1201
SNT VIA
FID H 0 1052
FID C 4 2053
FID C 6 1411
FID C 3 5203
FID C 8 3702
FID L 11 1200
FID L 12 1200
FID L 14 992
FID L 15 1200
FID L 16 1200
SNT VIA
FID H 0 1053
FID C 4 2052
FID C 6 1410
FID C 3 5202
FID C 8 3701
FID L 11 1199
FID L 12 1199
FID L 14 991
FID L 15 1199
FID L 16 1199
SNT VIA
FID H 0 1054
FID C 4 2043
FID C 6 1403
FID C 3 5191
FID C 8 3692
FID L 11 1193
FID L 12 1193
FID L 14 985
FID L 15 1193
FID L 16 1193
SNT VIA
FID H 0 1055
FID C 4 2044
FID C 6 1404
FID C 3 5192
FID C 8 3693
FID L 11 1194
FID L 12 1194
FID L 14 986
FID L 15 1194
FID L 16 1194
SNT VIA
FID H 0 1056
FID C 4 2047
FID C 6 1405
FID C 3 5195
FID C 10 3237
FID C 8 3694
FID L 11 1195
FID L 12 1195
FID L 13 1046
FID L 14 987
FID L 15 1195
FID L 16 1195
SNT VIA
FID H 0 1057
FID C 4 2048
FID C 6 1407
FID C 3 5196
FID C 10 3238
FID C 8 3697
FID L 11 1196
FID L 12 1196
FID L 13 1047
FID L 14 988
FID L 15 1196
FID L 16 1196
SNT PLN S C 0
SNT TRC
FID C 8 3696
SNT TRC
FID C 10 3239
FID C 10 3240
FID C 10 3241
FID C 10 3242
FID C 10 3243
FID C 10 3244
SNT PLN S C 0
FID C 3 5197
SNT PLN S C 0
FID C 3 5198
SNT PLN S C 0
FID C 8 3700
SNT PLN S C 0
FID C 8 3706
SNT PLN S C 0
FID C 3 5209
SNT TRC
FID C 10 3245
FID C 10 3246
FID C 10 3247
FID C 10 3248
FID C 10 3249
FID C 10 3250
SNT TRC
FID C 3 5217
# NET 14
NET XP1R2V_FPGA 
SNT TOP T 55 0
FID H 0 181
FID C 6 1120
FID C 3 4276
FID C 8 3005
FID L 11 1009
FID L 12 1009
FID L 14 812
FID L 15 1009
FID L 16 1009
SNT TOP T 118 0
FID C 4 1691
FID C 5 999
FID C 3 4281
SNT TOP T 118 1
FID C 4 1689
FID C 5 997
FID C 3 4279
SNT TOP T 430 0
FID C 4 1688
FID C 5 996
FID C 3 4278
SNT TOP T 502 0
FID C 4 1692
FID C 5 1000
FID C 3 4282
SNT TOP T 567 0
FID C 4 1690
FID C 5 998
FID C 3 4280
SNT TOP B 91 1
FID C 6 1114
FID C 7 357
FID C 8 2999
SNT TOP B 356 0
FID C 6 1115
FID C 7 358
FID C 8 3000
SNT TOP B 374 0
FID C 6 1113
FID C 7 356
FID C 8 2998
SNT VIA
FID H 0 832
FID C 4 1687
FID C 6 1119
FID C 3 4271
FID C 8 3004
FID L 11 1008
FID L 12 1008
FID L 14 811
FID L 15 1008
FID L 16 1008
SNT VIA
FID H 0 833
FID C 4 1686
FID C 6 1118
FID C 3 4270
FID C 8 3003
FID L 11 1007
FID L 12 1007
FID L 14 810
FID L 15 1007
FID L 16 1007
SNT VIA
FID H 0 834
FID C 4 1685
FID C 6 1117
FID C 3 4269
FID C 8 3002
FID L 11 1006
FID L 12 1006
FID L 14 809
FID L 15 1006
FID L 16 1006
SNT VIA
FID H 0 835
FID C 4 1684
FID C 6 1116
FID C 3 4268
FID C 8 3001
FID L 11 1005
FID L 12 1005
FID L 14 808
FID L 15 1005
FID L 16 1005
SNT VIA
FID H 0 836
FID C 4 1694
FID C 6 1122
FID C 3 4284
FID C 8 3007
FID L 11 1011
FID L 12 1011
FID L 14 814
FID L 15 1011
FID L 16 1011
SNT VIA
FID H 0 837
FID C 4 1693
FID C 6 1121
FID C 3 4283
FID C 8 3006
FID L 11 1010
FID L 12 1010
FID L 14 813
FID L 15 1010
FID L 16 1010
SNT VIA
FID H 0 838
FID C 4 1696
FID C 6 1124
FID C 3 4286
FID C 8 3009
FID L 11 1013
FID L 12 1013
FID L 14 816
FID L 15 1013
FID L 16 1013
SNT VIA
FID H 0 839
FID C 4 1695
FID C 6 1123
FID C 3 4285
FID C 8 3008
FID L 11 1012
FID L 12 1012
FID L 14 815
FID L 15 1012
FID L 16 1012
SNT PLN S C 0
SNT PLN S C 0
FID C 8 2997
SNT TRC
FID C 3 4272
SNT TRC
FID C 3 4273
SNT PLN S C 0
FID C 3 4274
SNT TRC
FID C 3 4275
SNT TRC
FID C 3 4277
# NET 15
NET XP1R0V_FPGA 
SNT TOP T 14 1
FID C 4 1770
FID C 5 1053
FID C 3 4438
SNT TOP T 73 0
FID H 0 180
FID C 6 1177
FID C 3 4441
FID C 8 3138
FID L 11 1060
FID L 12 1060
FID L 13 917
FID L 14 863
FID L 15 1060
FID L 16 1060
SNT TOP T 150 1
FID C 4 1762
FID C 5 1049
FID C 3 4429
SNT TOP T 153 1
FID C 4 1769
FID C 5 1052
FID C 3 4437
SNT TOP T 407 0
FID C 4 1780
FID C 5 1058
FID C 3 4449
SNT TOP T 474 0
FID C 4 1764
FID C 5 1051
FID C 3 4431
SNT TOP T 487 0
FID C 4 1777
FID C 5 1055
FID C 3 4446
SNT TOP T 489 0
FID C 4 1778
FID C 5 1056
FID C 3 4447
SNT TOP T 490 0
FID C 4 1779
FID C 5 1057
FID C 3 4448
SNT TOP T 515 0
FID C 4 1763
FID C 5 1050
FID C 3 4430
SNT TOP T 547 0
FID C 4 1776
FID C 5 1054
FID C 3 4445
SNT TOP B 362 0
FID C 6 1182
FID C 7 388
FID C 8 3143
SNT TOP B 403 0
FID C 6 1181
FID C 7 387
FID C 8 3142
SNT VIA
FID H 0 811
FID C 4 1766
FID C 6 1172
FID C 3 4433
FID C 8 3132
FID L 11 1055
FID L 12 1055
FID L 14 858
FID L 15 1055
FID L 16 1055
SNT VIA
FID H 0 812
FID C 4 1767
FID C 6 1173
FID C 3 4434
FID C 8 3133
FID L 11 1056
FID L 12 1056
FID L 14 859
FID L 15 1056
FID L 16 1056
SNT VIA
FID H 0 813
FID C 4 1768
FID C 6 1174
FID C 3 4435
FID C 8 3134
FID L 11 1057
FID L 12 1057
FID L 14 860
FID L 15 1057
FID L 16 1057
SNT VIA
FID H 0 814
FID C 4 1765
FID C 6 1171
FID C 3 4432
FID C 8 3131
FID L 11 1054
FID L 12 1054
FID L 14 857
FID L 15 1054
FID L 16 1054
SNT VIA
FID H 0 815
FID C 4 1773
FID C 6 1178
FID C 3 4442
FID C 8 3139
FID L 11 1061
FID L 12 1061
FID L 14 864
FID L 15 1061
FID L 16 1061
SNT VIA
FID H 0 816
FID C 4 1772
FID C 6 1176
FID C 3 4440
FID C 8 3137
FID L 11 1059
FID L 12 1059
FID L 14 862
FID L 15 1059
FID L 16 1059
SNT VIA
FID H 0 817
FID C 4 1774
FID C 6 1179
FID C 3 4443
FID C 8 3140
FID L 11 1062
FID L 12 1062
FID L 14 865
FID L 15 1062
FID L 16 1062
SNT VIA
FID H 0 818
FID C 4 1775
FID C 6 1180
FID C 3 4444
FID C 8 3141
FID L 11 1063
FID L 12 1063
FID L 14 866
FID L 15 1063
FID L 16 1063
SNT VIA
FID H 0 819
FID C 4 1771
FID C 6 1175
FID C 3 4439
FID C 8 3136
FID L 11 1058
FID L 12 1058
FID L 14 861
FID L 15 1058
FID L 16 1058
SNT VIA
FID H 0 820
FID C 4 1781
FID C 6 1183
FID C 3 4451
FID C 10 2685
FID C 8 3144
FID L 11 1064
FID L 12 1064
FID L 14 867
FID L 15 1064
FID L 16 1064
SNT VIA
FID H 0 821
FID C 4 1782
FID C 6 1184
FID C 3 4452
FID C 10 2686
FID C 8 3145
FID L 11 1065
FID L 12 1065
FID L 13 918
FID L 14 868
FID L 15 1065
FID L 16 1065
SNT PLN S C 0
SNT PLN S C 0
FID C 3 4428
SNT TRC
FID C 10 2676
FID C 10 2677
FID C 10 2678
FID C 10 2679
FID C 10 2680
FID C 10 2681
FID C 10 2682
FID C 10 2683
FID C 10 2684
SNT PLN S C 0
FID C 3 4436
SNT PLN S C 0
FID C 8 3135
SNT TRC
FID C 3 4450
# NET 16
NET XP1R8V_FPGA 
SNT TOP T 11 0
FID C 4 1641
FID C 5 968
FID C 3 4181
SNT TOP T 54 0
FID H 0 182
FID C 6 1099
FID C 3 4198
FID C 8 2979
FID L 11 994
FID L 12 994
FID L 13 896
FID L 14 801
FID L 15 994
FID L 16 994
SNT TOP T 116 0
FID C 4 1651
FID C 5 972
FID C 3 4195
SNT TOP T 116 1
FID C 4 1650
FID C 5 971
FID C 3 4194
SNT TOP T 156 1
FID C 4 1645
FID C 5 970
FID C 3 4186
SNT TOP T 432 0
FID C 4 1656
FID C 5 973
FID C 3 4203
SNT TOP T 509 0
FID C 4 1658
FID C 5 975
FID C 3 4205
SNT TOP T 535 0
FID C 4 1642
FID C 5 969
FID C 3 4182
SNT TOP T 577 0
FID C 4 1657
FID C 5 974
FID C 3 4204
SNT TOP B 363 0
FID C 6 1095
FID C 7 351
FID C 8 2975
SNT TOP B 404 0
FID C 6 1096
FID C 7 352
FID C 8 2976
SNT VIA
FID H 0 840
FID C 4 1649
FID C 6 1098
FID C 3 4190
FID C 8 2978
FID L 11 993
FID L 12 993
FID L 13 895
FID L 15 993
FID L 16 993
SNT VIA
FID H 0 841
FID C 4 1648
FID C 6 1097
FID C 3 4189
FID C 8 2977
FID L 11 992
FID L 12 992
FID L 13 894
FID L 15 992
FID L 16 992
SNT VIA
FID H 0 842
FID C 4 1646
FID C 6 1093
FID C 3 4187
FID C 8 2973
FID L 11 990
FID L 12 990
FID L 13 892
FID L 15 990
FID L 16 990
SNT VIA
FID H 0 843
FID C 4 1647
FID C 6 1094
FID C 3 4188
FID C 8 2974
FID L 11 991
FID L 12 991
FID L 13 893
FID L 15 991
FID L 16 991
SNT VIA
FID H 0 844
FID C 4 1652
FID C 6 1100
FID C 3 4199
FID C 8 2980
FID L 11 995
FID L 12 995
FID L 13 897
FID L 15 995
FID L 16 995
SNT VIA
FID H 0 845
FID C 4 1654
FID C 6 1102
FID C 3 4201
FID C 8 2982
FID L 11 997
FID L 12 997
FID L 13 899
FID L 15 997
FID L 16 997
SNT VIA
FID H 0 846
FID C 4 1655
FID C 6 1103
FID C 3 4202
FID C 8 2983
FID L 11 998
FID L 12 998
FID L 13 900
FID L 15 998
FID L 16 998
SNT VIA
FID H 0 847
FID C 4 1653
FID C 6 1101
FID C 3 4200
FID C 8 2981
FID L 11 996
FID L 12 996
FID L 13 898
FID L 15 996
FID L 16 996
SNT VIA
FID H 0 848
FID C 4 1644
FID C 6 1092
FID C 3 4184
FID C 8 2971
FID L 11 989
FID L 12 989
FID L 13 891
FID L 15 989
FID L 16 989
SNT VIA
FID H 0 849
FID C 4 1643
FID C 6 1091
FID C 3 4183
FID C 8 2970
FID L 11 988
FID L 12 988
FID L 13 890
FID L 15 988
FID L 16 988
SNT PLN S C 0
SNT PLN S C 0
FID C 3 4180
SNT PLN S C 0
FID C 8 2972
SNT PLN S C 0
FID C 3 4185
SNT TRC
FID C 3 4191
SNT PLN S C 0
FID C 3 4192
SNT TRC
FID C 3 4193
SNT TRC
FID C 3 4196
FID C 3 4197
# NET 17
NET UNNAMED_517_CAPACITOR_I30_1 
SNT TOP T 392 1
FID C 4 2213
FID C 5 1316
FID C 3 5477
SNT TOP T 394 0
FID C 4 2211
FID C 5 1314
FID C 3 5472
SNT TOP T 467 0
FID C 4 2212
FID C 5 1315
FID C 3 5473
SNT TRC
FID C 3 5469
FID C 3 5470
FID C 3 5471
SNT TRC
FID C 3 5474
FID C 3 5475
FID C 3 5476
# NET 18
NET XP3R3V_FB_R_TO_AGND 
SNT TOP T 181 13
FID C 4 2083
FID C 5 1246
FID C 3 5257
SNT TOP T 393 0
FID C 4 2081
FID C 5 1244
FID C 3 5255
SNT TOP T 394 1
FID C 4 2082
FID C 5 1245
FID C 3 5256
SNT TOP T 467 1
FID C 4 2084
FID C 5 1247
FID C 3 5258
SNT TOP B 114 1
FID C 6 1434
FID C 7 513
FID C 8 3745
SNT VIA
FID H 0 1381
FID C 4 2080
FID C 6 1433
FID C 3 5247
FID C 8 3744
FID L 11 1216
FID L 12 1216
FID L 13 1058
FID L 14 1008
FID L 15 1216
FID L 16 1216
SNT TRC
FID C 3 5241
FID C 3 5242
FID C 3 5243
FID C 3 5244
SNT TRC
FID C 3 5245
FID C 3 5246
SNT TRC
FID C 8 3742
FID C 8 3743
SNT TRC
FID C 3 5248
FID C 3 5249
FID C 3 5250
FID C 3 5251
SNT TRC
FID C 3 5252
FID C 3 5253
FID C 3 5254
# NET 19
NET XP3R3V 
SNT TOP T 58 0
FID H 0 179
FID C 6 1626
FID C 3 5716
FID C 8 4086
FID L 11 1331
FID L 12 1331
FID L 13 1129
FID L 14 1112
FID L 15 1331
FID L 16 1331
SNT TOP T 119 0
FID C 4 2312
FID C 5 1363
FID C 3 5705
SNT TOP T 119 2
FID C 4 2313
FID C 5 1364
FID C 3 5706
SNT TOP T 119 12
FID C 3 5709
SNT TOP T 161 0
FID C 4 2329
FID C 5 1369
FID C 3 5733
SNT TOP T 162 0
FID C 4 2333
FID C 5 1372
FID C 3 5738
SNT TOP T 163 0
FID C 4 2308
FID C 5 1360
FID C 3 5697
SNT TOP T 185 1
FID C 4 2301
FID C 5 1358
FID C 3 5689
SNT TOP T 187 7
FID C 4 2288
FID C 5 1353
FID C 3 5672
SNT TOP T 202 0
FID C 4 2342
FID C 5 1374
FID C 3 5748
SNT TOP T 383 0
FID C 4 2323
FID C 5 1367
FID C 3 5726
SNT TOP T 392 0
FID C 4 2292
FID C 5 1355
FID C 3 5680
SNT TOP T 404 0
FID C 4 2311
FID C 5 1362
FID C 3 5701
SNT TOP T 494 0
FID C 4 2336
FID C 5 1373
FID C 3 5741
SNT TOP T 496 0
FID C 4 2302
FID C 5 1359
FID C 3 5690
SNT TOP T 497 0
FID C 4 2295
FID C 5 1356
FID C 3 5683
SNT TOP T 498 0
FID C 4 2316
FID C 5 1365
FID C 3 5717
SNT TOP T 500 0
FID C 4 2296
FID C 5 1357
FID C 3 5684
SNT TOP T 537 0
FID C 4 2287
FID C 5 1352
FID C 3 5671
SNT TOP T 550 0
FID C 4 2330
FID C 5 1370
FID C 3 5734
SNT TOP T 556 0
FID C 4 2332
FID C 5 1371
FID C 3 5737
SNT TOP T 557 0
FID C 4 2291
FID C 5 1354
FID C 3 5679
SNT TOP T 560 0
FID C 4 2324
FID C 5 1368
FID C 3 5727
SNT TOP T 561 0
FID C 4 2317
FID C 5 1366
FID C 3 5718
SNT TOP T 573 0
FID C 4 2309
FID C 5 1361
FID C 3 5698
SNT TOP B 0 1
FID C 6 1643
FID C 7 587
FID C 8 4110
SNT TOP B 3 1
FID C 6 1646
FID C 7 590
FID C 8 4115
SNT TOP B 92 1
FID C 6 1648
FID C 7 591
FID C 8 4122
SNT TOP B 170 0
FID C 6 1616
FID C 7 581
FID C 8 4071
SNT TOP B 172 0
FID C 6 1617
FID C 7 582
FID C 8 4072
SNT TOP B 255 0
FID C 6 1632
FID C 7 584
FID C 8 4096
SNT TOP B 335 0
FID C 6 1639
FID C 7 586
FID C 8 4105
SNT TOP B 371 0
FID C 6 1622
FID C 7 583
FID C 8 4078
SNT TOP B 372 0
FID C 6 1633
FID C 7 585
FID C 8 4098
SNT TOP B 373 0
FID C 6 1644
FID C 7 588
FID C 8 4113
SNT TOP B 423 0
FID C 6 1645
FID C 7 589
FID C 8 4114
SNT VIA
FID H 0 873
FID C 4 2290
FID C 6 1608
FID C 3 5675
FID C 9 2290
FID C 8 4061
FID L 11 1316
FID L 12 1316
FID L 13 1127
FID L 14 1097
FID L 15 1316
FID L 16 1316
SNT VIA
FID H 0 874
FID C 4 2340
FID C 6 1650
FID C 3 5745
FID C 8 4124
FID L 11 1347
FID L 12 1347
FID L 14 1128
FID L 15 1347
FID L 16 1347
SNT VIA
FID H 0 875
FID C 4 2339
FID C 6 1649
FID C 3 5744
FID C 8 4123
FID L 11 1346
FID L 12 1346
FID L 14 1127
FID L 15 1346
FID L 16 1346
SNT VIA
FID H 0 876
FID C 4 2289
FID C 6 1607
FID C 3 5673
FID C 10 3397
FID C 8 4060
FID L 11 1315
FID L 12 1315
FID L 13 1126
FID L 14 1096
FID L 15 1315
FID L 16 1315
SNT VIA
FID H 0 877
FID C 4 2341
FID C 6 1651
FID C 3 5746
FID C 8 4125
FID L 11 1348
FID L 12 1348
FID L 14 1129
FID L 15 1348
FID L 16 1348
SNT VIA
FID H 0 878
FID C 4 2297
FID C 6 1611
FID C 3 5685
FID C 9 2293
FID C 8 4064
FID L 11 1319
FID L 12 1319
FID L 14 1100
FID L 15 1319
FID L 16 1319
SNT VIA
FID H 0 879
FID C 4 2298
FID C 6 1612
FID C 3 5686
FID C 8 4065
FID L 11 1320
FID L 12 1320
FID L 14 1101
FID L 15 1320
FID L 16 1320
SNT VIA
FID H 0 880
FID C 4 2299
FID C 6 1613
FID C 3 5687
FID C 8 4066
FID L 11 1321
FID L 12 1321
FID L 14 1102
FID L 15 1321
FID L 16 1321
SNT VIA
FID H 0 881
FID C 4 2293
FID C 6 1609
FID C 3 5681
FID C 8 4062
FID L 11 1317
FID L 12 1317
FID L 14 1098
FID L 15 1317
FID L 16 1317
SNT VIA
FID H 0 882
FID C 4 2300
FID C 6 1614
FID C 3 5688
FID C 9 2294
FID C 8 4067
FID L 11 1322
FID L 12 1322
FID L 14 1103
FID L 15 1322
FID L 16 1322
SNT VIA
FID H 0 883
FID C 4 2307
FID C 6 1621
FID C 3 5696
FID C 8 4077
FID L 11 1327
FID L 12 1327
FID L 14 1108
FID L 15 1327
FID L 16 1327
SNT VIA
FID H 0 884
FID C 4 2306
FID C 6 1620
FID C 3 5695
FID C 8 4076
FID L 11 1326
FID L 12 1326
FID L 14 1107
FID L 15 1326
FID L 16 1326
SNT VIA
FID H 0 885
FID C 4 2305
FID C 6 1619
FID C 3 5694
FID C 8 4075
FID L 11 1325
FID L 12 1325
FID L 14 1106
FID L 15 1325
FID L 16 1325
SNT VIA
FID H 0 886
FID C 4 2303
FID C 6 1615
FID C 3 5691
FID C 9 2295
FID C 8 4068
FID L 11 1323
FID L 12 1323
FID L 13 1128
FID L 14 1104
FID L 15 1323
FID L 16 1323
SNT VIA
FID H 0 887
FID C 4 2304
FID C 6 1618
FID C 3 5693
FID C 8 4074
FID L 11 1324
FID L 12 1324
FID L 14 1105
FID L 15 1324
FID L 16 1324
SNT VIA
FID H 0 888
FID C 4 2322
FID C 6 1631
FID C 3 5723
FID C 8 4095
FID L 11 1336
FID L 12 1336
FID L 13 1130
FID L 14 1117
FID L 15 1336
FID L 16 1336
SNT VIA
FID H 0 889
FID C 4 2338
FID C 6 1647
FID C 3 5743
FID C 8 4116
FID L 11 1345
FID L 12 1345
FID L 14 1126
FID L 15 1345
FID L 16 1345
SNT VIA
FID H 0 890
FID C 4 2320
FID C 6 1629
FID C 3 5721
FID C 8 4093
FID L 11 1334
FID L 12 1334
FID L 14 1115
FID L 15 1334
FID L 16 1334
SNT VIA
FID H 0 891
FID C 4 2319
FID C 6 1628
FID C 3 5720
FID C 8 4092
FID L 11 1333
FID L 12 1333
FID L 14 1114
FID L 15 1333
FID L 16 1333
SNT VIA
FID H 0 892
FID C 4 2321
FID C 6 1630
FID C 3 5722
FID C 8 4094
FID L 11 1335
FID L 12 1335
FID L 14 1116
FID L 15 1335
FID L 16 1335
SNT VIA
FID H 0 893
FID C 4 2318
FID C 6 1627
FID C 3 5719
FID C 8 4091
FID L 11 1332
FID L 12 1332
FID L 14 1113
FID L 15 1332
FID L 16 1332
SNT VIA
FID H 0 894
FID C 4 2326
FID C 6 1635
FID C 3 5730
FID C 8 4100
FID L 11 1338
FID L 12 1338
FID L 14 1119
FID L 15 1338
FID L 16 1338
SNT VIA
FID H 0 895
FID C 4 2328
FID C 6 1637
FID C 3 5732
FID C 8 4102
FID L 11 1340
FID L 12 1340
FID L 14 1121
FID L 15 1340
FID L 16 1340
SNT VIA
FID H 0 896
FID C 4 2327
FID C 6 1636
FID C 3 5731
FID C 8 4101
FID L 11 1339
FID L 12 1339
FID L 14 1120
FID L 15 1339
FID L 16 1339
SNT VIA
FID H 0 897
FID C 4 2325
FID C 6 1634
FID C 3 5729
FID C 8 4099
FID L 11 1337
FID L 12 1337
FID L 14 1118
FID L 15 1337
FID L 16 1337
SNT VIA
FID H 0 898
FID C 4 2310
FID C 6 1623
FID C 3 5699
FID C 8 4079
FID L 11 1328
FID L 12 1328
FID L 14 1109
FID L 15 1328
FID L 16 1328
SNT VIA
FID H 0 899
FID C 4 2331
FID C 6 1638
FID C 3 5735
FID C 8 4104
FID L 11 1341
FID L 12 1341
FID L 14 1122
FID L 15 1341
FID L 16 1341
SNT VIA
FID H 0 900
FID C 4 2334
FID C 6 1640
FID C 3 5739
FID C 8 4106
FID L 11 1342
FID L 12 1342
FID L 14 1123
FID L 15 1342
FID L 16 1342
SNT VIA
FID H 0 901
FID C 4 2335
FID C 6 1641
FID C 3 5740
FID C 8 4107
FID L 11 1343
FID L 12 1343
FID L 14 1124
FID L 15 1343
FID L 16 1343
SNT VIA
FID H 0 902
FID C 4 2286
FID C 6 1606
FID C 3 5670
FID C 9 2289
FID C 8 4059
FID L 11 1314
FID L 12 1314
FID L 13 1125
FID L 14 1095
FID L 15 1314
FID L 16 1314
SNT VIA
FID H 0 903
FID C 4 2285
FID C 6 1605
FID C 3 5662
FID C 9 2288
FID C 10 3396
FID C 8 4058
FID L 11 1313
FID L 12 1313
FID L 13 1124
FID L 14 1094
FID L 15 1313
FID L 16 1313
SNT VIA
FID H 0 1375
FID C 4 2294
FID C 6 1610
FID C 3 5682
FID C 8 4063
FID L 11 1318
FID L 12 1318
FID L 14 1099
FID L 15 1318
FID L 16 1318
SNT VIA
FID H 0 1962
FID C 4 2337
FID C 6 1642
FID C 3 5742
FID C 8 4108
FID L 11 1344
FID L 12 1344
FID L 14 1125
FID L 15 1344
FID L 16 1344
SNT VIA
FID H 0 2331
FID C 4 2314
FID C 6 1624
FID C 3 5712
FID C 8 4080
FID L 11 1329
FID L 12 1329
FID L 14 1110
FID L 15 1329
FID L 16 1329
SNT VIA
FID H 0 2332
FID C 4 2315
FID C 6 1625
FID C 3 5713
FID C 8 4081
FID L 11 1330
FID L 12 1330
FID L 14 1111
FID L 15 1330
FID L 16 1330
SNT PLN S C 0
SNT TRC
FID C 3 5657
SNT TRC
FID C 3 5658
FID C 3 5659
FID C 3 5660
SNT TRC
FID C 10 3387
FID C 10 3388
FID C 10 3389
FID C 10 3390
FID C 10 3391
FID C 10 3392
FID C 10 3393
FID C 10 3394
FID C 10 3395
SNT PLN S C 0
FID C 3 5661
SNT TRC
FID C 9 2272
FID C 9 2273
FID C 9 2274
FID C 9 2275
FID C 9 2276
FID C 9 2277
FID C 9 2278
SNT TRC
FID C 8 4056
FID C 8 4057
SNT TRC
FID C 9 2279
FID C 9 2280
FID C 9 2281
FID C 9 2282
FID C 9 2283
FID C 9 2284
FID C 9 2285
FID C 9 2286
FID C 9 2287
SNT TRC
FID C 3 5663
FID C 3 5664
FID C 3 5665
FID C 3 5666
SNT TRC
FID C 3 5667
FID C 3 5668
FID C 3 5669
SNT TRC
FID C 3 5674
SNT TRC
FID C 9 2291
FID C 9 2292
SNT TRC
FID C 3 5676
FID C 3 5677
FID C 3 5678
SNT TRC
FID C 8 4069
FID C 8 4070
SNT PLN S C 0
FID C 3 5692
SNT PLN S C 0
FID C 8 4073
SNT TRC
FID C 3 5700
SNT TRC
FID C 3 5702
SNT PLN S C 0
FID C 3 5703
SNT TRC
FID C 3 5704
SNT TRC
FID C 3 5707
FID C 3 5708
SNT TRC
FID C 3 5710
FID C 3 5711
SNT TRC
FID C 8 4082
FID C 8 4083
FID C 8 4084
FID C 8 4085
SNT TRC
FID C 3 5714
FID C 3 5715
SNT TRC
FID C 8 4087
FID C 8 4088
FID C 8 4089
FID C 8 4090
SNT TRC
FID C 3 5724
FID C 3 5725
SNT PLN S C 0
FID C 3 5728
SNT PLN S C 0
FID C 8 4097
SNT TRC
FID C 8 4103
SNT PLN S C 0
FID C 3 5736
SNT TRC
FID C 8 4109
SNT TRC
FID C 8 4111
FID C 8 4112
SNT TRC
FID C 8 4117
FID C 8 4118
SNT TRC
FID C 8 4119
FID C 8 4120
SNT PLN S C 0
FID C 8 4121
SNT TRC
FID C 3 5747
# NET 20
NET XP1R2V_EN_R 
SNT TOP T 118 6
FID C 4 1703
FID C 5 1006
FID C 3 4302
SNT TOP T 389 1
FID C 4 1702
FID C 5 1005
FID C 3 4298
SNT TOP T 569 0
FID C 4 1705
FID C 5 1007
FID C 3 4306
SNT TOP B 274 0
FID C 6 1127
FID C 7 360
FID C 8 3013
SNT TOP B 353 1
FID C 6 1126
FID C 7 359
FID C 8 3012
SNT VIA
FID H 0 2198
FID C 4 1704
FID C 6 1128
FID C 3 4305
FID C 8 3016
FID L 11 1015
FID L 12 1015
FID L 13 908
FID L 14 818
FID L 15 1015
FID L 16 1015
SNT TRC
FID C 8 3011
SNT TRC
FID C 8 3014
FID C 8 3015
SNT TRC
FID C 3 4297
SNT TRC
FID C 3 4299
FID C 3 4300
FID C 3 4301
SNT TRC
FID C 3 4303
FID C 3 4304
# NET 21
NET XP1R2V_VIN 
SNT TOP T 118 8
FID C 4 1671
FID C 5 986
FID C 3 4230
SNT TOP T 118 9
FID C 4 1672
FID C 5 987
FID C 3 4231
SNT TOP T 163 1
FID C 4 1668
FID C 5 983
FID C 3 4227
SNT TOP T 504 0
FID C 4 1670
FID C 5 985
FID C 3 4229
SNT TOP T 568 0
FID C 4 1669
FID C 5 984
FID C 3 4228
SNT TOP B 353 0
FID C 6 1109
FID C 7 355
FID C 8 2993
SNT VIA
FID H 0 2199
FID C 4 1673
FID C 6 1108
FID C 3 4232
FID C 8 2991
FID L 11 1001
FID L 12 1001
FID L 13 903
FID L 14 804
FID L 15 1001
FID L 16 1001
SNT PLN S C 0
FID C 3 4226
SNT TRC
FID C 8 2992
# NET 22
NET XP1R8V_VIN 
SNT TOP T 116 8
FID C 4 1609
FID C 5 947
FID C 3 4113
SNT TOP T 116 9
FID C 4 1610
FID C 5 948
FID C 3 4114
SNT TOP T 161 1
FID C 4 1613
FID C 5 950
FID C 3 4118
SNT TOP T 431 0
FID C 4 1612
FID C 5 949
FID C 3 4117
SNT TOP T 507 0
FID C 4 1614
FID C 5 951
FID C 3 4119
SNT TOP T 578 0
FID C 4 1615
FID C 5 952
FID C 3 4120
SNT VIA
FID H 0 1374
FID C 4 1611
FID C 6 1067
FID C 3 4115
FID C 8 2907
FID L 11 969
FID L 12 969
FID L 13 871
FID L 14 793
FID L 15 969
FID L 16 969
SNT PLN S C 0
FID C 3 4112
SNT TRC
FID C 3 4116
# NET 23
NET XP1R8V_EN_R 
SNT TOP T 116 6
FID C 4 1663
FID C 5 979
FID C 3 4213
SNT TOP T 385 1
FID C 4 1665
FID C 5 980
FID C 3 4221
SNT TOP T 431 1
FID C 4 1667
FID C 5 982
FID C 3 4225
SNT TOP T 563 0
FID C 4 1666
FID C 5 981
FID C 3 4222
SNT TOP B 263 0
FID C 6 1107
FID C 7 354
FID C 8 2990
SNT VIA
FID H 0 2294
FID C 4 1664
FID C 6 1106
FID C 3 4219
FID C 8 2987
FID L 11 1000
FID L 12 1000
FID L 13 902
FID L 14 803
FID L 15 1000
FID L 16 1000
SNT TRC
FID C 3 4214
FID C 3 4215
FID C 3 4216
SNT TRC
FID C 3 4217
FID C 3 4218
SNT TRC
FID C 8 2988
FID C 8 2989
SNT TRC
FID C 3 4220
SNT TRC
FID C 3 4223
FID C 3 4224
# NET 24
NET C_PCIEREFCLKP ;1=2,3=0
SNT TOP T 605 12
FID C 6 3050
FID C 8 6425
SNT TOP B 383 0
FID C 6 3051
FID C 7 883
FID C 8 6433
SNT TRC
FID C 8 6426
FID C 8 6427
FID C 8 6428
FID C 8 6429
FID C 8 6430
FID C 8 6431
FID C 8 6432
# NET 25
NET PCIE_REFCLKP ;1=2,3=0
SNT TOP T 170 163
FID C 4 1900
FID C 5 1130
FID C 3 4718
SNT TOP B 11 0
FID C 6 1305
FID C 7 457
FID C 8 3441
SNT TOP B 383 1
FID C 6 1304
FID C 7 456
FID C 8 3440
SNT VIA
FID H 0 2320
FID H 2 1
FID C 4 1899
FID C 6 1303
FID C 3 4715
FID C 10 2791
FID C 8 3431
FID L 11 1116
FID L 12 1116
FID L 13 969
FID L 14 919
FID L 15 1116
FID L 16 1116
SNT VIA
FID H 0 2571
FID C 3 4717
FID C 10 2820
FID C 8 3443
FID L 11 1117
FID L 12 1117
FID L 13 970
FID L 14 920
FID L 15 1117
FID L 16 1117
SNT TRC
FID C 8 3432
FID C 8 3433
FID C 8 3434
FID C 8 3435
FID C 8 3436
FID C 8 3437
FID C 8 3438
FID C 8 3439
SNT TRC
FID C 10 2792
FID C 10 2793
FID C 10 2794
FID C 10 2795
FID C 10 2796
FID C 10 2797
FID C 10 2798
FID C 10 2799
FID C 10 2800
FID C 10 2801
FID C 10 2802
FID C 10 2803
FID C 10 2804
FID C 10 2805
FID C 10 2806
FID C 10 2807
FID C 10 2808
FID C 10 2809
FID C 10 2810
FID C 10 2811
FID C 10 2812
FID C 10 2813
FID C 10 2814
FID C 10 2815
FID C 10 2816
FID C 10 2817
FID C 10 2818
FID C 10 2819
SNT TRC
FID C 8 3442
SNT TRC
FID C 3 4716
# NET 26
NET XP1R2V_SS 
SNT TOP T 118 5
FID C 4 1675
FID C 5 988
FID C 3 4238
SNT TOP T 465 0
FID C 4 1676
FID C 5 989
FID C 3 4239
SNT VIA
FID H 0 1372
FID C 4 1674
FID C 6 1110
FID C 3 4237
FID C 8 2994
FID L 11 1002
FID L 12 1002
FID L 13 904
FID L 14 805
FID L 15 1002
FID L 16 1002
SNT TRC
FID C 3 4233
FID C 3 4234
SNT TRC
FID C 3 4235
FID C 3 4236
# NET 27
NET XP1R8V_SS 
SNT TOP T 116 5
FID C 4 1616
FID C 5 953
FID C 3 4121
SNT TOP T 464 0
FID C 4 1618
FID C 5 954
FID C 3 4127
SNT VIA
FID H 0 2298
FID C 4 1617
FID C 6 1068
FID C 3 4124
FID C 8 2908
FID L 11 970
FID L 12 970
FID L 13 872
FID L 14 794
FID L 15 970
FID L 16 970
SNT TRC
FID C 3 4122
FID C 3 4123
SNT TRC
FID C 3 4125
FID C 3 4126
# NET 28
NET XP1R2V_PG_R 
SNT TOP T 118 3
FID C 4 1679
FID C 5 991
FID C 3 4251
SNT TOP T 382 0
FID C 4 1681
FID C 5 993
FID C 3 4253
SNT TOP T 383 1
FID C 4 1678
FID C 5 990
FID C 3 4247
SNT TOP T 463 0
FID C 4 1680
FID C 5 992
FID C 3 4252
SNT VIA
FID H 0 1371
FID C 4 1677
FID C 6 1111
FID C 3 4246
FID C 8 2995
FID L 11 1003
FID L 12 1003
FID L 13 905
FID L 14 806
FID L 15 1003
FID L 16 1003
SNT TRC
FID C 3 4240
FID C 3 4241
FID C 3 4242
SNT TRC
FID C 3 4243
FID C 3 4244
FID C 3 4245
SNT TRC
FID C 3 4248
SNT TRC
FID C 3 4249
FID C 3 4250
# NET 29
NET XP1R8V_PG_R 
SNT TOP T 116 3
FID C 4 1619
FID C 5 955
FID C 3 4132
SNT TOP T 403 0
FID C 4 1622
FID C 5 957
FID C 3 4139
SNT TOP T 404 1
FID C 4 1623
FID C 5 958
FID C 3 4141
SNT TOP T 469 0
FID C 4 1621
FID C 5 956
FID C 3 4138
SNT VIA
FID H 0 2297
FID C 4 1620
FID C 6 1069
FID C 3 4135
FID C 8 2909
FID L 11 971
FID L 12 971
FID L 13 873
FID L 14 795
FID L 15 971
FID L 16 971
SNT TRC
FID C 3 4128
FID C 3 4129
FID C 3 4130
FID C 3 4131
SNT TRC
FID C 3 4133
FID C 3 4134
SNT TRC
FID C 3 4136
FID C 3 4137
SNT TRC
FID C 3 4140
# NET 30
NET XP12R0V_IN 
SNT TOP T 22 0
FID H 0 167
FID C 6 131
FID C 3 742
FID C 8 369
FID L 11 222
FID L 12 222
FID L 13 206
FID L 15 222
FID L 16 222
SNT TOP T 160 1
FID C 4 312
FID C 5 228
FID C 3 759
SNT TOP T 164 2
FID C 3 776
SNT TOP T 176 0
FID C 4 283
FID C 5 224
FID C 3 723
SNT TOP T 177 0
FID C 4 270
FID C 5 220
FID C 3 708
SNT TOP T 178 1
FID C 4 279
FID C 5 223
FID C 3 719
SNT TOP T 189 20
FID C 4 290
FID C 5 226
FID C 3 732
SNT TOP T 189 21
FID C 4 291
FID C 5 227
FID C 3 733
SNT TOP T 189 22
FID C 3 730
SNT TOP T 189 23
FID C 3 731
SNT TOP T 189 24
FID C 3 734
SNT TOP T 189 25
FID C 3 735
SNT TOP T 326 0
FID C 4 275
FID C 5 222
FID C 3 714
SNT TOP T 337 0
FID C 4 274
FID C 5 221
FID C 3 712
SNT TOP T 530 0
FID C 4 286
FID C 5 225
FID C 3 726
SNT TOP B 358 0
FID C 6 123
FID C 7 46
FID C 8 361
SNT TOP B 359 0
FID C 6 125
FID C 7 48
FID C 8 363
SNT TOP B 360 0
FID C 6 124
FID C 7 47
FID C 8 362
SNT TOP B 361 0
FID C 6 126
FID C 7 49
FID C 8 364
SNT VIA
FID H 0 770
FID C 4 271
FID C 6 109
FID C 3 709
FID C 8 346
FID L 11 204
FID L 12 204
FID L 13 188
FID L 15 204
FID L 16 204
SNT VIA
FID H 0 771
FID C 4 273
FID C 6 111
FID C 3 711
FID C 8 348
FID L 11 206
FID L 12 206
FID L 13 190
FID L 15 206
FID L 16 206
SNT VIA
FID H 0 772
FID C 4 277
FID C 6 113
FID C 3 717
FID C 8 351
FID L 11 208
FID L 12 208
FID L 13 192
FID L 15 208
FID L 16 208
SNT VIA
FID H 0 773
FID C 4 280
FID C 6 115
FID C 3 720
FID C 8 353
FID L 11 210
FID L 12 210
FID L 13 194
FID L 15 210
FID L 16 210
SNT VIA
FID H 0 774
FID C 4 282
FID C 6 117
FID C 3 722
FID C 8 355
FID L 11 212
FID L 12 212
FID L 13 196
FID L 15 212
FID L 16 212
SNT VIA
FID H 0 775
FID C 4 306
FID C 6 142
FID C 3 753
FID C 8 380
FID L 11 233
FID L 12 233
FID L 13 217
FID L 15 233
FID L 16 233
SNT VIA
FID H 0 776
FID C 4 310
FID C 6 146
FID C 3 757
FID C 8 384
FID L 11 237
FID L 12 237
FID L 13 221
FID L 15 237
FID L 16 237
SNT VIA
FID H 0 777
FID C 4 305
FID C 6 141
FID C 3 752
FID C 8 379
FID L 11 232
FID L 12 232
FID L 13 216
FID L 15 232
FID L 16 232
SNT VIA
FID H 0 778
FID C 4 309
FID C 6 145
FID C 3 756
FID C 8 383
FID L 11 236
FID L 12 236
FID L 13 220
FID L 15 236
FID L 16 236
SNT VIA
FID H 0 779
FID C 4 316
FID C 6 151
FID C 3 763
FID C 8 389
FID L 11 242
FID L 12 242
FID L 13 226
FID L 15 242
FID L 16 242
SNT VIA
FID H 0 780
FID C 4 319
FID C 6 154
FID C 3 766
FID C 8 392
FID L 11 245
FID L 12 245
FID L 13 229
FID L 15 245
FID L 16 245
SNT VIA
FID H 0 781
FID C 4 320
FID C 6 155
FID C 3 767
FID C 8 393
FID L 11 246
FID L 12 246
FID L 13 230
FID L 15 246
FID L 16 246
SNT VIA
FID H 0 782
FID C 4 321
FID C 6 156
FID C 3 768
FID C 8 394
FID L 11 247
FID L 12 247
FID L 13 231
FID L 15 247
FID L 16 247
SNT VIA
FID H 0 783
FID C 4 315
FID C 6 150
FID C 3 762
FID C 8 388
FID L 11 241
FID L 12 241
FID L 13 225
FID L 15 241
FID L 16 241
SNT VIA
FID H 0 784
FID C 4 318
FID C 6 153
FID C 3 765
FID C 8 391
FID L 11 244
FID L 12 244
FID L 13 228
FID L 15 244
FID L 16 244
SNT VIA
FID H 0 785
FID C 4 317
FID C 6 152
FID C 3 764
FID C 8 390
FID L 11 243
FID L 12 243
FID L 13 227
FID L 15 243
FID L 16 243
SNT VIA
FID H 0 786
FID C 4 322
FID C 6 157
FID C 3 769
FID C 8 395
FID L 11 248
FID L 12 248
FID L 13 232
FID L 15 248
FID L 16 248
SNT VIA
FID H 0 787
FID C 4 314
FID C 6 149
FID C 3 761
FID C 8 387
FID L 11 240
FID L 12 240
FID L 13 224
FID L 15 240
FID L 16 240
SNT VIA
FID H 0 788
FID C 4 325
FID C 6 160
FID C 3 772
FID C 8 398
FID L 11 251
FID L 12 251
FID L 13 235
FID L 15 251
FID L 16 251
SNT VIA
FID H 0 789
FID C 4 324
FID C 6 159
FID C 3 771
FID C 8 397
FID L 11 250
FID L 12 250
FID L 13 234
FID L 15 250
FID L 16 250
SNT VIA
FID H 0 790
FID C 4 323
FID C 6 158
FID C 3 770
FID C 8 396
FID L 11 249
FID L 12 249
FID L 13 233
FID L 15 249
FID L 16 249
SNT VIA
FID H 0 791
FID C 4 313
FID C 6 148
FID C 3 760
FID C 8 386
FID L 11 239
FID L 12 239
FID L 13 223
FID L 15 239
FID L 16 239
SNT VIA
FID H 0 792
FID C 4 326
FID C 6 161
FID C 3 773
FID C 8 399
FID L 11 252
FID L 12 252
FID L 13 236
FID L 15 252
FID L 16 252
SNT VIA
FID H 0 793
FID C 4 327
FID C 6 162
FID C 3 774
FID C 8 400
FID L 11 253
FID L 12 253
FID L 13 237
FID L 15 253
FID L 16 253
SNT VIA
FID H 0 794
FID C 4 328
FID C 6 163
FID C 3 775
FID C 8 401
FID L 11 254
FID L 12 254
FID L 13 238
FID L 15 254
FID L 16 254
SNT VIA
FID H 0 795
FID C 4 296
FID C 6 132
FID C 3 743
FID C 8 370
FID L 11 223
FID L 12 223
FID L 13 207
FID L 15 223
FID L 16 223
SNT VIA
FID H 0 796
FID C 4 300
FID C 6 136
FID C 3 747
FID C 8 374
FID L 11 227
FID L 12 227
FID L 13 211
FID L 15 227
FID L 16 227
SNT VIA
FID H 0 797
FID C 4 297
FID C 6 133
FID C 3 744
FID C 8 371
FID L 11 224
FID L 12 224
FID L 13 208
FID L 15 224
FID L 16 224
SNT VIA
FID H 0 798
FID C 4 298
FID C 6 134
FID C 3 745
FID C 8 372
FID L 11 225
FID L 12 225
FID L 13 209
FID L 15 225
FID L 16 225
SNT VIA
FID H 0 799
FID C 4 303
FID C 6 139
FID C 3 750
FID C 8 377
FID L 11 230
FID L 12 230
FID L 13 214
FID L 15 230
FID L 16 230
SNT VIA
FID H 0 1352
FID C 4 269
FID C 6 108
FID C 3 707
FID C 8 345
FID L 11 203
FID L 12 203
FID L 13 187
FID L 14 203
FID L 15 203
FID L 16 203
SNT VIA
FID H 0 1353
FID C 4 272
FID C 6 110
FID C 3 710
FID C 8 347
FID L 11 205
FID L 12 205
FID L 13 189
FID L 15 205
FID L 16 205
SNT VIA
FID H 0 1354
FID C 4 284
FID C 6 118
FID C 3 724
FID C 9 21
FID C 8 356
FID L 11 213
FID L 12 213
FID L 13 197
FID L 15 213
FID L 16 213
SNT VIA
FID H 0 1355
FID C 4 278
FID C 6 114
FID C 3 718
FID C 8 352
FID L 11 209
FID L 12 209
FID L 13 193
FID L 15 209
FID L 16 209
SNT VIA
FID H 0 1356
FID C 4 281
FID C 6 116
FID C 3 721
FID C 8 354
FID L 11 211
FID L 12 211
FID L 13 195
FID L 15 211
FID L 16 211
SNT VIA
FID H 0 1357
FID C 4 304
FID C 6 140
FID C 3 751
FID C 8 378
FID L 11 231
FID L 12 231
FID L 13 215
FID L 15 231
FID L 16 231
SNT VIA
FID H 0 1358
FID C 4 308
FID C 6 144
FID C 3 755
FID C 8 382
FID L 11 235
FID L 12 235
FID L 13 219
FID L 15 235
FID L 16 235
SNT VIA
FID H 0 1359
FID C 4 307
FID C 6 143
FID C 3 754
FID C 8 381
FID L 11 234
FID L 12 234
FID L 13 218
FID L 15 234
FID L 16 234
SNT VIA
FID H 0 1360
FID C 4 311
FID C 6 147
FID C 3 758
FID C 8 385
FID L 11 238
FID L 12 238
FID L 13 222
FID L 15 238
FID L 16 238
SNT VIA
FID H 0 1361
FID C 4 299
FID C 6 135
FID C 3 746
FID C 8 373
FID L 11 226
FID L 12 226
FID L 13 210
FID L 15 226
FID L 16 226
SNT VIA
FID H 0 1362
FID C 4 302
FID C 6 138
FID C 3 749
FID C 8 376
FID L 11 229
FID L 12 229
FID L 13 213
FID L 15 229
FID L 16 229
SNT VIA
FID H 0 1363
FID C 4 301
FID C 6 137
FID C 3 748
FID C 8 375
FID L 11 228
FID L 12 228
FID L 13 212
FID L 15 228
FID L 16 228
SNT VIA
FID H 0 1948
FID C 4 295
FID C 6 130
FID C 3 739
FID C 8 368
FID L 11 221
FID L 12 221
FID L 13 205
FID L 15 221
FID L 16 221
SNT VIA
FID H 0 1949
FID C 4 294
FID C 6 129
FID C 3 738
FID C 8 367
FID L 11 220
FID L 12 220
FID L 13 204
FID L 15 220
FID L 16 220
SNT VIA
FID H 0 1950
FID C 4 293
FID C 6 128
FID C 3 737
FID C 8 366
FID L 11 219
FID L 12 219
FID L 13 203
FID L 15 219
FID L 16 219
SNT VIA
FID H 0 1951
FID C 4 292
FID C 6 127
FID C 3 736
FID C 8 365
FID L 11 218
FID L 12 218
FID L 13 202
FID L 15 218
FID L 16 218
SNT VIA
FID H 0 1952
FID C 4 289
FID C 6 122
FID C 3 729
FID C 8 360
FID L 11 217
FID L 12 217
FID L 13 201
FID L 15 217
FID L 16 217
SNT VIA
FID H 0 1953
FID C 4 285
FID C 6 119
FID C 3 725
FID C 8 357
FID L 11 214
FID L 12 214
FID L 13 198
FID L 15 214
FID L 16 214
SNT VIA
FID H 0 1954
FID C 4 287
FID C 6 120
FID C 3 727
FID C 8 358
FID L 11 215
FID L 12 215
FID L 13 199
FID L 15 215
FID L 16 215
SNT VIA
FID H 0 1955
FID C 4 288
FID C 6 121
FID C 3 728
FID C 8 359
FID L 11 216
FID L 12 216
FID L 13 200
FID L 15 216
FID L 16 216
SNT VIA
FID H 0 2289
FID C 4 276
FID C 6 112
FID C 3 715
FID C 9 20
FID C 8 350
FID L 11 207
FID L 12 207
FID L 13 191
FID L 15 207
FID L 16 207
SNT PLN S C 0
SNT PLN S C 0
FID C 3 713
SNT PLN S C 0
FID C 8 349
SNT TRC
FID C 3 716
SNT TRC
FID C 9 22
FID C 9 23
SNT PLN S C 0
FID C 3 740
SNT PLN S C 0
FID C 3 741
# NET 31
NET UNNAMED_515_CAPACITOR_I128_1 
SNT TOP T 117 6
FID C 4 1847
FID C 5 1103
FID C 3 4589
SNT TOP T 429 1
FID C 4 1846
FID C 5 1102
FID C 3 4586
SNT TOP T 551 0
FID C 4 1848
FID C 5 1104
FID C 3 4594
SNT TOP B 250 0
FID C 6 1234
FID C 7 415
FID C 8 3252
SNT TOP B 251 1
FID C 6 1236
FID C 7 417
FID C 8 3257
SNT TOP B 417 0
FID C 6 1235
FID C 7 416
FID C 8 3255
SNT VIA
FID H 0 2276
FID C 4 1849
FID C 6 1233
FID C 3 4595
FID C 8 3251
FID L 11 1087
FID L 12 1087
FID L 13 940
FID L 14 890
FID L 15 1087
FID L 16 1087
SNT TRC
FID C 8 3248
FID C 8 3249
FID C 8 3250
SNT TRC
FID C 3 4587
FID C 3 4588
SNT TRC
FID C 3 4590
FID C 3 4591
SNT TRC
FID C 3 4592
FID C 3 4593
SNT TRC
FID C 8 3253
FID C 8 3254
SNT TRC
FID C 8 3256
# NET 32
NET UNNAMED_515_CAPACITOR_I130_1 
SNT TOP T 117 8
FID C 4 1843
FID C 5 1100
FID C 3 4583
SNT TOP T 117 9
FID C 4 1844
FID C 5 1101
FID C 3 4584
SNT TOP T 162 1
FID C 4 1840
FID C 5 1097
FID C 3 4580
SNT TOP T 429 0
FID C 4 1839
FID C 5 1096
FID C 3 4579
SNT TOP T 493 0
FID C 4 1842
FID C 5 1099
FID C 3 4582
SNT TOP T 555 0
FID C 4 1841
FID C 5 1098
FID C 3 4581
SNT VIA
FID H 0 2277
FID C 4 1845
FID C 6 1232
FID C 3 4585
FID C 8 3247
FID L 11 1086
FID L 12 1086
FID L 13 939
FID L 14 889
FID L 15 1086
FID L 16 1086
SNT PLN S C 0
FID C 3 4577
SNT TRC
FID C 3 4578
# NET 33
NET XP3R3V_FPGA_EN_R 
SNT TOP T 119 1
FID C 4 1312
FID C 5 789
FID C 3 3514
SNT TOP T 269 0
FID C 4 1313
FID C 5 790
FID C 3 3515
SNT TOP B 254 1
FID C 6 798
FID C 7 210
FID C 8 2370
SNT TOP B 255 1
FID C 6 799
FID C 7 211
FID C 8 2373
SNT TOP B 427 0
FID C 6 801
FID C 7 213
FID C 8 2376
SNT TOP B 428 0
FID C 6 800
FID C 7 212
FID C 8 2374
SNT VIA
FID H 0 1387
FID C 4 1314
FID C 6 797
FID C 3 3520
FID C 8 2369
FID L 11 791
FID L 12 791
FID L 13 775
FID L 14 740
FID L 15 791
FID L 16 791
SNT TRC
FID C 3 3516
FID C 3 3517
SNT TRC
FID C 3 3518
FID C 3 3519
SNT TRC
FID C 8 2367
FID C 8 2368
SNT TRC
FID C 8 2371
SNT TRC
FID C 8 2372
SNT TRC
FID C 8 2375
# NET 34
NET C_PCIEREFCLKN ;1=2,3=0
SNT TOP T 605 13
FID C 6 3052
FID C 8 6434
SNT TOP B 384 0
FID C 6 3053
FID C 7 884
FID C 8 6442
SNT TRC
FID C 8 6435
FID C 8 6436
FID C 8 6437
FID C 8 6438
FID C 8 6439
FID C 8 6440
FID C 8 6441
# NET 35
NET PCIE_REFCLKN ;1=2,3=0
SNT TOP T 170 141
FID C 4 1902
FID C 5 1131
FID C 3 4722
SNT TOP B 11 1
FID C 6 1307
FID C 7 458
FID C 8 3447
SNT TOP B 384 1
FID C 6 1308
FID C 7 459
FID C 8 3457
SNT VIA
FID H 0 2319
FID H 2 0
FID C 4 1901
FID C 6 1306
FID C 3 4719
FID C 10 2821
FID C 8 3444
FID L 11 1118
FID L 12 1118
FID L 13 971
FID L 14 921
FID L 15 1118
FID L 16 1118
SNT VIA
FID H 0 2570
FID C 3 4721
FID C 10 2844
FID C 8 3448
FID L 11 1119
FID L 12 1119
FID L 13 972
FID L 14 922
FID L 15 1119
FID L 16 1119
SNT TRC
FID C 8 3445
FID C 8 3446
SNT TRC
FID C 10 2822
FID C 10 2823
FID C 10 2824
FID C 10 2825
FID C 10 2826
FID C 10 2827
FID C 10 2828
FID C 10 2829
FID C 10 2830
FID C 10 2831
FID C 10 2832
FID C 10 2833
FID C 10 2834
FID C 10 2835
FID C 10 2836
FID C 10 2837
FID C 10 2838
FID C 10 2839
FID C 10 2840
FID C 10 2841
FID C 10 2842
FID C 10 2843
SNT TRC
FID C 3 4720
SNT TRC
FID C 8 3449
FID C 8 3450
FID C 8 3451
FID C 8 3452
FID C 8 3453
FID C 8 3454
FID C 8 3455
FID C 8 3456
# NET 36
NET UNNAMED_515_CAPACITOR_I132_1 
SNT TOP T 117 5
FID C 4 1837
FID C 5 1094
FID C 3 4575
SNT TOP T 462 0
FID C 4 1838
FID C 5 1095
FID C 3 4576
SNT VIA
FID H 0 2278
FID C 4 1836
FID C 6 1231
FID C 3 4574
FID C 8 3246
FID L 11 1085
FID L 12 1085
FID L 13 938
FID L 14 888
FID L 15 1085
FID L 16 1085
SNT TRC
FID C 3 4570
FID C 3 4571
SNT TRC
FID C 3 4572
FID C 3 4573
# NET 37
NET UNNAMED_515_CAPACITOR_I138_1 
SNT TOP T 117 3
FID C 4 1835
FID C 5 1093
FID C 3 4569
SNT TOP T 461 0
FID C 4 1834
FID C 5 1092
FID C 3 4568
SNT TOP B 243 0
FID C 6 1229
FID C 7 413
FID C 8 3244
SNT TOP B 245 1
FID C 6 1230
FID C 7 414
FID C 8 3245
SNT VIA
FID H 0 1311
FID C 4 1833
FID C 6 1228
FID C 3 4567
FID C 8 3243
FID L 11 1084
FID L 12 1084
FID L 13 937
FID L 14 887
FID L 15 1084
FID L 16 1084
SNT TRC
FID C 3 4563
SNT TRC
FID C 3 4564
FID C 3 4565
FID C 3 4566
SNT TRC
FID C 8 3238
FID C 8 3239
SNT TRC
FID C 8 3240
FID C 8 3241
FID C 8 3242
# NET 38
NET XP3R3V_FPGA_SR 
SNT TOP T 119 4
FID C 4 1309
FID C 5 787
FID C 3 3505
SNT TOP T 559 0
FID C 4 1311
FID C 5 788
FID C 3 3513
SNT VIA
FID H 0 1388
FID C 4 1310
FID C 6 796
FID C 3 3512
FID C 8 2366
FID L 11 790
FID L 12 790
FID L 13 774
FID L 14 739
FID L 15 790
FID L 16 790
SNT TRC
FID C 3 3506
FID C 3 3507
FID C 3 3508
SNT TRC
FID C 3 3509
FID C 3 3510
FID C 3 3511
# NET 39
NET C_CPU_RX_PCIE_MGT0_TXP ;0,1=16,2=15,3=0
SNT TOP T 605 15
FID C 6 3067
FID C 8 6531
SNT TOP B 382 0
FID C 6 3066
FID C 7 891
FID C 8 6522
SNT TRC
FID C 8 6523
FID C 8 6524
FID C 8 6525
FID C 8 6526
FID C 8 6527
FID C 8 6528
FID C 8 6529
FID C 8 6530
# NET 40
NET CPU_RX_PCIE_MGT0_TXP ;0,1=16,2=15,3=0
SNT TOP T 170 69
FID C 4 3954
FID C 5 1882
FID C 3 8675
SNT TOP B 382 1
FID C 6 3091
FID C 7 899
FID C 8 6875
SNT VIA
FID H 0 2322
FID H 2 3
FID C 4 3953
FID C 6 3090
FID C 3 8672
FID C 10 4033
FID C 8 6870
FID L 11 1562
FID L 12 1562
FID L 13 2339
FID L 14 2338
FID L 15 1562
FID L 16 1562
SNT VIA
FID H 0 2578
FID H 1 15
FID C 3 8674
FID C 10 4066
FID C 8 6876
FID L 11 1563
FID L 12 1563
FID L 13 2340
FID L 14 2339
FID L 15 1563
FID L 16 1563
SNT TRC
FID C 8 6871
FID C 8 6872
FID C 8 6873
FID C 8 6874
SNT TRC
FID C 3 8673
SNT TRC
FID C 10 4034
FID C 10 4035
FID C 10 4036
FID C 10 4037
FID C 10 4038
FID C 10 4039
FID C 10 4040
FID C 10 4041
FID C 10 4042
FID C 10 4043
FID C 10 4044
FID C 10 4045
FID C 10 4046
FID C 10 4047
FID C 10 4048
FID C 10 4049
FID C 10 4050
FID C 10 4051
FID C 10 4052
FID C 10 4053
FID C 10 4054
FID C 10 4055
FID C 10 4056
FID C 10 4057
FID C 10 4058
FID C 10 4059
FID C 10 4060
FID C 10 4061
FID C 10 4062
FID C 10 4063
FID C 10 4064
FID C 10 4065
# NET 41
NET VDD3V3_OSC_200M 
SNT TOP T 166 5
FID C 4 1829
FID C 5 1089
FID C 3 4555
SNT TOP T 376 0
FID C 4 1828
FID C 5 1088
FID C 3 4554
SNT TOP B 3 0
FID C 6 1221
FID C 7 408
FID C 8 3227
SNT TOP B 424 0
FID C 6 1223
FID C 7 409
FID C 8 3229
SNT TOP B 425 0
FID C 6 1224
FID C 7 410
FID C 8 3230
SNT VIA
FID H 0 1338
FID C 4 1827
FID C 6 1222
FID C 3 4553
FID C 8 3228
FID L 11 1082
FID L 12 1082
FID L 13 935
FID L 14 885
FID L 15 1082
FID L 16 1082
SNT TRC
FID C 3 4548
FID C 3 4549
FID C 3 4550
SNT TRC
FID C 3 4551
FID C 3 4552
SNT TRC
FID C 8 3221
FID C 8 3222
SNT TRC
FID C 8 3223
FID C 8 3224
FID C 8 3225
SNT TRC
FID C 8 3226
# NET 42
NET VDD3V3_OSC_125M 
SNT TOP T 165 5
FID C 4 1826
FID C 5 1087
FID C 3 4547
SNT TOP T 195 0
FID C 4 1825
FID C 5 1086
FID C 3 4544
SNT TOP T 514 0
FID C 4 1824
FID C 5 1085
FID C 3 4539
SNT TOP T 519 0
FID C 4 1823
FID C 5 1084
FID C 3 4537
SNT TOP B 0 0
FID C 6 1220
FID C 7 407
FID C 8 3220
SNT VIA
FID H 0 2285
FID C 4 1822
FID C 6 1219
FID C 3 4536
FID C 8 3217
FID L 11 1081
FID L 12 1081
FID L 13 934
FID L 14 884
FID L 15 1081
FID L 16 1081
SNT TRC
FID C 3 4538
SNT TRC
FID C 3 4540
FID C 3 4541
SNT TRC
FID C 3 4542
FID C 3 4543
SNT TRC
FID C 3 4545
FID C 3 4546
SNT TRC
FID C 8 3218
FID C 8 3219
# NET 43
NET C_CPU_RX_PCIE_MGT0_TXN ;0,1=16,2=15,3=0
SNT TOP T 605 16
FID C 6 3069
FID C 8 6542
SNT TOP B 381 0
FID C 6 3068
FID C 7 892
FID C 8 6532
SNT TRC
FID C 8 6533
FID C 8 6534
FID C 8 6535
FID C 8 6536
FID C 8 6537
FID C 8 6538
FID C 8 6539
FID C 8 6540
FID C 8 6541
# NET 44
NET CPU_RX_PCIE_MGT0_TXN ;0,1=16,2=15,3=0
SNT TOP T 170 3
FID C 4 3956
FID C 5 1883
FID C 3 8679
SNT TOP B 381 1
FID C 6 3093
FID C 7 900
FID C 8 6881
SNT VIA
FID H 0 2321
FID H 2 2
FID C 4 3955
FID C 6 3092
FID C 3 8676
FID C 10 4067
FID C 8 6877
FID L 11 1564
FID L 12 1564
FID L 13 2341
FID L 14 2340
FID L 15 1564
FID L 16 1564
SNT VIA
FID H 0 2577
FID H 1 14
FID C 3 8678
FID C 10 4129
FID C 8 6882
FID L 11 1565
FID L 12 1565
FID L 13 2342
FID L 14 2341
FID L 15 1565
FID L 16 1565
SNT TRC
FID C 8 6878
FID C 8 6879
FID C 8 6880
SNT TRC
FID C 3 8677
SNT TRC
FID C 10 4068
FID C 10 4069
FID C 10 4070
FID C 10 4071
FID C 10 4072
FID C 10 4073
FID C 10 4074
FID C 10 4075
FID C 10 4076
FID C 10 4077
FID C 10 4078
FID C 10 4079
FID C 10 4080
FID C 10 4081
FID C 10 4082
FID C 10 4083
FID C 10 4084
FID C 10 4085
FID C 10 4086
FID C 10 4087
FID C 10 4088
FID C 10 4089
FID C 10 4090
FID C 10 4091
FID C 10 4092
FID C 10 4093
FID C 10 4094
FID C 10 4095
FID C 10 4096
FID C 10 4097
FID C 10 4098
FID C 10 4099
FID C 10 4100
FID C 10 4101
FID C 10 4102
FID C 10 4103
FID C 10 4104
FID C 10 4105
FID C 10 4106
FID C 10 4107
FID C 10 4108
FID C 10 4109
FID C 10 4110
FID C 10 4111
FID C 10 4112
FID C 10 4113
FID C 10 4114
FID C 10 4115
FID C 10 4116
FID C 10 4117
FID C 10 4118
FID C 10 4119
FID C 10 4120
FID C 10 4121
FID C 10 4122
FID C 10 4123
FID C 10 4124
FID C 10 4125
FID C 10 4126
FID C 10 4127
FID C 10 4128
# NET 45
NET UNNAMED_3_RESISTOR_I151_2 
SNT TOP T 219 1
FID C 4 21
FID C 5 14
FID C 3 75
SNT TOP T 520 0
FID C 4 24
FID C 5 16
FID C 3 78
SNT TOP T 598 3
FID C 4 23
FID C 5 15
FID C 3 77
SNT VIA
FID H 0 1310
FID C 4 22
FID C 6 11
FID C 3 76
FID C 8 17
FID L 11 10
FID L 12 10
FID L 13 10
FID L 14 10
FID L 15 10
FID L 16 10
SNT TRC
FID C 3 69
FID C 3 70
FID C 3 71
SNT TRC
FID C 3 72
FID C 3 73
SNT TRC
FID C 3 74
# NET 46
NET OSC_200M_CLKP ;1=3,3=0
SNT TOP T 166 3
FID C 4 1903
FID C 5 1132
FID C 3 4730
SNT TOP T 374 0
FID C 4 1905
FID C 5 1134
FID C 3 4737
SNT TOP T 552 0
FID C 4 1904
FID C 5 1133
FID C 3 4736
SNT TRC
FID C 3 4723
FID C 3 4724
FID C 3 4725
FID C 3 4726
FID C 3 4727
FID C 3 4728
FID C 3 4729
SNT TRC
FID C 3 4731
FID C 3 4732
FID C 3 4733
FID C 3 4734
FID C 3 4735
# NET 47
NET MHZ200CLKP_CLKIN ;1=3,3=0
SNT TOP T 170 355
FID C 4 1918
FID C 5 1146
FID C 3 4795
SNT TOP T 270 0
FID C 4 1917
FID C 5 1145
FID C 3 4793
SNT TOP T 552 1
FID C 4 1916
FID C 5 1144
FID C 3 4792
SNT TOP B 18 0
FID C 6 1311
FID C 7 461
FID C 8 3468
SNT TOP B 177 0
FID C 6 1309
FID C 7 460
FID C 8 3463
SNT VIA
FID H 0 1416
FID C 4 1915
FID C 6 1310
FID C 3 4791
FID C 10 2879
FID C 8 3464
FID L 11 1120
FID L 12 1120
FID L 13 973
FID L 14 923
FID L 15 1120
FID L 16 1120
SNT VIA
FID H 0 2569
FID C 3 4794
FID C 10 2880
FID C 8 3465
FID L 11 1121
FID L 12 1121
FID L 13 974
FID L 14 924
FID L 15 1121
FID L 16 1121
SNT TRC
FID C 10 2845
FID C 10 2846
FID C 10 2847
FID C 10 2848
FID C 10 2849
FID C 10 2850
FID C 10 2851
FID C 10 2852
FID C 10 2853
FID C 10 2854
FID C 10 2855
FID C 10 2856
FID C 10 2857
FID C 10 2858
FID C 10 2859
FID C 10 2860
FID C 10 2861
FID C 10 2862
FID C 10 2863
FID C 10 2864
FID C 10 2865
FID C 10 2866
FID C 10 2867
FID C 10 2868
FID C 10 2869
FID C 10 2870
FID C 10 2871
FID C 10 2872
FID C 10 2873
FID C 10 2874
FID C 10 2875
FID C 10 2876
FID C 10 2877
FID C 10 2878
SNT TRC
FID C 3 4780
FID C 3 4781
FID C 3 4782
FID C 3 4783
FID C 3 4784
FID C 3 4785
SNT TRC
FID C 8 3458
FID C 8 3459
FID C 8 3460
FID C 8 3461
FID C 8 3462
SNT TRC
FID C 3 4786
FID C 3 4787
FID C 3 4788
FID C 3 4789
FID C 3 4790
SNT TRC
FID C 3 4796
SNT TRC
FID C 8 3466
FID C 8 3467
# NET 48
NET OSC_200M_CLKN ;1=3,3=0
SNT TOP T 166 4
FID C 4 1907
FID C 5 1136
FID C 3 4752
SNT TOP T 375 0
FID C 4 1908
FID C 5 1137
FID C 3 4753
SNT TOP T 553 0
FID C 4 1906
FID C 5 1135
FID C 3 4751
SNT TRC
FID C 3 4738
FID C 3 4739
FID C 3 4740
FID C 3 4741
FID C 3 4742
FID C 3 4743
FID C 3 4744
FID C 3 4745
SNT TRC
FID C 3 4746
FID C 3 4747
FID C 3 4748
FID C 3 4749
FID C 3 4750
# NET 49
NET MHZ200CLKN_CLKIN ;1=3,3=0
SNT TOP T 170 377
FID C 4 1922
FID C 5 1149
FID C 3 4812
SNT TOP T 271 0
FID C 4 1921
FID C 5 1148
FID C 3 4810
SNT TOP T 553 1
FID C 4 1920
FID C 5 1147
FID C 3 4809
SNT TOP B 18 1
FID C 6 1314
FID C 7 463
FID C 8 3479
SNT TOP B 176 0
FID C 6 1312
FID C 7 462
FID C 8 3474
SNT VIA
FID H 0 1415
FID C 4 1919
FID C 6 1313
FID C 3 4808
FID C 10 2901
FID C 8 3475
FID L 11 1122
FID L 12 1122
FID L 13 975
FID L 14 925
FID L 15 1122
FID L 16 1122
SNT VIA
FID H 0 2568
FID C 3 4811
FID C 10 2902
FID C 8 3476
FID L 11 1123
FID L 12 1123
FID L 13 976
FID L 14 926
FID L 15 1123
FID L 16 1123
SNT TRC
FID C 10 2881
FID C 10 2882
FID C 10 2883
FID C 10 2884
FID C 10 2885
FID C 10 2886
FID C 10 2887
FID C 10 2888
FID C 10 2889
FID C 10 2890
FID C 10 2891
FID C 10 2892
FID C 10 2893
FID C 10 2894
FID C 10 2895
FID C 10 2896
FID C 10 2897
FID C 10 2898
FID C 10 2899
FID C 10 2900
SNT TRC
FID C 3 4797
FID C 3 4798
FID C 3 4799
FID C 3 4800
FID C 3 4801
FID C 3 4802
SNT TRC
FID C 8 3469
FID C 8 3470
FID C 8 3471
FID C 8 3472
FID C 8 3473
SNT TRC
FID C 3 4803
FID C 3 4804
FID C 3 4805
FID C 3 4806
FID C 3 4807
SNT TRC
FID C 3 4813
SNT TRC
FID C 8 3477
FID C 8 3478
# NET 50
NET OSC_125M_CLKP ;1=4,3=0
SNT TOP T 165 3
FID C 4 1910
FID C 5 1139
FID C 3 4760
SNT TOP T 194 0
FID C 4 1911
FID C 5 1140
FID C 3 4766
SNT TOP T 512 0
FID C 4 1909
FID C 5 1138
FID C 3 4759
SNT TRC
FID C 3 4754
FID C 3 4755
FID C 3 4756
FID C 3 4757
FID C 3 4758
SNT TRC
FID C 3 4761
FID C 3 4762
FID C 3 4763
FID C 3 4764
FID C 3 4765
# NET 51
NET MHZ125CLKP_CLKIN ;1=4,3=0
SNT TOP T 170 159
FID C 4 1925
FID C 5 1151
FID C 3 4822
SNT TOP T 512 1
FID C 4 1923
FID C 5 1150
FID C 3 4818
SNT TOP B 10 0
FID C 6 1316
FID C 7 464
FID C 8 3481
SNT VIA
FID H 0 1414
FID C 4 1924
FID C 6 1315
FID C 3 4819
FID C 10 2903
FID C 8 3480
FID L 11 1124
FID L 12 1124
FID L 13 977
FID L 14 927
FID L 15 1124
FID L 16 1124
SNT VIA
FID H 0 2567
FID C 3 4821
FID C 10 2916
FID C 8 3484
FID L 11 1125
FID L 12 1125
FID L 13 978
FID L 14 928
FID L 15 1125
FID L 16 1125
SNT TRC
FID C 3 4814
FID C 3 4815
FID C 3 4816
FID C 3 4817
SNT TRC
FID C 10 2904
FID C 10 2905
FID C 10 2906
FID C 10 2907
FID C 10 2908
FID C 10 2909
FID C 10 2910
FID C 10 2911
FID C 10 2912
FID C 10 2913
FID C 10 2914
FID C 10 2915
SNT TRC
FID C 3 4820
SNT TRC
FID C 8 3482
FID C 8 3483
# NET 52
NET OSC_125M_CLKN ;1=4,3=0
SNT TOP T 165 4
FID C 4 1913
FID C 5 1142
FID C 3 4773
SNT TOP T 193 0
FID C 4 1914
FID C 5 1143
FID C 3 4779
SNT TOP T 513 0
FID C 4 1912
FID C 5 1141
FID C 3 4772
SNT TRC
FID C 3 4767
FID C 3 4768
FID C 3 4769
FID C 3 4770
FID C 3 4771
SNT TRC
FID C 3 4774
FID C 3 4775
FID C 3 4776
FID C 3 4777
FID C 3 4778
# NET 53
NET MHZ125CLKN_CLKIN ;1=4,3=0
SNT TOP T 170 137
FID C 4 1928
FID C 5 1153
FID C 3 4831
SNT TOP T 513 1
FID C 4 1926
FID C 5 1152
FID C 3 4827
SNT TOP B 10 1
FID C 6 1318
FID C 7 465
FID C 8 3486
SNT VIA
FID H 0 1413
FID C 4 1927
FID C 6 1317
FID C 3 4828
FID C 10 2917
FID C 8 3485
FID L 11 1126
FID L 12 1126
FID L 13 979
FID L 14 929
FID L 15 1126
FID L 16 1126
SNT VIA
FID H 0 2566
FID C 3 4830
FID C 10 2930
FID C 8 3489
FID L 11 1127
FID L 12 1127
FID L 13 980
FID L 14 930
FID L 15 1127
FID L 16 1127
SNT TRC
FID C 3 4823
FID C 3 4824
FID C 3 4825
FID C 3 4826
SNT TRC
FID C 8 3487
FID C 8 3488
SNT TRC
FID C 10 2918
FID C 10 2919
FID C 10 2920
FID C 10 2921
FID C 10 2922
FID C 10 2923
FID C 10 2924
FID C 10 2925
FID C 10 2926
FID C 10 2927
FID C 10 2928
FID C 10 2929
SNT TRC
FID C 3 4829
# NET 54
NET UNNAMED_523_CAPACITOR_I7_1 
SNT TOP T 182 16
FID C 4 1817
FID C 5 1080
FID C 3 4524
SNT TOP T 580 0
FID C 4 1816
FID C 5 1079
FID C 3 4521
SNT TOP B 174 1
FID C 6 1210
FID C 7 400
FID C 8 3196
SNT TOP B 332 1
FID C 6 1211
FID C 7 401
FID C 8 3199
SNT TOP B 333 0
FID C 6 1212
FID C 7 402
FID C 8 3200
SNT VIA
FID H 0 2280
FID C 4 1818
FID C 6 1213
FID C 3 4527
FID C 8 3203
FID L 11 1080
FID L 12 1080
FID L 13 933
FID L 14 883
FID L 15 1080
FID L 16 1080
SNT TRC
FID C 8 3197
SNT TRC
FID C 8 3198
SNT TRC
FID C 8 3201
FID C 8 3202
SNT TRC
FID C 3 4522
FID C 3 4523
SNT TRC
FID C 3 4525
FID C 3 4526
# NET 55
NET VIN_XP1R0V 
SNT TOP T 159 1
FID C 4 1804
FID C 5 1072
FID C 3 4509
SNT TOP T 182 1
FID C 4 1812
FID C 5 1077
FID C 3 4517
SNT TOP T 182 10
FID C 4 1808
FID C 5 1074
FID C 3 4513
SNT TOP T 488 0
FID C 4 1811
FID C 5 1076
FID C 3 4516
SNT TOP T 510 0
FID C 4 1807
FID C 5 1073
FID C 3 4512
SNT TOP T 581 0
FID C 4 1809
FID C 5 1075
FID C 3 4514
SNT TOP T 584 0
FID C 4 1813
FID C 5 1078
FID C 3 4518
SNT TOP B 174 0
FID C 6 1201
FID C 7 397
FID C 8 3182
SNT VIA
FID H 0 730
FID C 4 1814
FID C 6 1205
FID C 3 4519
FID C 9 2051
FID C 8 3186
FID L 11 1078
FID L 12 1078
FID L 13 931
FID L 14 881
FID L 15 1078
FID L 16 1078
SNT VIA
FID H 0 731
FID C 4 1815
FID C 6 1206
FID C 3 4520
FID C 9 2052
FID C 8 3187
FID L 11 1079
FID L 12 1079
FID L 13 932
FID L 14 882
FID L 15 1079
FID L 16 1079
SNT VIA
FID H 0 732
FID C 4 1806
FID C 6 1203
FID C 3 4511
FID C 9 2049
FID C 8 3184
FID L 11 1076
FID L 12 1076
FID L 13 929
FID L 14 879
FID L 15 1076
FID L 16 1076
SNT VIA
FID H 0 1341
FID C 4 1810
FID C 6 1204
FID C 3 4515
FID C 9 2050
FID C 8 3185
FID L 11 1077
FID L 12 1077
FID L 13 930
FID L 14 880
FID L 15 1077
FID L 16 1077
SNT VIA
FID H 0 1342
FID C 4 1805
FID C 6 1202
FID C 3 4510
FID C 9 2048
FID C 8 3183
FID L 11 1075
FID L 12 1075
FID L 13 928
FID L 14 878
FID L 15 1075
FID L 16 1075
SNT PLN S C 0
FID C 3 4507
SNT PLN S C 0
FID C 3 4508
SNT PLN S C 0
FID C 8 3180
SNT TRC
FID C 9 2043
FID C 9 2044
FID C 9 2045
SNT PLN S C 0
FID C 9 2046
SNT TRC
FID C 9 2047
SNT TRC
FID C 8 3181
# NET 56
NET XP1R0V_PG 
SNT TOP T 182 17
FID C 4 1716
FID C 5 1015
FID C 3 4327
SNT TOP T 410 1
FID C 4 1719
FID C 5 1017
FID C 3 4334
SNT TOP T 470 1
FID C 4 1718
FID C 5 1016
FID C 3 4331
SNT TOP B 335 1
FID C 6 1134
FID C 7 363
FID C 8 3027
SNT VIA
FID H 0 2293
FID C 4 1717
FID C 6 1135
FID C 3 4330
FID C 8 3028
FID L 11 1019
FID L 12 1019
FID L 13 912
FID L 14 822
FID L 15 1019
FID L 16 1019
SNT TRC
FID C 8 3024
FID C 8 3025
FID C 8 3026
SNT TRC
FID C 3 4325
FID C 3 4326
SNT TRC
FID C 3 4328
FID C 3 4329
SNT TRC
FID C 3 4332
FID C 3 4333
# NET 57
NET XP1R0V_SS 
SNT TOP T 182 15
FID C 4 1711
FID C 5 1011
FID C 3 4316
SNT TOP T 579 0
FID C 4 1712
FID C 5 1012
FID C 3 4317
SNT TRC
FID C 3 4313
FID C 3 4314
FID C 3 4315
# NET 58
NET XP1R0V_AGND 
SNT TOP T 182 11
FID C 4 1792
FID C 5 1065
FID C 3 4484
SNT TOP T 408 1
FID C 4 1794
FID C 5 1066
FID C 3 4486
SNT TOP T 471 1
FID C 4 1799
FID C 5 1068
FID C 3 4493
SNT TOP T 579 1
FID C 4 1798
FID C 5 1067
FID C 3 4492
SNT TOP B 104 1
FID C 7 393
FID C 8 3167
SNT TOP B 115 0
FID C 6 1196
FID C 7 395
FID C 8 3175
SNT TOP B 182 0
FID C 6 1192
FID C 7 394
FID C 8 3168
SNT TOP B 354 1
FID C 6 1198
FID C 7 396
FID C 8 3177
SNT VIA
FID H 0 808
FID C 4 1797
FID C 6 1197
FID C 3 4491
FID C 9 2042
FID C 8 3176
FID L 11 1072
FID L 12 1072
FID L 13 925
FID L 14 875
FID L 15 1072
FID L 16 1072
SNT VIA
FID H 0 809
FID C 4 1793
FID C 6 1193
FID C 3 4485
FID C 9 2039
FID C 8 3171
FID L 11 1069
FID L 12 1069
FID L 13 922
FID L 14 872
FID L 15 1069
FID L 16 1069
SNT VIA
FID H 0 810
FID C 4 1796
FID C 6 1195
FID C 3 4489
FID C 9 2041
FID C 8 3173
FID L 11 1071
FID L 12 1071
FID L 13 924
FID L 14 874
FID L 15 1071
FID L 16 1071
SNT VIA
FID H 0 2290
FID C 4 1795
FID C 6 1194
FID C 3 4488
FID C 9 2040
FID C 8 3172
FID L 11 1070
FID L 12 1070
FID L 13 923
FID L 14 873
FID L 15 1070
FID L 16 1070
SNT PLN S C 0
FID C 9 2038
SNT TRC
FID C 8 3162
FID C 8 3163
FID C 8 3164
FID C 8 3165
SNT PLN S C 0
FID C 8 3166
SNT TRC
FID C 3 4479
FID C 3 4480
FID C 3 4481
SNT TRC
FID C 8 3169
FID C 8 3170
SNT TRC
FID C 3 4482
FID C 3 4483
SNT TRC
FID C 3 4487
SNT TRC
FID C 8 3174
SNT TRC
FID C 3 4490
# NET 59
NET C_CPU_RX_PCIE_MGT1_TXP ;0,1=14,2=13,3=0
SNT TOP T 605 20
FID C 6 3063
FID C 8 6511
SNT TOP B 380 0
FID C 6 3062
FID C 7 889
FID C 8 6503
SNT TRC
FID C 8 6504
FID C 8 6505
FID C 8 6506
FID C 8 6507
FID C 8 6508
FID C 8 6509
FID C 8 6510
# NET 60
NET CPU_RX_PCIE_MGT1_TXP ;0,1=14,2=13,3=0
SNT TOP T 170 114
FID C 4 3950
FID C 5 1880
FID C 3 8667
SNT TOP B 380 1
FID C 6 3087
FID C 7 897
FID C 8 6862
SNT VIA
FID H 0 2324
FID H 2 5
FID C 4 3949
FID C 6 3086
FID C 3 8664
FID C 10 3935
FID C 8 6858
FID L 11 1558
FID L 12 1558
FID L 13 2335
FID L 14 2334
FID L 15 1558
FID L 16 1558
SNT VIA
FID H 0 2580
FID H 1 17
FID C 3 8666
FID C 10 3970
FID C 8 6863
FID L 11 1559
FID L 12 1559
FID L 13 2336
FID L 14 2335
FID L 15 1559
FID L 16 1559
SNT TRC
FID C 8 6859
FID C 8 6860
FID C 8 6861
SNT TRC
FID C 3 8665
SNT TRC
FID C 10 3936
FID C 10 3937
FID C 10 3938
FID C 10 3939
FID C 10 3940
FID C 10 3941
FID C 10 3942
FID C 10 3943
FID C 10 3944
FID C 10 3945
FID C 10 3946
FID C 10 3947
FID C 10 3948
FID C 10 3949
FID C 10 3950
FID C 10 3951
FID C 10 3952
FID C 10 3953
FID C 10 3954
FID C 10 3955
FID C 10 3956
FID C 10 3957
FID C 10 3958
FID C 10 3959
FID C 10 3960
FID C 10 3961
FID C 10 3962
FID C 10 3963
FID C 10 3964
FID C 10 3965
FID C 10 3966
FID C 10 3967
FID C 10 3968
FID C 10 3969
# NET 61
NET UNNAMED_523_CAPACITOR_I9_1 
SNT TOP B 334 1
FID C 6 1209
FID C 7 399
FID C 8 3195
SNT TOP B 354 0
FID C 6 1208
FID C 7 398
FID C 8 3194
SNT VIA
FID C 6 1207
FID C 8 3193
SNT TRC
FID C 8 3188
FID C 8 3189
FID C 8 3190
SNT TRC
FID C 8 3191
FID C 8 3192
# NET 62
NET XP1R0V_COMP 
SNT TOP T 182 14
FID C 4 1788
FID C 5 1062
FID C 3 4472
SNT TOP T 471 0
FID C 4 1789
FID C 5 1063
FID C 3 4473
SNT TOP B 334 0
FID C 6 1188
FID C 7 391
FID C 8 3156
SNT VIA
FID H 0 2291
FID C 4 1787
FID C 6 1189
FID C 3 4471
FID C 8 3157
FID L 11 1067
FID L 12 1067
FID L 13 920
FID L 14 870
FID L 15 1067
FID L 16 1067
SNT TRC
FID C 3 4464
FID C 3 4465
FID C 3 4466
FID C 3 4467
SNT TRC
FID C 3 4468
FID C 3 4469
FID C 3 4470
SNT TRC
FID C 8 3154
FID C 8 3155
# NET 63
NET UNNAMED_523_CAPACITOR_I24_1 
SNT TOP B 168 1
FID C 6 1217
FID C 7 405
FID C 8 3215
SNT TOP B 441 0
FID C 6 1218
FID C 7 406
FID C 8 3216
SNT VIA
FID C 6 1216
FID C 8 3214
SNT TRC
FID C 8 3208
FID C 8 3209
FID C 8 3210
SNT TRC
FID C 8 3211
FID C 8 3212
FID C 8 3213
# NET 64
NET XP1R0V_SW 
SNT TOP T 14 0
FID C 4 1706
FID C 5 1008
FID C 3 4308
SNT TOP T 182 5
FID C 4 1709
FID C 5 1009
FID C 3 4311
SNT TOP T 182 6
FID C 4 1710
FID C 5 1010
FID C 3 4312
SNT TOP B 401 0
FID C 6 1132
FID C 7 362
FID C 8 3022
SNT TOP B 441 1
FID C 6 1131
FID C 7 361
FID C 8 3021
SNT VIA
FID H 0 831
FID C 4 1708
FID C 6 1130
FID C 3 4310
FID C 8 3019
FID L 11 1017
FID L 12 1017
FID L 13 910
FID L 14 820
FID L 15 1017
FID L 16 1017
SNT VIA
FID H 0 1369
FID C 4 1707
FID C 6 1129
FID C 3 4309
FID C 8 3018
FID L 11 1016
FID L 12 1016
FID L 13 909
FID L 14 819
FID L 15 1016
FID L 16 1016
SNT PLN S C 0
FID C 3 4307
SNT TRC
FID C 8 3017
SNT TRC
FID C 8 3020
# NET 65
NET UNNAMED_523_CAPACITOR_I31_2 
SNT TOP B 119 0
FID C 6 1214
FID C 7 403
FID C 8 3204
SNT TOP B 401 1
FID C 6 1215
FID C 7 404
FID C 8 3207
SNT TRC
FID C 8 3205
FID C 8 3206
# NET 66
NET UNNAMED_523_CAPACITOR_I28_1 
SNT TOP T 407 1
FID C 4 1819
FID C 5 1081
FID C 3 4533
SNT TOP T 409 0
FID C 4 1820
FID C 5 1082
FID C 3 4534
SNT TOP T 472 0
FID C 4 1821
FID C 5 1083
FID C 3 4535
SNT TRC
FID C 3 4528
FID C 3 4529
SNT TRC
FID C 3 4530
FID C 3 4531
FID C 3 4532
# NET 67
NET XP1R0V_FB_R_TO_AGND 
SNT TOP T 182 13
FID C 4 1784
FID C 5 1059
FID C 3 4461
SNT TOP T 409 1
FID C 4 1786
FID C 5 1061
FID C 3 4463
SNT TOP T 472 1
FID C 4 1785
FID C 5 1060
FID C 3 4462
SNT TOP B 115 1
FID C 6 1186
FID C 7 390
FID C 8 3152
SNT TOP B 182 1
FID C 6 1185
FID C 7 389
FID C 8 3149
SNT VIA
FID H 0 2292
FID C 4 1783
FID C 6 1187
FID C 3 4460
FID C 8 3153
FID L 11 1066
FID L 12 1066
FID L 13 919
FID L 14 869
FID L 15 1066
FID L 16 1066
SNT TRC
FID C 3 4453
FID C 3 4454
SNT TRC
FID C 3 4455
FID C 3 4456
FID C 3 4457
SNT TRC
FID C 8 3146
FID C 8 3147
FID C 8 3148
SNT TRC
FID C 8 3150
FID C 8 3151
SNT TRC
FID C 3 4458
FID C 3 4459
# NET 68
NET C_CPU_RX_PCIE_MGT1_TXN ;0,1=14,2=13,3=0
SNT TOP T 605 21
FID C 6 3065
FID C 8 6521
SNT TOP B 379 0
FID C 6 3064
FID C 7 890
FID C 8 6512
SNT TRC
FID C 8 6513
FID C 8 6514
FID C 8 6515
FID C 8 6516
FID C 8 6517
FID C 8 6518
FID C 8 6519
FID C 8 6520
# NET 69
NET CPU_RX_PCIE_MGT1_TXN ;0,1=14,2=13,3=0
SNT TOP T 170 92
FID C 4 3952
FID C 5 1881
FID C 3 8671
SNT TOP B 379 1
FID C 6 3089
FID C 7 898
FID C 8 6868
SNT VIA
FID H 0 2323
FID H 2 4
FID C 4 3951
FID C 6 3088
FID C 3 8668
FID C 10 3971
FID C 8 6864
FID L 11 1560
FID L 12 1560
FID L 13 2337
FID L 14 2336
FID L 15 1560
FID L 16 1560
SNT VIA
FID H 0 2579
FID H 1 16
FID C 3 8670
FID C 10 4032
FID C 8 6869
FID L 11 1561
FID L 12 1561
FID L 13 2338
FID L 14 2337
FID L 15 1561
FID L 16 1561
SNT TRC
FID C 8 6865
FID C 8 6866
FID C 8 6867
SNT TRC
FID C 3 8669
SNT TRC
FID C 10 3972
FID C 10 3973
FID C 10 3974
FID C 10 3975
FID C 10 3976
FID C 10 3977
FID C 10 3978
FID C 10 3979
FID C 10 3980
FID C 10 3981
FID C 10 3982
FID C 10 3983
FID C 10 3984
FID C 10 3985
FID C 10 3986
FID C 10 3987
FID C 10 3988
FID C 10 3989
FID C 10 3990
FID C 10 3991
FID C 10 3992
FID C 10 3993
FID C 10 3994
FID C 10 3995
FID C 10 3996
FID C 10 3997
FID C 10 3998
FID C 10 3999
FID C 10 4000
FID C 10 4001
FID C 10 4002
FID C 10 4003
FID C 10 4004
FID C 10 4005
FID C 10 4006
FID C 10 4007
FID C 10 4008
FID C 10 4009
FID C 10 4010
FID C 10 4011
FID C 10 4012
FID C 10 4013
FID C 10 4014
FID C 10 4015
FID C 10 4016
FID C 10 4017
FID C 10 4018
FID C 10 4019
FID C 10 4020
FID C 10 4021
FID C 10 4022
FID C 10 4023
FID C 10 4024
FID C 10 4025
FID C 10 4026
FID C 10 4027
FID C 10 4028
FID C 10 4029
FID C 10 4030
FID C 10 4031
# NET 70
NET XP3R3V_GPS 
SNT TOP T 155 0
FID C 4 230
FID C 5 202
FID C 3 651
SNT TOP T 167 1
FID C 4 232
FID C 5 203
FID C 3 653
SNT TOP T 506 0
FID C 4 233
FID C 5 204
FID C 3 654
SNT TOP B 294 0
FID C 6 69
FID C 7 28
FID C 8 263
SNT TOP B 435 0
FID C 6 71
FID C 7 29
FID C 8 267
SNT TOP B 436 0
FID C 6 72
FID C 7 30
FID C 8 268
SNT VIA
FID H 0 1035
FID C 4 234
FID C 6 70
FID C 3 655
FID C 8 266
FID L 11 182
FID L 12 182
FID L 13 182
FID L 14 182
FID L 15 182
FID L 16 182
SNT VIA
FID H 0 2201
FID C 4 231
FID C 6 68
FID C 3 652
FID C 8 262
FID L 11 181
FID L 12 181
FID L 13 181
FID L 14 181
FID L 15 181
FID L 16 181
SNT PLN S C 0
FID C 3 650
SNT PLN S C 0
FID C 8 261
SNT TRC
FID C 8 264
FID C 8 265
# NET 71
NET VDD3V3_SHT31A 
SNT TOP T 10 1
FID C 4 1188
FID C 5 713
FID C 3 3092
SNT TOP T 142 4
FID C 4 1187
FID C 5 712
FID C 3 3091
SNT TOP T 588 0
FID C 4 1191
FID C 5 715
FID C 3 3101
SNT TOP T 589 0
FID C 4 1190
FID C 5 714
FID C 3 3100
SNT VIA
FID H 0 1339
FID C 4 1189
FID C 6 708
FID C 3 3097
FID C 8 2148
FID L 11 702
FID L 12 702
FID L 13 686
FID L 14 651
FID L 15 702
FID L 16 702
SNT TRC
FID C 3 3093
FID C 3 3094
SNT TRC
FID C 3 3095
FID C 3 3096
SNT TRC
FID C 3 3098
SNT TRC
FID C 3 3099
# NET 72
NET XP1R8V_ICP10100 
SNT TOP T 11 1
FID C 4 1133
FID C 5 675
FID C 3 2960
SNT TOP T 148 9
FID C 4 1137
FID C 5 679
FID C 3 2967
SNT TOP T 187 0
FID C 4 1147
FID C 5 683
FID C 3 2981
SNT TOP T 263 1
FID C 4 1135
FID C 5 677
FID C 3 2963
SNT TOP T 264 1
FID C 4 1134
FID C 5 676
FID C 3 2962
SNT TOP T 304 0
FID C 4 1143
FID C 5 682
FID C 3 2973
SNT TOP T 339 0
FID C 4 1136
FID C 5 678
FID C 3 2966
SNT TOP T 533 0
FID C 4 1139
FID C 5 681
FID C 3 2969
SNT TOP T 534 0
FID C 4 1138
FID C 5 680
FID C 3 2968
SNT TOP T 538 0
FID C 4 1148
FID C 5 684
FID C 3 2983
SNT VIA
FID H 0 856
FID C 4 1144
FID C 6 691
FID C 3 2974
FID C 9 1576
FID C 8 2126
FID L 11 687
FID L 12 687
FID L 13 671
FID L 14 636
FID L 15 687
FID L 16 687
SNT VIA
FID H 0 857
FID C 4 1146
FID C 6 693
FID C 3 2977
FID C 10 2114
FID C 8 2128
FID L 11 689
FID L 12 689
FID L 13 673
FID L 14 638
FID L 15 689
FID L 16 689
SNT VIA
FID H 0 858
FID C 4 1140
FID C 6 688
FID C 3 2970
FID C 9 1573
FID C 8 2123
FID L 11 684
FID L 12 684
FID L 13 668
FID L 14 633
FID L 15 684
FID L 16 684
SNT VIA
FID H 0 1960
FID C 4 1142
FID C 6 690
FID C 3 2972
FID C 9 1575
FID C 8 2125
FID L 11 686
FID L 12 686
FID L 13 670
FID L 14 635
FID L 15 686
FID L 16 686
SNT VIA
FID H 0 1961
FID C 4 1145
FID C 6 692
FID C 3 2975
FID C 9 1577
FID C 10 2110
FID C 8 2127
FID L 11 688
FID L 12 688
FID L 13 672
FID L 14 637
FID L 15 688
FID L 16 688
SNT VIA
FID H 0 2200
FID C 4 1141
FID C 6 689
FID C 3 2971
FID C 9 1574
FID C 8 2124
FID L 11 685
FID L 12 685
FID L 13 669
FID L 14 634
FID L 15 685
FID L 16 685
SNT TRC
FID C 3 2955
FID C 3 2956
FID C 3 2957
SNT PLN S C 0
FID C 3 2958
SNT PLN S C 0
FID C 9 1572
SNT TRC
FID C 3 2959
SNT TRC
FID C 3 2961
SNT TRC
FID C 3 2964
FID C 3 2965
SNT TRC
FID C 3 2976
SNT TRC
FID C 10 2111
FID C 10 2112
FID C 10 2113
SNT TRC
FID C 3 2978
FID C 3 2979
FID C 3 2980
SNT TRC
FID C 3 2982
# NET 73
NET C_CPU_RX_PCIE_MGT2_TXP ;0,1=12,2=11,3=0
SNT TOP T 605 24
FID C 6 3059
FID C 8 6489
SNT TOP B 378 0
FID C 6 3058
FID C 7 887
FID C 8 6477
SNT TRC
FID C 8 6478
FID C 8 6479
FID C 8 6480
FID C 8 6481
FID C 8 6482
FID C 8 6483
FID C 8 6484
FID C 8 6485
FID C 8 6486
FID C 8 6487
FID C 8 6488
# NET 74
NET CPU_RX_PCIE_MGT2_TXP ;0,1=12,2=11,3=0
SNT TOP T 170 71
FID C 4 3946
FID C 5 1878
FID C 3 8659
SNT TOP B 378 1
FID C 6 3083
FID C 7 895
FID C 8 6847
SNT VIA
FID H 0 2326
FID H 2 7
FID C 4 3945
FID C 6 3082
FID C 3 8656
FID C 10 3858
FID C 8 6840
FID L 11 1554
FID L 12 1554
FID L 13 2331
FID L 14 2330
FID L 15 1554
FID L 16 1554
SNT VIA
FID H 0 2582
FID H 1 19
FID C 3 8658
FID C 10 3883
FID C 8 6848
FID L 11 1555
FID L 12 1555
FID L 13 2332
FID L 14 2331
FID L 15 1555
FID L 16 1555
SNT TRC
FID C 8 6841
FID C 8 6842
FID C 8 6843
FID C 8 6844
FID C 8 6845
FID C 8 6846
SNT TRC
FID C 3 8657
SNT TRC
FID C 10 3859
FID C 10 3860
FID C 10 3861
FID C 10 3862
FID C 10 3863
FID C 10 3864
FID C 10 3865
FID C 10 3866
FID C 10 3867
FID C 10 3868
FID C 10 3869
FID C 10 3870
FID C 10 3871
FID C 10 3872
FID C 10 3873
FID C 10 3874
FID C 10 3875
FID C 10 3876
FID C 10 3877
FID C 10 3878
FID C 10 3879
FID C 10 3880
FID C 10 3881
FID C 10 3882
# NET 75
NET VDD_BNO085 
SNT TOP T 12 0
FID C 4 1151
FID C 5 686
FID C 3 2989
SNT TOP T 149 2
FID C 4 1154
FID C 5 689
FID C 3 2995
SNT TOP T 149 27
FID C 4 1153
FID C 5 688
FID C 3 2994
SNT TOP T 590 0
FID C 4 1152
FID C 5 687
FID C 3 2990
SNT TOP T 591 0
FID C 4 1150
FID C 5 685
FID C 3 2988
SNT VIA
FID H 0 2193
FID C 4 1149
FID C 6 694
FID C 3 2987
FID C 8 2129
FID L 11 690
FID L 12 690
FID L 13 674
FID L 14 639
FID L 15 690
FID L 16 690
SNT TRC
FID C 3 2984
SNT TRC
FID C 3 2985
SNT PLN S C 0
FID C 3 2986
SNT TRC
FID C 3 2991
FID C 3 2992
FID C 3 2993
SNT TRC
FID C 3 2996
# NET 76
NET XP5R0V_MAC 
SNT TOP T 139 0
FID H 0 46
FID C 4 2271
FID C 6 1577
FID C 3 5616
FID C 8 4020
FID L 11 1303
FID L 12 1303
FID L 13 1114
FID L 14 1084
FID L 15 1303
FID L 16 1303
SNT TOP B 5 1
FID C 6 1579
FID C 7 566
FID C 8 4022
SNT TOP B 93 0
FID C 6 1578
FID C 7 565
FID C 8 4021
SNT TOP B 106 4
FID C 6 1581
FID C 7 568
FID C 8 4024
SNT TOP B 117 0
FID C 6 1582
FID C 7 569
FID C 8 4025
SNT TOP B 240 0
FID C 6 1580
FID C 7 567
FID C 8 4023
SNT TOP B 366 0
FID C 6 1584
FID C 7 571
FID C 8 4027
SNT TOP B 367 0
FID C 6 1585
FID C 7 572
FID C 8 4028
SNT TOP B 368 0
FID C 6 1583
FID C 7 570
FID C 8 4026
SNT TOP B 411 0
FID C 6 1586
FID C 7 573
FID C 8 4029
SNT TOP B 412 0
FID C 6 1588
FID C 7 575
FID C 8 4031
SNT TOP B 415 0
FID C 6 1587
FID C 7 574
FID C 8 4030
SNT PLN S C 0
FID C 8 4019
# NET 77
NET UNNAMED_525_CAPACITOR_I7_1 
SNT TOP T 8 1
FID C 4 342
FID C 5 237
FID C 3 807
SNT TOP T 9 1
FID C 4 343
FID C 5 238
FID C 3 808
SNT TOP T 151 0
FID C 4 344
FID C 5 239
FID C 3 809
SNT TOP T 477 0
FID C 4 341
FID C 5 236
FID C 3 806
SNT TOP T 523 0
FID C 4 340
FID C 5 235
FID C 3 805
SNT VIA
FID H 0 1323
FID C 4 339
FID C 6 175
FID C 3 804
FID C 8 433
FID L 11 259
FID L 12 259
FID L 13 243
FID L 14 208
FID L 15 259
FID L 16 259
SNT PLN S C 0
FID C 3 803
# NET 78
NET UNNAMED_9_BNO080LGA28_I29_CAP 
SNT TOP T 149 8
FID C 4 1172
FID C 5 702
FID C 3 3051
SNT TOP T 549 0
FID C 4 1171
FID C 5 701
FID C 3 3050
SNT VIA
FID H 0 2189
FID C 4 1170
FID C 6 701
FID C 3 3049
FID C 8 2138
FID L 11 696
FID L 12 696
FID L 13 680
FID L 14 645
FID L 15 696
FID L 16 696
SNT TRC
FID C 3 3042
FID C 3 3043
FID C 3 3044
FID C 3 3045
SNT TRC
FID C 3 3046
FID C 3 3047
FID C 3 3048
# NET 79
NET XP3R3V_EN 
SNT TOP T 56 0
FID H 0 185
FID C 6 1435
FID C 3 5259
FID C 10 3279
FID C 8 3746
FID L 11 1217
FID L 12 1217
FID L 13 1059
FID L 14 1009
FID L 15 1217
FID L 16 1217
SNT TOP T 181 16
FID C 4 2085
FID C 5 1248
FID C 3 5264
SNT TOP T 390 0
FID C 4 2086
FID C 5 1249
FID C 3 5265
SNT TOP T 572 0
FID C 4 2087
FID C 5 1250
FID C 3 5267
SNT TOP B 277 1
FID C 6 1437
FID C 7 514
FID C 8 3749
SNT TOP B 432 0
FID C 6 1438
FID C 7 515
FID C 8 3752
SNT VIA
FID H 0 908
FID C 4 2088
FID C 6 1436
FID C 3 5268
FID C 10 3280
FID C 8 3747
FID L 11 1218
FID L 12 1218
FID L 13 1060
FID L 14 1010
FID L 15 1218
FID L 16 1218
SNT TRC
FID C 10 3274
FID C 10 3275
FID C 10 3276
FID C 10 3277
FID C 10 3278
SNT TRC
FID C 3 5260
FID C 3 5261
SNT TRC
FID C 3 5262
FID C 3 5263
SNT TRC
FID C 3 5266
SNT TRC
FID C 8 3748
SNT TRC
FID C 8 3750
FID C 8 3751
# NET 80
NET XP3R3V_AUX_PCIE 
SNT TOP T 517 0
FID C 4 2280
FID C 5 1351
FID C 3 5645
SNT TOP T 518 0
FID C 4 2279
FID C 5 1350
FID C 3 5641
SNT TOP T 605 41
FID C 4 2281
FID C 3 5646
SNT TOP B 224 1
FID C 6 1603
FID C 7 580
FID C 8 4054
SNT VIA
FID H 0 906
FID C 4 2278
FID C 6 1600
FID C 3 5632
FID C 9 2261
FID C 8 4050
FID L 11 1309
FID L 12 1309
FID L 13 1120
FID L 14 1090
FID L 15 1309
FID L 16 1309
SNT VIA
FID H 0 907
FID C 4 2284
FID C 6 1604
FID C 3 5656
FID C 9 2271
FID C 8 4055
FID L 11 1312
FID L 12 1312
FID L 13 1123
FID L 14 1093
FID L 15 1312
FID L 16 1312
SNT VIA
FID H 0 1377
FID C 4 2282
FID C 6 1601
FID C 3 5654
FID C 10 3385
FID C 8 4051
FID L 11 1310
FID L 12 1310
FID L 13 1121
FID L 14 1091
FID L 15 1310
FID L 16 1310
SNT VIA
FID H 0 1378
FID C 4 2283
FID C 6 1602
FID C 3 5655
FID C 10 3386
FID C 8 4053
FID L 11 1311
FID L 12 1311
FID L 13 1122
FID L 14 1092
FID L 15 1311
FID L 16 1311
SNT TRC
FID C 3 5633
FID C 3 5634
FID C 3 5635
FID C 3 5636
FID C 3 5637
FID C 3 5638
FID C 3 5639
SNT TRC
FID C 3 5640
SNT TRC
FID C 3 5642
FID C 3 5643
FID C 3 5644
SNT TRC
FID C 10 3359
FID C 10 3360
FID C 10 3361
FID C 10 3362
FID C 10 3363
FID C 10 3364
FID C 10 3365
FID C 10 3366
FID C 10 3367
FID C 10 3368
FID C 10 3369
FID C 10 3370
FID C 10 3371
FID C 10 3372
FID C 10 3373
FID C 10 3374
FID C 10 3375
FID C 10 3376
FID C 10 3377
FID C 10 3378
FID C 10 3379
FID C 10 3380
FID C 10 3381
FID C 10 3382
FID C 10 3383
FID C 10 3384
SNT TRC
FID C 3 5647
FID C 3 5648
FID C 3 5649
FID C 3 5650
FID C 3 5651
FID C 3 5652
FID C 3 5653
SNT TRC
FID C 8 4052
SNT TRC
FID C 9 2262
FID C 9 2263
FID C 9 2264
FID C 9 2265
FID C 9 2266
FID C 9 2267
FID C 9 2268
FID C 9 2269
FID C 9 2270
# NET 81
NET XP3R3V_PCIE 
SNT TOP T 605 8
FID C 6 1593
FID C 8 4042
SNT TOP T 605 9
FID C 6 1594
FID C 8 4043
SNT TOP T 605 39
FID C 4 2273
FID C 3 5620
SNT TOP B 92 0
FID C 6 1591
FID C 7 578
FID C 8 4037
SNT TOP B 223 1
FID C 6 1599
FID C 7 579
FID C 8 4049
SNT TOP B 385 0
FID C 6 1590
FID C 7 577
FID C 8 4036
SNT TOP B 386 0
FID C 6 1589
FID C 7 576
FID C 8 4035
SNT VIA
FID H 0 1036
FID C 4 2274
FID C 6 1595
FID C 3 5621
FID C 10 3311
FID C 8 4044
FID L 11 1305
FID L 12 1305
FID L 13 1116
FID L 14 1086
FID L 15 1305
FID L 16 1305
SNT VIA
FID H 0 1037
FID C 4 2275
FID C 6 1596
FID C 3 5622
FID C 10 3322
FID C 8 4045
FID L 11 1306
FID L 12 1306
FID L 13 1117
FID L 14 1087
FID L 15 1306
FID L 16 1306
SNT VIA
FID H 0 1391
FID C 4 2276
FID C 6 1597
FID C 3 5630
FID C 10 3357
FID C 8 4046
FID L 11 1307
FID L 12 1307
FID L 13 1118
FID L 14 1088
FID L 15 1307
FID L 16 1307
SNT VIA
FID H 0 1392
FID C 4 2277
FID C 6 1598
FID C 3 5631
FID C 10 3358
FID C 8 4047
FID L 11 1308
FID L 12 1308
FID L 13 1119
FID L 14 1089
FID L 15 1308
FID L 16 1308
SNT VIA
FID H 0 1973
FID C 4 2272
FID C 6 1592
FID C 3 5617
FID C 8 4041
FID L 11 1304
FID L 12 1304
FID L 13 1115
FID L 14 1085
FID L 15 1304
FID L 16 1304
SNT TRC
FID C 8 4032
SNT PLN S C 0
FID C 8 4033
SNT TRC
FID C 8 4034
SNT TRC
FID C 8 4038
SNT TRC
FID C 8 4039
FID C 8 4040
SNT TRC
FID C 3 5618
FID C 3 5619
SNT TRC
FID C 10 3312
FID C 10 3313
FID C 10 3314
FID C 10 3315
FID C 10 3316
FID C 10 3317
FID C 10 3318
FID C 10 3319
FID C 10 3320
FID C 10 3321
SNT TRC
FID C 10 3323
FID C 10 3324
FID C 10 3325
FID C 10 3326
FID C 10 3327
FID C 10 3328
FID C 10 3329
FID C 10 3330
FID C 10 3331
FID C 10 3332
FID C 10 3333
FID C 10 3334
FID C 10 3335
FID C 10 3336
FID C 10 3337
FID C 10 3338
FID C 10 3339
FID C 10 3340
FID C 10 3341
FID C 10 3342
FID C 10 3343
FID C 10 3344
FID C 10 3345
FID C 10 3346
FID C 10 3347
FID C 10 3348
FID C 10 3349
FID C 10 3350
FID C 10 3351
FID C 10 3352
FID C 10 3353
FID C 10 3354
FID C 10 3355
FID C 10 3356
SNT TRC
FID C 3 5623
FID C 3 5624
FID C 3 5625
FID C 3 5626
FID C 3 5627
FID C 3 5628
FID C 3 5629
SNT TRC
FID C 8 4048
# NET 82
NET R_XP5R0V_EN 
SNT TOP T 180 16
FID C 4 2239
FID C 5 1334
FID C 3 5544
SNT TOP T 541 0
FID C 4 2240
FID C 5 1335
FID C 3 5545
SNT TOP B 171 1
FID C 6 1545
FID C 7 549
FID C 8 3928
SNT TOP B 219 0
FID C 6 1548
FID C 7 550
FID C 8 3940
SNT TOP B 220 1
FID C 6 1549
FID C 7 551
FID C 8 3941
SNT VIA
FID C 6 1547
FID C 8 3936
SNT VIA
FID H 0 1434
FID C 4 2241
FID C 6 1546
FID C 3 5546
FID C 8 3932
FID L 11 1289
FID L 12 1289
FID L 13 1100
FID L 14 1070
FID L 15 1289
FID L 16 1289
SNT TRC
FID C 8 3929
FID C 8 3930
FID C 8 3931
SNT TRC
FID C 3 5540
FID C 3 5541
SNT TRC
FID C 3 5542
FID C 3 5543
SNT TRC
FID C 8 3933
FID C 8 3934
FID C 8 3935
SNT TRC
FID C 8 3937
FID C 8 3938
SNT TRC
FID C 8 3939
# NET 83
NET XP12R0V_A_EN 
SNT TOP T 21 0
FID H 0 168
FID C 6 1471
FID C 3 5372
FID C 8 3800
FID L 11 1245
FID L 12 1245
FID L 13 1075
FID L 14 1026
FID L 15 1245
FID L 16 1245
SNT TOP T 189 0
FID C 4 2137
FID C 5 1274
FID C 3 5371
SNT TOP T 326 1
FID C 4 2138
FID C 5 1275
FID C 3 5375
SNT TOP T 350 0
FID C 4 2139
FID C 5 1276
FID C 3 5378
SNT TOP T 529 0
FID C 4 2140
FID C 5 1277
FID C 3 5385
SNT VIA
FID H 0 2194
FID C 4 2141
FID C 6 1472
FID C 3 5386
FID C 8 3801
FID L 11 1246
FID L 12 1246
FID L 13 1076
FID L 14 1027
FID L 15 1246
FID L 16 1246
SNT TRC
FID C 3 5373
FID C 3 5374
SNT TRC
FID C 3 5376
SNT TRC
FID C 3 5377
SNT TRC
FID C 3 5379
FID C 3 5380
FID C 3 5381
FID C 3 5382
FID C 3 5383
SNT TRC
FID C 3 5384
# NET 84
NET VIN_XP5R0V 
SNT TOP T 157 1
FID C 4 2183
FID C 5 1300
FID C 3 5439
SNT TOP T 180 1
FID C 4 2187
FID C 5 1304
FID C 3 5443
SNT TOP T 180 10
FID C 4 2186
FID C 5 1303
FID C 3 5442
SNT TOP T 481 0
FID C 4 2185
FID C 5 1302
FID C 3 5441
SNT TOP T 482 0
FID C 4 2189
FID C 5 1306
FID C 3 5445
SNT TOP T 539 0
FID C 4 2184
FID C 5 1301
FID C 3 5440
SNT TOP T 540 0
FID C 4 2188
FID C 5 1305
FID C 3 5444
SNT TOP B 171 0
FID C 6 1495
FID C 7 525
FID C 8 3828
SNT VIA
FID H 0 740
FID C 4 2194
FID C 6 1500
FID C 3 5450
FID C 9 2247
FID C 8 3833
FID L 11 1271
FID L 12 1271
FID L 13 1082
FID L 14 1052
FID L 15 1271
FID L 16 1271
SNT VIA
FID H 0 741
FID C 4 2190
FID C 6 1496
FID C 3 5446
FID C 9 2243
FID C 8 3829
FID L 11 1267
FID L 12 1267
FID L 13 1078
FID L 14 1048
FID L 15 1267
FID L 16 1267
SNT VIA
FID H 0 742
FID C 4 2191
FID C 6 1497
FID C 3 5447
FID C 9 2244
FID C 8 3830
FID L 11 1268
FID L 12 1268
FID L 13 1079
FID L 14 1049
FID L 15 1268
FID L 16 1268
SNT VIA
FID H 0 743
FID C 4 2193
FID C 6 1499
FID C 3 5449
FID C 9 2246
FID C 8 3832
FID L 11 1270
FID L 12 1270
FID L 13 1081
FID L 14 1051
FID L 15 1270
FID L 16 1270
SNT VIA
FID H 0 2286
FID C 4 2192
FID C 6 1498
FID C 3 5448
FID C 9 2245
FID C 8 3831
FID L 11 1269
FID L 12 1269
FID L 13 1080
FID L 14 1050
FID L 15 1269
FID L 16 1269
SNT VIA
FID H 0 2287
FID C 4 2195
FID C 6 1501
FID C 3 5451
FID C 9 2248
FID C 8 3834
FID L 11 1272
FID L 12 1272
FID L 13 1083
FID L 14 1053
FID L 15 1272
FID L 16 1272
SNT PLN S C 0
FID C 9 2242
SNT PLN S C 0
FID C 3 5437
SNT PLN S C 0
FID C 3 5438
SNT TRC
FID C 8 3826
FID C 8 3827
# NET 85
NET UNNAMED_525_CAPACITOR_I16_1 
SNT TOP T 115 8
FID C 4 348
FID C 5 242
FID C 3 818
SNT TOP T 115 9
FID C 4 349
FID C 5 243
FID C 3 819
SNT TOP T 151 1
FID C 4 353
FID C 5 246
FID C 3 823
SNT TOP T 224 0
FID C 4 352
FID C 5 245
FID C 3 822
SNT TOP T 508 0
FID C 4 350
FID C 5 244
FID C 3 820
SNT TOP T 525 0
FID C 4 354
FID C 5 247
FID C 3 824
SNT VIA
FID H 0 1321
FID C 4 351
FID C 6 177
FID C 3 821
FID C 8 435
FID L 11 261
FID L 12 261
FID L 13 245
FID L 14 210
FID L 15 261
FID L 16 261
SNT PLN S C 0
FID C 3 817
# NET 86
NET UNNAMED_525_CAPACITOR_I14_1 
SNT TOP T 115 6
FID C 4 355
FID C 5 248
FID C 3 825
SNT TOP T 224 1
FID C 4 358
FID C 5 250
FID C 3 834
SNT TOP T 524 0
FID C 4 357
FID C 5 249
FID C 3 832
SNT TOP B 157 0
FID C 6 178
FID C 7 57
FID C 8 438
SNT VIA
FID H 0 1320
FID C 4 356
FID C 6 179
FID C 3 831
FID C 8 439
FID L 11 262
FID L 12 262
FID L 13 246
FID L 14 211
FID L 15 262
FID L 16 262
SNT TRC
FID C 3 826
FID C 3 827
SNT TRC
FID C 8 436
FID C 8 437
SNT TRC
FID C 3 828
FID C 3 829
FID C 3 830
SNT TRC
FID C 3 833
# NET 87
NET UNNAMED_525_CAPACITOR_I18_1 
SNT TOP T 115 5
FID C 4 345
FID C 5 240
FID C 3 810
SNT TOP T 451 0
FID C 4 347
FID C 5 241
FID C 3 816
SNT VIA
FID H 0 1322
FID C 4 346
FID C 6 176
FID C 3 815
FID C 8 434
FID L 11 260
FID L 12 260
FID L 13 244
FID L 14 209
FID L 15 260
FID L 16 260
SNT TRC
FID C 3 811
FID C 3 812
FID C 3 813
SNT TRC
FID C 3 814
# NET 88
NET XP3R3V_FT4232 
SNT TOP T 13 19
FID C 4 245
FID C 5 207
FID C 3 673
SNT TOP T 13 30
FID C 4 263
FID C 5 217
FID C 3 699
SNT TOP T 13 41
FID C 4 261
FID C 5 216
FID C 3 695
SNT TOP T 13 49
FID C 4 251
FID C 5 209
FID C 3 682
SNT TOP T 13 55
FID C 4 250
FID C 5 208
FID C 3 679
SNT TOP T 80 0
FID H 0 153
FID C 6 100
FID C 3 691
FID C 8 334
FID L 11 197
FID L 12 197
FID L 14 197
FID L 15 197
FID L 16 197
SNT TOP T 115 0
FID C 4 255
FID C 5 211
FID C 3 687
SNT TOP T 115 1
FID C 4 254
FID C 5 210
FID C 3 686
SNT TOP T 152 1
FID C 4 256
FID C 5 212
FID C 3 688
SNT TOP T 241 1
FID C 4 266
FID C 5 218
FID C 3 703
SNT TOP T 242 1
FID C 4 268
FID C 5 219
FID C 3 706
SNT TOP T 248 0
FID C 4 259
FID C 5 215
FID C 3 692
SNT TOP T 476 0
FID C 4 257
FID C 5 213
FID C 3 689
SNT TOP T 521 0
FID C 4 258
FID C 5 214
FID C 3 690
SNT TOP B 1 0
FID C 6 79
FID C 7 32
FID C 8 297
SNT TOP B 2 0
FID C 6 87
FID C 7 37
FID C 8 310
SNT TOP B 96 0
FID C 6 80
FID C 7 33
FID C 8 298
SNT TOP B 107 5
FID C 6 82
FID C 7 34
FID C 8 301
SNT TOP B 107 7
FID C 6 84
FID C 7 35
FID C 8 304
SNT TOP B 154 1
FID C 6 105
FID C 7 45
FID C 8 342
SNT TOP B 155 1
FID C 6 104
FID C 7 44
FID C 8 341
SNT TOP B 156 1
FID C 6 90
FID C 7 39
FID C 8 315
SNT TOP B 158 0
FID C 6 94
FID C 7 42
FID C 8 326
SNT TOP B 159 0
FID C 6 92
FID C 7 41
FID C 8 324
SNT TOP B 160 0
FID C 6 91
FID C 7 40
FID C 8 323
SNT TOP B 306 1
FID C 6 77
FID C 7 31
FID C 8 291
SNT TOP B 345 1
FID C 6 98
FID C 7 43
FID C 8 332
SNT TOP B 402 0
FID C 6 85
FID C 7 36
FID C 8 307
SNT TOP B 438 0
FID C 6 88
FID C 7 38
FID C 8 311
SNT VIA
FID H 0 1018
FID C 4 267
FID C 6 107
FID C 3 705
FID C 8 344
FID L 11 202
FID L 12 202
FID L 14 202
FID L 15 202
FID L 16 202
SNT VIA
FID H 0 1019
FID C 4 244
FID C 6 86
FID C 3 670
FID C 8 309
FID L 11 190
FID L 12 190
FID L 14 190
FID L 15 190
FID L 16 190
SNT VIA
FID H 0 1020
FID C 4 260
FID C 6 101
FID C 3 693
FID C 8 335
FID L 11 198
FID L 12 198
FID L 14 198
FID L 15 198
FID L 16 198
SNT VIA
FID H 0 1021
FID C 4 265
FID C 6 106
FID C 3 702
FID C 8 343
FID L 11 201
FID L 12 201
FID L 14 201
FID L 15 201
FID L 16 201
SNT VIA
FID H 0 1022
FID C 4 241
FID C 6 78
FID C 3 667
FID C 8 296
FID L 11 187
FID L 12 187
FID L 14 187
FID L 15 187
FID L 16 187
SNT VIA
FID H 0 1023
FID C 4 252
FID C 6 97
FID C 3 683
FID C 8 331
FID L 11 195
FID L 12 195
FID L 14 195
FID L 15 195
FID L 16 195
SNT VIA
FID H 0 1024
FID C 4 249
FID C 6 96
FID C 3 677
FID C 8 328
FID L 11 194
FID L 12 194
FID L 14 194
FID L 15 194
FID L 16 194
SNT VIA
FID H 0 1025
FID C 4 253
FID C 6 99
FID C 3 685
FID C 8 333
FID L 11 196
FID L 12 196
FID L 14 196
FID L 15 196
FID L 16 196
SNT VIA
FID H 0 1026
FID C 4 239
FID C 6 75
FID C 3 665
FID C 10 40
FID C 8 288
FID L 11 185
FID L 12 185
FID L 14 185
FID L 15 185
FID L 16 185
SNT VIA
FID H 0 1027
FID C 4 243
FID C 6 83
FID C 3 669
FID C 8 302
FID L 11 189
FID L 12 189
FID L 14 189
FID L 15 189
FID L 16 189
SNT VIA
FID H 0 1028
FID C 4 242
FID C 6 81
FID C 3 668
FID C 8 299
FID L 11 188
FID L 12 188
FID L 14 188
FID L 15 188
FID L 16 188
SNT VIA
FID H 0 1029
FID C 4 247
FID C 6 93
FID C 3 675
FID C 10 56
FID C 8 325
FID L 11 192
FID L 12 192
FID L 13 186
FID L 14 192
FID L 15 192
FID L 16 192
SNT VIA
FID H 0 1030
FID C 4 248
FID C 6 95
FID C 3 676
FID C 10 57
FID C 8 327
FID L 11 193
FID L 12 193
FID L 14 193
FID L 15 193
FID L 16 193
SNT VIA
FID H 0 1031
FID C 4 264
FID C 6 103
FID C 3 700
FID C 8 339
FID L 11 200
FID L 12 200
FID L 14 200
FID L 15 200
FID L 16 200
SNT VIA
FID H 0 1032
FID C 4 262
FID C 6 102
FID C 3 698
FID C 8 336
FID L 11 199
FID L 12 199
FID L 14 199
FID L 15 199
FID L 16 199
SNT VIA
FID H 0 1033
FID C 4 246
FID C 6 89
FID C 3 674
FID C 8 314
FID L 11 191
FID L 12 191
FID L 14 191
FID L 15 191
FID L 16 191
SNT VIA
FID H 0 1389
FID C 4 240
FID C 6 76
FID C 3 666
FID C 10 53
FID C 8 290
FID L 11 186
FID L 12 186
FID L 13 185
FID L 14 186
FID L 15 186
FID L 16 186
SNT PLN S C 0
SNT TRC
FID C 10 41
FID C 10 42
FID C 10 43
FID C 10 44
FID C 10 45
FID C 10 46
FID C 10 47
FID C 10 48
FID C 10 49
FID C 10 50
FID C 10 51
FID C 10 52
SNT TRC
FID C 8 289
SNT TRC
FID C 8 292
FID C 8 293
SNT TRC
FID C 8 294
FID C 8 295
SNT TRC
FID C 8 300
SNT TRC
FID C 8 303
SNT TRC
FID C 8 305
FID C 8 306
SNT PLN S C 0
FID C 8 308
SNT TRC
FID C 8 312
FID C 8 313
SNT TRC
FID C 3 671
FID C 3 672
SNT TRC
FID C 10 54
FID C 10 55
SNT TRC
FID C 8 316
FID C 8 317
SNT TRC
FID C 8 318
FID C 8 319
FID C 8 320
SNT TRC
FID C 8 321
FID C 8 322
SNT TRC
FID C 3 678
SNT TRC
FID C 3 680
FID C 3 681
SNT TRC
FID C 8 329
FID C 8 330
SNT PLN S C 0
FID C 3 684
SNT TRC
FID C 3 694
SNT TRC
FID C 3 696
FID C 3 697
SNT TRC
FID C 8 337
FID C 8 338
SNT TRC
FID C 8 340
SNT TRC
FID C 3 701
SNT TRC
FID C 3 704
# NET 89
NET XP5R0V_SS 
SNT TOP T 180 15
FID C 4 2018
FID C 5 1212
FID C 3 5128
SNT TOP T 542 0
FID C 4 2017
FID C 5 1211
FID C 3 5127
SNT VIA
FID H 0 2303
FID C 4 2016
FID C 6 1385
FID C 3 5121
FID C 8 3654
FID L 11 1183
FID L 12 1183
FID L 13 1036
FID L 14 975
FID L 15 1183
FID L 16 1183
SNT TRC
FID C 3 5122
FID C 3 5123
SNT TRC
FID C 3 5124
FID C 3 5125
FID C 3 5126
# NET 90
NET XP5R0V_AGND 
SNT TOP T 180 11
FID C 4 2036
FID C 5 1224
FID C 3 5178
SNT TOP T 345 1
FID C 4 2039
FID C 5 1225
FID C 3 5183
SNT TOP T 455 1
FID C 4 2041
FID C 5 1226
FID C 3 5187
SNT TOP T 542 1
FID C 4 2042
FID C 5 1227
FID C 3 5190
SNT TOP B 102 1
FID C 7 503
FID C 8 3685
SNT TOP B 110 1
FID C 6 1396
FID C 7 502
FID C 8 3679
SNT TOP B 112 0
FID C 6 1400
FID C 7 505
FID C 8 3689
SNT TOP B 399 1
FID C 6 1398
FID C 7 504
FID C 8 3687
SNT VIA
FID H 0 1058
FID C 4 2040
FID C 6 1402
FID C 3 5184
FID C 10 3236
FID C 8 3691
FID L 11 1192
FID L 12 1192
FID L 13 1045
FID L 14 984
FID L 15 1192
FID L 16 1192
SNT VIA
FID H 0 1059
FID C 4 2037
FID C 6 1399
FID C 3 5179
FID C 10 3234
FID C 8 3688
FID L 11 1190
FID L 12 1190
FID L 13 1043
FID L 14 982
FID L 15 1190
FID L 16 1190
SNT VIA
FID H 0 1060
FID C 4 2035
FID C 6 1397
FID C 3 5175
FID C 10 3233
FID C 8 3686
FID L 11 1189
FID L 12 1189
FID L 13 1042
FID L 14 981
FID L 15 1189
FID L 16 1189
SNT VIA
FID H 0 2299
FID C 4 2038
FID C 6 1401
FID C 3 5180
FID C 10 3235
FID C 8 3690
FID L 11 1191
FID L 12 1191
FID L 13 1044
FID L 14 983
FID L 15 1191
FID L 16 1191
SNT PLN S C 0
FID C 10 3232
SNT TRC
FID C 8 3675
FID C 8 3676
FID C 8 3677
FID C 8 3678
SNT TRC
FID C 8 3680
FID C 8 3681
FID C 8 3682
SNT TRC
FID C 8 3683
SNT PLN S C 0
FID C 8 3684
SNT TRC
FID C 3 5176
FID C 3 5177
SNT TRC
FID C 3 5181
FID C 3 5182
SNT TRC
FID C 3 5185
FID C 3 5186
SNT TRC
FID C 3 5188
FID C 3 5189
# NET 91
NET UNNAMED_12_CAPACITOR_I318_2 
SNT TOP T 447 1
FID C 4 63
FID C 5 46
FID C 3 198
SNT TOP B 124 0
FID C 6 44
FID C 7 19
FID C 8 84
SNT VIA
FID H 0 1268
FID C 4 64
FID C 6 45
FID C 3 199
FID C 8 85
FID L 11 31
FID L 12 31
FID L 13 31
FID L 14 31
FID L 15 31
FID L 16 31
SNT TRC
FID C 8 82
FID C 8 83
SNT TRC
FID C 3 197
# NET 92
NET UNNAMED_12_CAPACITOR_I321_2 
SNT TOP T 448 1
FID C 4 61
FID C 5 45
FID C 3 195
SNT TOP B 125 0
FID C 6 42
FID C 7 18
FID C 8 80
SNT VIA
FID H 0 1269
FID C 4 62
FID C 6 43
FID C 3 196
FID C 8 81
FID L 11 30
FID L 12 30
FID L 13 30
FID L 14 30
FID L 15 30
FID L 16 30
SNT TRC
FID C 8 77
FID C 8 78
FID C 8 79
SNT TRC
FID C 3 193
FID C 3 194
# NET 93
NET RGB_LED_SHUTDOWN_N 
SNT TOP T 39 0
FID H 0 148
FID C 6 16
FID C 3 109
FID C 8 24
FID L 11 17
FID L 12 17
FID L 13 17
FID L 14 17
FID L 15 17
FID L 16 17
SNT TOP T 120 0
FID C 4 36
FID C 5 24
FID C 3 108
SNT TOP T 386 1
FID C 4 37
FID C 5 25
FID C 3 114
SNT TOP B 264 1
FID C 6 17
FID C 7 4
FID C 8 25
SNT TOP B 431 0
FID C 6 18
FID C 7 5
FID C 8 29
SNT TRC
FID C 3 110
FID C 3 111
FID C 3 112
FID C 3 113
SNT TRC
FID C 8 26
FID C 8 27
FID C 8 28
SNT TRC
FID C 8 30
SNT TRC
FID C 3 115
# NET 94
NET UNNAMED_12_CAPACITOR_I328_2 
SNT TOP T 449 1
FID C 4 59
FID C 5 44
FID C 3 191
SNT TOP B 126 0
FID C 6 41
FID C 7 17
FID C 8 76
SNT VIA
FID H 0 1270
FID C 4 60
FID C 6 40
FID C 3 192
FID C 8 75
FID L 11 29
FID L 12 29
FID L 13 29
FID L 14 29
FID L 15 29
FID L 16 29
SNT TRC
FID C 8 72
FID C 8 73
FID C 8 74
SNT TRC
FID C 3 189
FID C 3 190
# NET 95
NET UNNAMED_12_CAPACITOR_I332_2 
SNT TOP T 450 1
FID C 4 57
FID C 5 43
FID C 3 187
SNT TOP B 127 0
FID C 6 39
FID C 7 16
FID C 8 71
SNT VIA
FID H 0 1271
FID C 4 58
FID C 6 38
FID C 3 188
FID C 8 70
FID L 11 28
FID L 12 28
FID L 13 28
FID L 14 28
FID L 15 28
FID L 16 28
SNT TRC
FID C 3 185
FID C 3 186
SNT TRC
FID C 8 67
FID C 8 68
FID C 8 69
# NET 96
NET C_CPU_RX_PCIE_MGT2_TXN ;0,1=12,2=11,3=0
SNT TOP T 605 25
FID C 6 3061
FID C 8 6502
SNT TOP B 377 0
FID C 6 3060
FID C 7 888
FID C 8 6490
SNT TRC
FID C 8 6491
FID C 8 6492
FID C 8 6493
FID C 8 6494
FID C 8 6495
FID C 8 6496
FID C 8 6497
FID C 8 6498
FID C 8 6499
FID C 8 6500
FID C 8 6501
# NET 97
NET CPU_RX_PCIE_MGT2_TXN ;0,1=12,2=11,3=0
SNT TOP T 170 5
FID C 4 3948
FID C 5 1879
FID C 3 8663
SNT TOP B 377 1
FID C 6 3085
FID C 7 896
FID C 8 6856
SNT VIA
FID H 0 2325
FID H 2 6
FID C 4 3947
FID C 6 3084
FID C 3 8660
FID C 10 3884
FID C 8 6849
FID L 11 1556
FID L 12 1556
FID L 13 2333
FID L 14 2332
FID L 15 1556
FID L 16 1556
SNT VIA
FID H 0 2581
FID H 1 18
FID C 3 8662
FID C 10 3934
FID C 8 6857
FID L 11 1557
FID L 12 1557
FID L 13 2334
FID L 14 2333
FID L 15 1557
FID L 16 1557
SNT TRC
FID C 8 6850
FID C 8 6851
FID C 8 6852
FID C 8 6853
FID C 8 6854
FID C 8 6855
SNT TRC
FID C 3 8661
SNT TRC
FID C 10 3885
FID C 10 3886
FID C 10 3887
FID C 10 3888
FID C 10 3889
FID C 10 3890
FID C 10 3891
FID C 10 3892
FID C 10 3893
FID C 10 3894
FID C 10 3895
FID C 10 3896
FID C 10 3897
FID C 10 3898
FID C 10 3899
FID C 10 3900
FID C 10 3901
FID C 10 3902
FID C 10 3903
FID C 10 3904
FID C 10 3905
FID C 10 3906
FID C 10 3907
FID C 10 3908
FID C 10 3909
FID C 10 3910
FID C 10 3911
FID C 10 3912
FID C 10 3913
FID C 10 3914
FID C 10 3915
FID C 10 3916
FID C 10 3917
FID C 10 3918
FID C 10 3919
FID C 10 3920
FID C 10 3921
FID C 10 3922
FID C 10 3923
FID C 10 3924
FID C 10 3925
FID C 10 3926
FID C 10 3927
FID C 10 3928
FID C 10 3929
FID C 10 3930
FID C 10 3931
FID C 10 3932
FID C 10 3933
# NET 98
NET C_CPU_RX_PCIE_MGT3_TXP ;0,1=10,2=9,3=0
SNT TOP T 605 28
FID C 6 3055
FID C 8 6459
SNT TOP B 376 0
FID C 6 3054
FID C 7 885
FID C 8 6443
SNT TRC
FID C 8 6444
FID C 8 6445
FID C 8 6446
FID C 8 6447
FID C 8 6448
FID C 8 6449
FID C 8 6450
FID C 8 6451
FID C 8 6452
FID C 8 6453
FID C 8 6454
FID C 8 6455
FID C 8 6456
FID C 8 6457
FID C 8 6458
# NET 99
NET CPU_RX_PCIE_MGT3_TXP ;0,1=10,2=9,3=0
SNT TOP T 170 116
FID C 4 3942
FID C 5 1876
FID C 3 8651
SNT TOP B 376 1
FID C 6 3079
FID C 7 893
FID C 8 6829
SNT VIA
FID H 0 2328
FID H 2 9
FID C 4 3941
FID C 6 3078
FID C 3 8648
FID C 10 3772
FID C 8 6822
FID L 11 1550
FID L 12 1550
FID L 13 2327
FID L 14 2326
FID L 15 1550
FID L 16 1550
SNT VIA
FID H 0 2584
FID H 1 21
FID C 3 8650
FID C 10 3801
FID C 8 6830
FID L 11 1551
FID L 12 1551
FID L 13 2328
FID L 14 2327
FID L 15 1551
FID L 16 1551
SNT TRC
FID C 8 6823
FID C 8 6824
FID C 8 6825
FID C 8 6826
FID C 8 6827
FID C 8 6828
SNT TRC
FID C 3 8649
SNT TRC
FID C 10 3773
FID C 10 3774
FID C 10 3775
FID C 10 3776
FID C 10 3777
FID C 10 3778
FID C 10 3779
FID C 10 3780
FID C 10 3781
FID C 10 3782
FID C 10 3783
FID C 10 3784
FID C 10 3785
FID C 10 3786
FID C 10 3787
FID C 10 3788
FID C 10 3789
FID C 10 3790
FID C 10 3791
FID C 10 3792
FID C 10 3793
FID C 10 3794
FID C 10 3795
FID C 10 3796
FID C 10 3797
FID C 10 3798
FID C 10 3799
FID C 10 3800
# NET 100
NET C_CPU_RX_PCIE_MGT3_TXN ;0,1=10,2=9,3=0
SNT TOP T 605 29
FID C 6 3057
FID C 8 6476
SNT TOP B 375 0
FID C 6 3056
FID C 7 886
FID C 8 6460
SNT TRC
FID C 8 6461
FID C 8 6462
FID C 8 6463
FID C 8 6464
FID C 8 6465
FID C 8 6466
FID C 8 6467
FID C 8 6468
FID C 8 6469
FID C 8 6470
FID C 8 6471
FID C 8 6472
FID C 8 6473
FID C 8 6474
FID C 8 6475
# NET 101
NET CPU_RX_PCIE_MGT3_TXN ;0,1=10,2=9,3=0
SNT TOP T 170 94
FID C 4 3944
FID C 5 1877
FID C 3 8655
SNT TOP B 375 1
FID C 6 3081
FID C 7 894
FID C 8 6838
SNT VIA
FID H 0 2327
FID H 2 8
FID C 4 3943
FID C 6 3080
FID C 3 8652
FID C 10 3802
FID C 8 6831
FID L 11 1552
FID L 12 1552
FID L 13 2329
FID L 14 2328
FID L 15 1552
FID L 16 1552
SNT VIA
FID H 0 2583
FID H 1 20
FID C 3 8654
FID C 10 3857
FID C 8 6839
FID L 11 1553
FID L 12 1553
FID L 13 2330
FID L 14 2329
FID L 15 1553
FID L 16 1553
SNT TRC
FID C 8 6832
FID C 8 6833
FID C 8 6834
FID C 8 6835
FID C 8 6836
FID C 8 6837
SNT TRC
FID C 3 8653
SNT TRC
FID C 10 3803
FID C 10 3804
FID C 10 3805
FID C 10 3806
FID C 10 3807
FID C 10 3808
FID C 10 3809
FID C 10 3810
FID C 10 3811
FID C 10 3812
FID C 10 3813
FID C 10 3814
FID C 10 3815
FID C 10 3816
FID C 10 3817
FID C 10 3818
FID C 10 3819
FID C 10 3820
FID C 10 3821
FID C 10 3822
FID C 10 3823
FID C 10 3824
FID C 10 3825
FID C 10 3826
FID C 10 3827
FID C 10 3828
FID C 10 3829
FID C 10 3830
FID C 10 3831
FID C 10 3832
FID C 10 3833
FID C 10 3834
FID C 10 3835
FID C 10 3836
FID C 10 3837
FID C 10 3838
FID C 10 3839
FID C 10 3840
FID C 10 3841
FID C 10 3842
FID C 10 3843
FID C 10 3844
FID C 10 3845
FID C 10 3846
FID C 10 3847
FID C 10 3848
FID C 10 3849
FID C 10 3850
FID C 10 3851
FID C 10 3852
FID C 10 3853
FID C 10 3854
FID C 10 3855
FID C 10 3856
# NET 102
NET VDD_PCA9546A 
SNT TOP T 566 0
FID C 4 787
FID C 5 487
FID C 3 2114
SNT TOP T 604 15
FID C 4 786
FID C 5 486
FID C 3 2113
SNT TOP B 165 0
FID C 6 479
FID C 7 151
FID C 8 1350
SNT TOP B 166 0
FID C 6 480
FID C 7 152
FID C 8 1351
SNT VIA
FID H 0 729
FID C 4 788
FID C 6 478
FID C 3 2115
FID C 10 793
FID C 8 1349
FID L 11 479
FID L 12 479
FID L 13 463
FID L 14 428
FID L 15 479
FID L 16 479
SNT VIA
FID H 0 1340
FID C 4 785
FID C 6 477
FID C 3 2112
FID C 10 792
FID C 8 1346
FID L 11 478
FID L 12 478
FID L 13 462
FID L 14 427
FID L 15 478
FID L 16 478
SNT TRC
FID C 10 790
FID C 10 791
SNT TRC
FID C 3 2109
SNT TRC
FID C 3 2110
FID C 3 2111
SNT TRC
FID C 8 1347
FID C 8 1348
SNT TRC
FID C 8 1352
# NET 103
NET XP12R0V_A_TIMER 
SNT TOP T 189 3
FID C 4 2102
FID C 5 1259
FID C 3 5302
SNT TOP T 452 1
FID C 4 2104
FID C 5 1260
FID C 3 5308
SNT VIA
FID H 0 1350
FID C 4 2103
FID C 6 1448
FID C 3 5303
FID C 8 3773
FID L 11 1224
FID L 12 1224
FID L 13 1066
FID L 14 1016
FID L 15 1224
FID L 16 1224
SNT TRC
FID C 3 5304
FID C 3 5305
FID C 3 5306
SNT TRC
FID C 3 5307
# NET 104
NET UNNAMED_516_CAPACITOR_I13_1 
SNT TOP B 218 1
FID C 6 1531
FID C 7 543
FID C 8 3903
SNT TOP B 399 0
FID C 6 1530
FID C 7 542
FID C 8 3901
SNT TRC
FID C 8 3902
# NET 105
NET XP5R0V_COMP 
SNT TOP T 180 14
FID C 4 2031
FID C 5 1222
FID C 3 5168
SNT TOP T 455 0
FID C 4 2030
FID C 5 1221
FID C 3 5165
SNT TOP B 218 0
FID C 6 1393
FID C 7 500
FID C 8 3670
SNT VIA
FID H 0 2300
FID C 4 2032
FID C 6 1392
FID C 3 5169
FID C 8 3667
FID L 11 1187
FID L 12 1187
FID L 13 1040
FID L 14 979
FID L 15 1187
FID L 16 1187
SNT TRC
FID C 3 5163
FID C 3 5164
SNT TRC
FID C 3 5166
FID C 3 5167
SNT TRC
FID C 8 3668
FID C 8 3669
# NET 106
NET UNNAMED_516_CAPACITOR_I27_1 
SNT TOP B 163 1
FID C 6 1528
FID C 7 540
FID C 8 3899
SNT TOP B 398 0
FID C 6 1529
FID C 7 541
FID C 8 3900
SNT VIA
FID C 6 1527
FID C 8 3898
SNT TRC
FID C 8 3894
FID C 8 3895
SNT TRC
FID C 8 3896
FID C 8 3897
# NET 107
NET XP5R0V_SW 
SNT TOP T 180 5
FID C 4 2014
FID C 5 1209
FID C 3 5119
SNT TOP T 180 6
FID C 4 2015
FID C 5 1210
FID C 3 5120
SNT TOP T 184 0
FID C 4 2012
FID C 5 1208
FID C 3 5117
SNT TOP B 397 0
FID C 6 1382
FID C 7 495
FID C 8 3651
SNT TOP B 398 1
FID C 6 1384
FID C 7 496
FID C 8 3653
SNT VIA
FID H 0 1065
FID C 4 2013
FID C 6 1383
FID C 3 5118
FID C 8 3652
FID L 11 1182
FID L 12 1182
FID L 13 1035
FID L 14 974
FID L 15 1182
FID L 16 1182
SNT VIA
FID H 0 1400
FID C 4 2011
FID C 6 1381
FID C 3 5116
FID C 8 3650
FID L 11 1181
FID L 12 1181
FID L 13 1034
FID L 14 973
FID L 15 1181
FID L 16 1181
SNT PLN S C 0
FID C 3 5113
SNT TRC
FID C 3 5114
FID C 3 5115
SNT TRC
FID C 8 3645
FID C 8 3646
FID C 8 3647
SNT TRC
FID C 8 3648
FID C 8 3649
# NET 108
NET UNNAMED_516_CAPACITOR_I37_2 
SNT TOP B 116 0
FID C 6 1524
FID C 7 538
FID C 8 3889
SNT TOP B 397 1
FID C 6 1525
FID C 7 539
FID C 8 3892
SNT TRC
FID C 8 3890
FID C 8 3891
# NET 109
NET UNNAMED_9_BNO080LGA28_I29_XOUT3 
SNT TOP T 149 25
FID C 4 1156
FID C 5 690
FID C 3 3002
SNT TOP T 192 0
FID C 4 1157
FID C 5 691
FID C 3 3003
SNT TOP T 460 0
FID C 4 1158
FID C 5 692
FID C 3 3007
SNT TOP B 308 1
FID C 6 695
FID C 7 187
FID C 8 2130
SNT VIA
FID H 0 727
FID C 4 1155
FID C 6 696
FID C 3 3001
FID C 8 2133
FID L 11 691
FID L 12 691
FID L 13 675
FID L 14 640
FID L 15 691
FID L 16 691
SNT TRC
FID C 8 2131
FID C 8 2132
SNT TRC
FID C 3 2997
FID C 3 2998
FID C 3 2999
SNT TRC
FID C 3 3000
SNT TRC
FID C 3 3004
FID C 3 3005
FID C 3 3006
# NET 110
NET VIN_XP3R3 
SNT TOP T 158 1
FID C 4 2196
FID C 5 1307
FID C 3 5454
SNT TOP T 181 1
FID C 4 2203
FID C 5 1310
FID C 3 5461
SNT TOP T 181 10
FID C 4 2204
FID C 5 1311
FID C 3 5462
SNT TOP T 495 0
FID C 4 2206
FID C 5 1313
FID C 3 5464
SNT TOP T 505 0
FID C 4 2198
FID C 5 1309
FID C 3 5456
SNT TOP T 558 0
FID C 4 2205
FID C 5 1312
FID C 3 5463
SNT TOP T 575 0
FID C 4 2197
FID C 5 1308
FID C 3 5455
SNT TOP B 277 0
FID C 6 1509
FID C 7 526
FID C 8 3842
SNT VIA
FID H 0 733
FID C 4 2201
FID C 6 1504
FID C 3 5459
FID C 9 2255
FID C 8 3837
FID L 11 1275
FID L 12 1275
FID L 13 1086
FID L 14 1056
FID L 15 1275
FID L 16 1275
SNT VIA
FID H 0 734
FID C 4 2200
FID C 6 1503
FID C 3 5458
FID C 9 2254
FID C 8 3836
FID L 11 1274
FID L 12 1274
FID L 13 1085
FID L 14 1055
FID L 15 1274
FID L 16 1274
SNT VIA
FID H 0 735
FID C 4 2209
FID C 6 1508
FID C 3 5467
FID C 9 2259
FID C 8 3841
FID L 11 1279
FID L 12 1279
FID L 13 1090
FID L 14 1060
FID L 15 1279
FID L 16 1279
SNT VIA
FID H 0 736
FID C 4 2208
FID C 6 1507
FID C 3 5466
FID C 9 2258
FID C 8 3840
FID L 11 1278
FID L 12 1278
FID L 13 1089
FID L 14 1059
FID L 15 1278
FID L 16 1278
SNT VIA
FID H 0 737
FID C 4 2207
FID C 6 1506
FID C 3 5465
FID C 9 2257
FID C 8 3839
FID L 11 1277
FID L 12 1277
FID L 13 1088
FID L 14 1058
FID L 15 1277
FID L 16 1277
SNT VIA
FID H 0 738
FID C 4 2199
FID C 6 1502
FID C 3 5457
FID C 9 2253
FID C 8 3835
FID L 11 1273
FID L 12 1273
FID L 13 1084
FID L 14 1054
FID L 15 1273
FID L 16 1273
SNT VIA
FID H 0 739
FID C 4 2210
FID C 6 1510
FID C 3 5468
FID C 9 2260
FID C 8 3845
FID L 11 1280
FID L 12 1280
FID L 13 1091
FID L 14 1061
FID L 15 1280
FID L 16 1280
SNT VIA
FID H 0 1343
FID C 4 2202
FID C 6 1505
FID C 3 5460
FID C 9 2256
FID C 8 3838
FID L 11 1276
FID L 12 1276
FID L 13 1087
FID L 14 1057
FID L 15 1276
FID L 16 1276
SNT PLN S C 0
FID C 9 2249
SNT PLN S C 0
FID C 3 5452
SNT PLN S C 0
FID C 3 5453
SNT TRC
FID C 9 2250
FID C 9 2251
FID C 9 2252
SNT TRC
FID C 8 3843
FID C 8 3844
# NET 111
NET XP3R3V_SS 
SNT TOP T 181 15
FID C 4 2075
FID C 5 1240
FID C 3 5233
SNT TOP T 571 0
FID C 4 2076
FID C 5 1241
FID C 3 5234
SNT TRC
FID C 3 5229
FID C 3 5230
FID C 3 5231
FID C 3 5232
# NET 112
NET XP3R3V_AGND 
SNT TOP T 181 11
FID C 4 2101
FID C 5 1258
FID C 3 5301
SNT TOP T 391 1
FID C 4 2098
FID C 5 1256
FID C 3 5298
SNT TOP T 393 1
FID C 4 2099
FID C 5 1257
FID C 3 5299
SNT TOP T 466 1
FID C 4 2096
FID C 5 1255
FID C 3 5294
SNT TOP T 571 1
FID C 4 2095
FID C 5 1254
FID C 3 5290
SNT TOP B 103 1
FID C 7 519
FID C 8 3769
SNT TOP B 114 0
FID C 6 1444
FID C 7 518
FID C 8 3765
SNT TOP B 433 1
FID C 6 1446
FID C 7 520
FID C 8 3771
SNT VIA
FID H 0 904
FID C 4 2100
FID C 6 1447
FID C 3 5300
FID C 10 3284
FID C 8 3772
FID L 11 1223
FID L 12 1223
FID L 13 1065
FID L 14 1015
FID L 15 1223
FID L 16 1223
SNT VIA
FID H 0 905
FID C 4 2094
FID C 6 1443
FID C 3 5289
FID C 10 3282
FID C 8 3764
FID L 11 1221
FID L 12 1221
FID L 13 1063
FID L 14 1013
FID L 15 1221
FID L 16 1221
SNT VIA
FID H 0 1376
FID C 4 2097
FID C 6 1445
FID C 3 5297
FID C 10 3283
FID C 8 3768
FID L 11 1222
FID L 12 1222
FID L 13 1064
FID L 14 1014
FID L 15 1222
FID L 16 1222
SNT PLN S C 0
FID C 10 3281
SNT TRC
FID C 8 3761
FID C 8 3762
FID C 8 3763
SNT TRC
FID C 3 5283
FID C 3 5284
FID C 3 5285
SNT TRC
FID C 3 5286
SNT TRC
FID C 3 5287
FID C 3 5288
SNT TRC
FID C 3 5291
FID C 3 5292
FID C 3 5293
SNT TRC
FID C 3 5295
FID C 3 5296
SNT TRC
FID C 8 3766
FID C 8 3767
SNT PLN S C 0
FID C 8 3770
# NET 113
NET XP12R0V_A_SS 
SNT TOP T 189 5
FID C 4 2105
FID C 5 1261
FID C 3 5309
SNT TOP T 531 0
FID C 4 2107
FID C 5 1262
FID C 3 5315
SNT VIA
FID H 0 1349
FID C 4 2106
FID C 6 1449
FID C 3 5310
FID C 8 3774
FID L 11 1225
FID L 12 1225
FID L 13 1067
FID L 14 1017
FID L 15 1225
FID L 16 1225
SNT TRC
FID C 3 5311
FID C 3 5312
FID C 3 5313
SNT TRC
FID C 3 5314
# NET 114
NET UNNAMED_9_CAPACITOR_I17_1 
SNT TOP T 149 26
FID C 4 2364
FID C 5 1378
FID C 3 5785
SNT TOP T 192 1
FID C 4 2365
FID C 5 1379
FID C 3 5786
SNT TOP T 459 0
FID C 4 2362
FID C 5 1377
FID C 3 5778
SNT TOP B 308 0
FID C 6 1668
FID C 7 592
FID C 8 4145
SNT VIA
FID H 0 728
FID C 4 2363
FID C 6 1669
FID C 3 5784
FID C 8 4148
FID L 11 1363
FID L 12 1363
FID L 13 1131
FID L 14 1130
FID L 15 1363
FID L 16 1363
SNT TRC
FID C 3 5776
FID C 3 5777
SNT TRC
FID C 8 4146
FID C 8 4147
SNT TRC
FID C 3 5779
FID C 3 5780
FID C 3 5781
SNT TRC
FID C 3 5782
FID C 3 5783
# NET 115
NET UNNAMED_517_CAPACITOR_I17_1 
SNT TOP B 276 1
FID C 6 1523
FID C 7 537
FID C 8 3888
SNT TOP B 433 0
FID C 6 1522
FID C 7 536
FID C 8 3887
SNT TRC
FID C 8 3886
# NET 116
NET XP3R3V_COMP 
SNT TOP T 181 14
FID C 4 2090
FID C 5 1251
FID C 3 5276
SNT TOP T 466 0
FID C 4 2091
FID C 5 1252
FID C 3 5277
SNT TOP B 276 0
FID C 6 1440
FID C 7 516
FID C 8 3756
SNT VIA
FID H 0 1380
FID C 4 2089
FID C 6 1439
FID C 3 5275
FID C 8 3755
FID L 11 1219
FID L 12 1219
FID L 13 1061
FID L 14 1011
FID L 15 1219
FID L 16 1219
SNT TRC
FID C 8 3753
FID C 8 3754
SNT TRC
FID C 3 5269
FID C 3 5270
FID C 3 5271
SNT TRC
FID C 3 5272
FID C 3 5273
FID C 3 5274
# NET 117
NET UNNAMED_517_CAPACITOR_I27_1 
SNT TOP B 164 1
FID C 6 1520
FID C 7 534
FID C 8 3884
SNT TOP B 434 0
FID C 6 1521
FID C 7 535
FID C 8 3885
SNT VIA
FID C 6 1519
FID C 8 3883
SNT TRC
FID C 8 3879
FID C 8 3880
SNT TRC
FID C 8 3881
FID C 8 3882
# NET 118
NET XP3R3V_SW 
SNT TOP T 181 5
FID C 4 2072
FID C 5 1237
FID C 3 5226
SNT TOP T 181 6
FID C 4 2073
FID C 5 1238
FID C 3 5227
SNT TOP T 185 0
FID C 4 2074
FID C 5 1239
FID C 3 5228
SNT TOP B 426 0
FID C 6 1428
FID C 7 510
FID C 8 3724
SNT TOP B 434 1
FID C 6 1426
FID C 7 509
FID C 8 3720
SNT VIA
FID H 0 1039
FID C 4 2071
FID C 6 1427
FID C 3 5225
FID C 8 3723
FID L 11 1213
FID L 12 1213
FID L 13 1055
FID L 14 1005
FID L 15 1213
FID L 16 1213
SNT VIA
FID H 0 1393
FID C 4 2070
FID C 6 1425
FID C 3 5224
FID C 8 3719
FID L 11 1212
FID L 12 1212
FID L 13 1054
FID L 14 1004
FID L 15 1212
FID L 16 1212
SNT PLN S C 0
FID C 3 5223
SNT TRC
FID C 8 3717
FID C 8 3718
SNT TRC
FID C 8 3721
FID C 8 3722
# NET 119
NET UNNAMED_517_CAPACITOR_I29_2 
SNT TOP B 118 0
FID C 6 1518
FID C 7 533
FID C 8 3878
SNT TOP B 426 1
FID C 6 1517
FID C 7 532
FID C 8 3876
SNT TRC
FID C 8 3877
# NET 120
NET XP12R0V_A_AVIN 
SNT TOP T 177 1
FID C 4 2144
FID C 5 1280
FID C 3 5390
SNT TOP T 189 11
FID C 4 2142
FID C 5 1278
FID C 3 5388
SNT TOP T 480 0
FID C 4 2143
FID C 5 1279
FID C 3 5389
SNT VIA
FID H 0 1346
FID C 4 2145
FID C 6 1473
FID C 3 5391
FID C 8 3802
FID L 11 1247
FID L 12 1247
FID L 13 1077
FID L 14 1028
FID L 15 1247
FID L 16 1247
SNT PLN S C 0
FID C 3 5387
# NET 121
NET XP5R0V_USB_CONN 
SNT TOP T 511 0
FID C 4 2009
FID C 5 1207
FID C 3 5111
SNT TOP T 586 0
FID C 4 2008
FID C 5 1206
FID C 3 5110
SNT TOP T 600 4
FID C 4 2004
FID C 5 1204
FID C 3 5104
SNT TOP T 603 0
FID C 4 2006
FID C 5 1205
FID C 3 5108
SNT TOP B 244 0
FID C 6 1378
FID C 7 494
FID C 8 3642
SNT VIA
FID H 0 1066
FID C 4 2007
FID C 6 1379
FID C 3 5109
FID C 8 3643
FID L 11 1179
FID L 12 1179
FID L 13 1032
FID L 14 971
FID L 15 1179
FID L 16 1179
SNT VIA
FID H 0 1974
FID C 4 2005
FID C 6 1377
FID C 3 5105
FID C 8 3641
FID L 11 1178
FID L 12 1178
FID L 13 1031
FID L 14 970
FID L 15 1178
FID L 16 1178
SNT VIA
FID H 0 2304
FID C 4 2010
FID C 6 1380
FID C 3 5112
FID C 8 3644
FID L 11 1180
FID L 12 1180
FID L 13 1033
FID L 14 972
FID L 15 1180
FID L 16 1180
SNT PLN S C 0
FID C 3 5102
SNT TRC
FID C 8 3636
FID C 8 3637
FID C 8 3638
SNT TRC
FID C 3 5103
SNT TRC
FID C 8 3639
FID C 8 3640
SNT TRC
FID C 3 5106
FID C 3 5107
# NET 122
NET XP5R0V_MAC_USB 
SNT TOP T 169 5
FID C 4 2270
FID C 5 1349
FID C 3 5615
SNT TOP B 106 0
FID C 6 1573
FID C 7 561
FID C 8 4015
SNT TOP B 113 1
FID C 6 1574
FID C 7 562
FID C 8 4016
SNT TOP B 364 0
FID C 6 1575
FID C 7 563
FID C 8 4017
SNT TOP B 405 0
FID C 6 1576
FID C 7 564
FID C 8 4018
SNT TOP B 406 0
FID C 6 1571
FID C 7 559
FID C 8 4013
SNT TOP B 410 0
FID C 6 1572
FID C 7 560
FID C 8 4014
SNT VIA
FID C 6 1570
FID C 8 4012
SNT VIA
FID H 0 1063
FID C 4 2268
FID C 6 1568
FID C 3 5609
FID C 8 4010
FID L 11 1301
FID L 12 1301
FID L 13 1112
FID L 14 1082
FID L 15 1301
FID L 16 1301
SNT VIA
FID H 0 1064
FID C 4 2269
FID C 6 1569
FID C 3 5612
FID C 8 4011
FID L 11 1302
FID L 12 1302
FID L 13 1113
FID L 14 1083
FID L 15 1302
FID L 16 1302
SNT PLN S C 0
FID C 8 4009
SNT TRC
FID C 3 5610
FID C 3 5611
SNT TRC
FID C 3 5613
FID C 3 5614
# NET 123
NET USB_PWR_EN 
SNT TOP B 4 0
FID C 6 1511
FID C 7 527
FID C 8 3855
SNT TOP B 106 3
FID C 6 1515
FID C 7 530
FID C 8 3874
SNT TOP B 248 1
FID C 6 1514
FID C 7 529
FID C 8 3873
SNT TOP B 413 0
FID C 6 1516
FID C 7 531
FID C 8 3875
SNT TOP B 444 3
FID C 6 1513
FID C 7 528
FID C 8 3869
SNT VIA
FID C 6 1512
FID C 8 3861
SNT TRC
FID C 8 3846
FID C 8 3847
FID C 8 3848
FID C 8 3849
FID C 8 3850
FID C 8 3851
FID C 8 3852
FID C 8 3853
FID C 8 3854
SNT TRC
FID C 8 3856
FID C 8 3857
FID C 8 3858
FID C 8 3859
FID C 8 3860
SNT TRC
FID C 8 3862
FID C 8 3863
FID C 8 3864
FID C 8 3865
FID C 8 3866
FID C 8 3867
FID C 8 3868
SNT TRC
FID C 8 3870
SNT TRC
FID C 8 3871
SNT TRC
FID C 8 3872
# NET 124
NET XP12R0V_A_IMON 
SNT TOP T 189 7
FID C 4 2116
FID C 5 1269
FID C 3 5336
SNT TOP T 532 0
FID C 4 2117
FID C 5 1270
FID C 3 5340
SNT TOP B 199 0
FID C 6 1452
FID C 7 521
FID C 8 3777
SNT VIA
FID H 0 1347
FID C 4 2118
FID C 6 1453
FID C 3 5343
FID C 8 3780
FID L 11 1228
FID L 12 1228
FID L 13 1070
FID L 14 1020
FID L 15 1228
FID L 16 1228
SNT TRC
FID C 8 3778
FID C 8 3779
SNT TRC
FID C 3 5337
FID C 3 5338
FID C 3 5339
SNT TRC
FID C 3 5341
FID C 3 5342
# NET 125
NET XP5R0V_VCC_ANT 
SNT TOP T 154 1
FID C 4 2263
FID C 5 1346
FID C 3 5604
SNT TOP T 167 0
FID C 4 2266
FID C 5 1347
FID C 3 5607
SNT TOP T 503 0
FID C 4 2267
FID C 5 1348
FID C 3 5608
SNT TOP B 429 0
FID C 6 1566
FID C 7 558
FID C 8 4007
SNT TOP B 430 0
FID C 6 1565
FID C 7 557
FID C 8 4006
SNT VIA
FID H 0 1069
FID C 4 2265
FID C 6 1567
FID C 3 5606
FID C 8 4008
FID L 11 1300
FID L 12 1300
FID L 13 1111
FID L 14 1081
FID L 15 1300
FID L 16 1300
SNT VIA
FID H 0 1402
FID C 4 2264
FID C 6 1564
FID C 3 5605
FID C 8 4005
FID L 11 1299
FID L 12 1299
FID L 13 1110
FID L 14 1080
FID L 15 1299
FID L 16 1299
SNT PLN S C 0
FID C 3 5603
SNT PLN S C 0
FID C 8 4004
# NET 126
NET XP5R0V_PG 
SNT TOP T 180 17
FID C 4 2024
FID C 5 1216
FID C 3 5150
SNT TOP T 349 0
FID C 4 2022
FID C 5 1215
FID C 3 5148
SNT TOP T 456 1
FID C 4 2025
FID C 5 1217
FID C 3 5151
SNT TOP B 170 1
FID C 6 1387
FID C 7 497
FID C 8 3656
SNT VIA
FID H 0 2302
FID C 4 2023
FID C 6 1388
FID C 3 5149
FID C 8 3659
FID L 11 1185
FID L 12 1185
FID L 13 1038
FID L 14 977
FID L 15 1185
FID L 16 1185
SNT TRC
FID C 8 3657
FID C 8 3658
SNT TRC
FID C 3 5138
SNT TRC
FID C 3 5139
FID C 3 5140
SNT TRC
FID C 3 5141
FID C 3 5142
FID C 3 5143
FID C 3 5144
SNT TRC
FID C 3 5145
FID C 3 5146
FID C 3 5147
# NET 127
NET R_XP3R3V_PG 
SNT TOP T 181 17
FID C 4 1880
FID C 5 1121
FID C 3 4662
SNT TOP T 468 1
FID C 4 1879
FID C 5 1120
FID C 3 4661
SNT TOP B 172 1
FID C 6 1275
FID C 7 440
FID C 8 3348
SNT TOP B 275 0
FID C 6 1274
FID C 7 439
FID C 8 3347
SNT VIA
FID H 0 1223
FID C 4 1878
FID C 6 1276
FID C 3 4660
FID C 8 3349
FID L 11 1103
FID L 12 1103
FID L 13 956
FID L 14 906
FID L 15 1103
FID L 16 1103
SNT TRC
FID C 8 3341
FID C 8 3342
FID C 8 3343
FID C 8 3344
SNT TRC
FID C 8 3345
FID C 8 3346
SNT TRC
FID C 3 4656
FID C 3 4657
SNT TRC
FID C 3 4658
FID C 3 4659
# NET 128
NET XP12R0V_A_OV 
SNT TOP T 189 10
FID C 4 2108
FID C 5 1263
FID C 3 5316
SNT TOP T 337 1
FID C 4 2112
FID C 5 1266
FID C 3 5328
SNT TOP T 338 0
FID C 4 2110
FID C 5 1264
FID C 3 5324
SNT TOP T 453 0
FID C 4 2111
FID C 5 1265
FID C 3 5327
SNT VIA
FID H 0 2195
FID C 4 2109
FID C 6 1450
FID C 3 5317
FID C 8 3775
FID L 11 1226
FID L 12 1226
FID L 13 1068
FID L 14 1018
FID L 15 1226
FID L 16 1226
SNT TRC
FID C 3 5318
FID C 3 5319
FID C 3 5320
FID C 3 5321
SNT TRC
FID C 3 5322
SNT TRC
FID C 3 5323
SNT TRC
FID C 3 5325
FID C 3 5326
# NET 129
NET UNNAMED_524_CAPACITOR_I7_2 
SNT TOP T 13 1
FID C 4 386
FID C 5 269
FID C 3 918
SNT TOP T 258 0
FID C 4 389
FID C 5 272
FID C 3 927
SNT TOP T 457 1
FID C 4 388
FID C 5 271
FID C 3 926
SNT TOP T 596 0
FID C 4 387
FID C 5 270
FID C 3 925
SNT TRC
FID C 3 915
FID C 3 916
FID C 3 917
SNT TRC
FID C 3 919
FID C 3 920
FID C 3 921
FID C 3 922
SNT TRC
FID C 3 923
FID C 3 924
# NET 130
NET UNNAMED_524_CAPACITOR_I10_2 
SNT TOP T 13 2
FID C 4 390
FID C 5 273
FID C 3 930
SNT TOP T 258 1
FID C 4 393
FID C 5 276
FID C 3 937
SNT TOP T 458 1
FID C 4 392
FID C 5 275
FID C 3 934
SNT TOP T 596 2
FID C 4 391
FID C 5 274
FID C 3 933
SNT TRC
FID C 3 928
FID C 3 929
SNT TRC
FID C 3 931
FID C 3 932
SNT TRC
FID C 3 935
FID C 3 936
# NET 131
NET FT4232_VREGOUT 
SNT TOP T 13 11
FID C 4 492
FID C 5 330
FID C 3 1331
SNT TOP T 13 36
FID C 4 485
FID C 5 327
FID C 3 1320
SNT TOP T 13 48
FID C 4 487
FID C 5 328
FID C 3 1326
SNT TOP T 13 63
FID C 4 490
FID C 5 329
FID C 3 1329
SNT TOP B 95 0
FID C 6 279
FID C 7 96
FID C 8 639
SNT TOP B 440 0
FID C 6 281
FID C 7 97
FID C 8 641
SNT VIA
FID H 0 306
FID C 4 491
FID C 6 283
FID C 3 1330
FID C 9 175
FID C 8 643
FID L 11 327
FID L 12 327
FID L 13 311
FID L 14 276
FID L 15 327
FID L 16 327
SNT VIA
FID H 0 307
FID C 4 486
FID C 6 278
FID C 3 1325
FID C 9 172
FID C 8 638
FID L 11 324
FID L 12 324
FID L 13 308
FID L 14 273
FID L 15 324
FID L 16 324
SNT VIA
FID H 0 308
FID C 4 489
FID C 6 282
FID C 3 1328
FID C 9 174
FID C 8 642
FID L 11 326
FID L 12 326
FID L 13 310
FID L 14 275
FID L 15 326
FID L 16 326
SNT VIA
FID H 0 1185
FID C 4 488
FID C 6 280
FID C 3 1327
FID C 9 173
FID C 8 640
FID L 11 325
FID L 12 325
FID L 13 309
FID L 14 274
FID L 15 325
FID L 16 325
SNT TRC
FID C 9 162
FID C 9 163
FID C 9 164
FID C 9 165
FID C 9 166
FID C 9 167
FID C 9 168
FID C 9 169
SNT TRC
FID C 3 1317
FID C 3 1318
FID C 3 1319
SNT TRC
FID C 9 170
FID C 9 171
SNT TRC
FID C 8 630
FID C 8 631
SNT TRC
FID C 3 1321
SNT TRC
FID C 3 1322
FID C 3 1323
SNT TRC
FID C 8 632
FID C 8 633
FID C 8 634
FID C 8 635
SNT TRC
FID C 3 1324
SNT TRC
FID C 8 636
FID C 8 637
# NET 132
NET XP5R0V_FT4232 
SNT TOP T 1 1
FID H 0 10
FID C 4 224
FID C 6 57
FID C 3 637
FID C 10 37
FID C 8 243
FID L 11 176
FID L 12 176
FID L 13 176
FID L 14 176
FID L 15 176
FID L 16 176
SNT TOP T 1 5
FID H 0 14
FID C 4 222
FID C 6 55
FID C 3 635
FID C 10 35
FID C 8 241
FID L 11 174
FID L 12 174
FID L 13 174
FID L 14 174
FID L 15 174
FID L 16 174
SNT TOP T 1 8
FID H 0 17
FID C 4 223
FID C 6 56
FID C 3 636
FID C 10 36
FID C 8 242
FID L 11 175
FID L 12 175
FID L 13 175
FID L 14 175
FID L 15 175
FID L 16 175
SNT TOP T 1 12
FID H 0 21
FID C 4 225
FID C 6 58
FID C 3 638
FID C 10 38
FID C 8 244
FID L 11 177
FID L 12 177
FID L 13 177
FID L 14 177
FID L 15 177
FID L 16 177
SNT TOP T 8 0
FID C 4 219
FID C 5 198
FID C 3 631
SNT TOP T 67 0
FID H 0 164
FID C 6 59
FID C 3 639
FID C 10 39
FID C 8 245
FID L 11 178
FID L 12 178
FID L 13 178
FID L 14 178
FID L 15 178
FID L 16 178
SNT TOP T 599 4
FID C 4 220
FID C 5 199
FID C 3 633
SNT TOP B 228 0
FID C 6 49
FID C 7 20
FID C 8 233
SNT TOP B 391 0
FID C 6 53
FID C 7 21
FID C 8 237
SNT VIA
FID H 0 1061
FID C 4 217
FID C 6 51
FID C 3 629
FID C 10 32
FID C 8 235
FID L 11 171
FID L 12 171
FID L 13 171
FID L 14 171
FID L 15 171
FID L 16 171
SNT VIA
FID H 0 1062
FID C 4 221
FID C 6 54
FID C 3 634
FID C 10 34
FID C 8 240
FID L 11 173
FID L 12 173
FID L 13 173
FID L 14 173
FID L 15 173
FID L 16 173
SNT VIA
FID H 0 1397
FID C 4 216
FID C 6 50
FID C 3 628
FID C 10 31
FID C 8 234
FID L 11 170
FID L 12 170
FID L 13 170
FID L 14 170
FID L 15 170
FID L 16 170
SNT VIA
FID H 0 1398
FID C 4 218
FID C 6 52
FID C 3 630
FID C 10 33
FID C 8 236
FID L 11 172
FID L 12 172
FID L 13 172
FID L 14 172
FID L 15 172
FID L 16 172
SNT PLN S C 0
FID C 10 30
SNT PLN S C 0
FID C 3 627
SNT TRC
FID C 8 224
FID C 8 225
FID C 8 226
FID C 8 227
FID C 8 228
FID C 8 229
FID C 8 230
FID C 8 231
FID C 8 232
SNT TRC
FID C 3 632
SNT TRC
FID C 8 238
FID C 8 239
# NET 133
NET XP12R0V_PCIE 
SNT TOP T 160 0
FID C 4 2350
FID C 5 1375
FID C 3 5764
SNT TOP T 164 0
FID C 4 2351
FID C 5 1376
FID C 3 5765
SNT TOP T 605 1
FID C 6 1654
FID C 8 4130
SNT TOP T 605 2
FID C 6 1655
FID C 8 4132
SNT TOP T 605 32
FID C 4 2347
FID C 3 5760
SNT TOP T 605 33
FID C 4 2346
FID C 3 5759
SNT TOP T 605 34
FID C 4 2345
FID C 3 5754
SNT VIA
FID H 0 800
FID C 4 2361
FID C 6 1667
FID C 3 5775
FID C 8 4144
FID L 11 1362
FID L 12 1362
FID L 15 1362
FID L 16 1362
SNT VIA
FID H 0 801
FID C 4 2360
FID C 6 1666
FID C 3 5774
FID C 8 4143
FID L 11 1361
FID L 12 1361
FID L 15 1361
FID L 16 1361
SNT VIA
FID H 0 802
FID C 4 2354
FID C 6 1660
FID C 3 5768
FID C 8 4137
FID L 11 1355
FID L 12 1355
FID L 15 1355
FID L 16 1355
SNT VIA
FID H 0 803
FID C 4 2357
FID C 6 1663
FID C 3 5771
FID C 8 4140
FID L 11 1358
FID L 12 1358
FID L 15 1358
FID L 16 1358
SNT VIA
FID H 0 804
FID C 4 2353
FID C 6 1659
FID C 3 5767
FID C 8 4136
FID L 11 1354
FID L 12 1354
FID L 15 1354
FID L 16 1354
SNT VIA
FID H 0 805
FID C 4 2358
FID C 6 1664
FID C 3 5772
FID C 8 4141
FID L 11 1359
FID L 12 1359
FID L 15 1359
FID L 16 1359
SNT VIA
FID H 0 806
FID C 4 2352
FID C 6 1658
FID C 3 5766
FID C 8 4135
FID L 11 1353
FID L 12 1353
FID L 15 1353
FID L 16 1353
SNT VIA
FID H 0 807
FID C 4 2359
FID C 6 1665
FID C 3 5773
FID C 8 4142
FID L 11 1360
FID L 12 1360
FID L 15 1360
FID L 16 1360
SNT VIA
FID H 0 1364
FID C 4 2356
FID C 6 1662
FID C 3 5770
FID C 8 4139
FID L 11 1357
FID L 12 1357
FID L 15 1357
FID L 16 1357
SNT VIA
FID H 0 1365
FID C 4 2355
FID C 6 1661
FID C 3 5769
FID C 8 4138
FID L 11 1356
FID L 12 1356
FID L 15 1356
FID L 16 1356
SNT VIA
FID H 0 1956
FID C 4 2344
FID C 6 1653
FID C 3 5752
FID C 8 4128
FID L 11 1350
FID L 12 1350
FID L 15 1350
FID L 16 1350
SNT VIA
FID H 0 1957
FID C 4 2343
FID C 6 1652
FID C 3 5750
FID C 8 4127
FID L 11 1349
FID L 12 1349
FID L 15 1349
FID L 16 1349
SNT VIA
FID H 0 1958
FID C 4 2349
FID C 6 1657
FID C 3 5762
FID C 8 4134
FID L 11 1352
FID L 12 1352
FID L 15 1352
FID L 16 1352
SNT VIA
FID H 0 1959
FID C 4 2348
FID C 6 1656
FID C 3 5761
FID C 8 4133
FID L 11 1351
FID L 12 1351
FID L 15 1351
FID L 16 1351
SNT PLN S C 0
SNT PLN S C 0
SNT PLN S C 0
FID C 8 4126
SNT PLN S C 0
FID C 3 5749
SNT TRC
FID C 3 5751
SNT TRC
FID C 3 5753
SNT TRC
FID C 3 5755
FID C 3 5756
FID C 3 5757
SNT TRC
FID C 3 5758
SNT TRC
FID C 8 4129
SNT TRC
FID C 8 4131
SNT PLN S C 0
FID C 3 5763
# NET 134
NET XP12R0V_EXT 
SNT TOP T 143 0
FID H 0 94
FID C 4 2121
FID C 6 1456
FID C 3 5355
FID C 8 3785
FID L 11 1230
FID L 12 1230
FID L 13 1072
FID L 14 1022
FID L 15 1230
FID L 16 1230
SNT TOP T 143 1
FID H 0 95
FID C 4 2122
FID C 6 1457
FID C 3 5356
FID C 8 3786
FID L 11 1231
FID L 12 1231
FID L 13 1073
FID L 14 1023
FID L 15 1231
FID L 16 1231
SNT TOP T 143 2
FID H 0 96
FID C 4 2123
FID C 6 1458
FID C 3 5357
FID C 8 3787
FID L 11 1232
FID L 12 1232
FID L 13 1074
FID L 14 1024
FID L 15 1232
FID L 16 1232
SNT TOP T 164 1
FID C 4 2135
FID C 5 1273
FID C 3 5369
SNT VIA
FID H 0 759
FID C 4 2136
FID C 6 1470
FID C 3 5370
FID C 8 3799
FID L 11 1244
FID L 12 1244
FID L 15 1244
FID L 16 1244
SNT VIA
FID H 0 760
FID C 4 2134
FID C 6 1469
FID C 3 5368
FID C 8 3798
FID L 11 1243
FID L 12 1243
FID L 14 1025
FID L 15 1243
FID L 16 1243
SNT VIA
FID H 0 761
FID C 4 2124
FID C 6 1459
FID C 3 5358
FID C 8 3788
FID L 11 1233
FID L 12 1233
FID L 15 1233
FID L 16 1233
SNT VIA
FID H 0 762
FID C 4 2130
FID C 6 1465
FID C 3 5364
FID C 8 3794
FID L 11 1239
FID L 12 1239
FID L 15 1239
FID L 16 1239
SNT VIA
FID H 0 763
FID C 4 2125
FID C 6 1460
FID C 3 5359
FID C 8 3789
FID L 11 1234
FID L 12 1234
FID L 15 1234
FID L 16 1234
SNT VIA
FID H 0 764
FID C 4 2131
FID C 6 1466
FID C 3 5365
FID C 8 3795
FID L 11 1240
FID L 12 1240
FID L 15 1240
FID L 16 1240
SNT VIA
FID H 0 765
FID C 4 2132
FID C 6 1467
FID C 3 5366
FID C 8 3796
FID L 11 1241
FID L 12 1241
FID L 15 1241
FID L 16 1241
SNT VIA
FID H 0 766
FID C 4 2126
FID C 6 1461
FID C 3 5360
FID C 8 3790
FID L 11 1235
FID L 12 1235
FID L 15 1235
FID L 16 1235
SNT VIA
FID H 0 767
FID C 4 2127
FID C 6 1462
FID C 3 5361
FID C 8 3791
FID L 11 1236
FID L 12 1236
FID L 15 1236
FID L 16 1236
SNT VIA
FID H 0 768
FID C 4 2128
FID C 6 1463
FID C 3 5362
FID C 8 3792
FID L 11 1237
FID L 12 1237
FID L 15 1237
FID L 16 1237
SNT VIA
FID H 0 769
FID C 4 2129
FID C 6 1464
FID C 3 5363
FID C 8 3793
FID L 11 1238
FID L 12 1238
FID L 15 1238
FID L 16 1238
SNT VIA
FID H 0 1351
FID C 4 2133
FID C 6 1468
FID C 3 5367
FID C 8 3797
FID L 11 1242
FID L 12 1242
FID L 15 1242
FID L 16 1242
SNT PLN S C 0
SNT PLN S C 0
SNT PLN S C 0
FID C 3 5354
# NET 135
NET SMA2_SIG_IO_CONN 
SNT TOP T 109 0
FID H 0 37
FID C 4 901
FID C 6 548
FID C 3 2353
FID C 8 1615
FID L 11 552
FID L 12 552
FID L 13 536
FID L 14 501
FID L 15 552
FID L 16 552
SNT TOP T 275 1
FID C 4 900
FID C 5 544
FID C 3 2349
SNT TOP T 595 1
FID C 4 902
FID C 5 545
FID C 3 2354
SNT VIA
FID H 0 1250
FID C 4 899
FID C 6 547
FID C 3 2348
FID C 8 1614
FID L 11 551
FID L 12 551
FID L 13 535
FID L 14 500
FID L 15 551
FID L 16 551
SNT TRC
FID C 3 2343
FID C 3 2344
FID C 3 2345
FID C 3 2346
SNT TRC
FID C 3 2347
SNT TRC
FID C 3 2350
FID C 3 2351
FID C 3 2352
# NET 136
NET SMA1_SIG_IO_CONN 
SNT TOP T 108 0
FID H 0 32
FID C 4 905
FID C 6 550
FID C 3 2364
FID C 8 1617
FID L 11 554
FID L 12 554
FID L 13 538
FID L 14 503
FID L 15 554
FID L 16 554
SNT TOP T 276 1
FID C 4 904
FID C 5 546
FID C 3 2360
SNT TOP T 595 2
FID C 4 906
FID C 5 547
FID C 3 2365
SNT VIA
FID H 0 1247
FID C 4 903
FID C 6 549
FID C 3 2359
FID C 8 1616
FID L 11 553
FID L 12 553
FID L 13 537
FID L 14 502
FID L 15 553
FID L 16 553
SNT TRC
FID C 3 2355
FID C 3 2356
SNT TRC
FID C 3 2357
FID C 3 2358
SNT TRC
FID C 3 2361
FID C 3 2362
FID C 3 2363
# NET 137
NET SMA4_SIG_IO_CONN 
SNT TOP T 107 0
FID H 0 27
FID C 4 908
FID C 6 553
FID C 3 2374
FID C 8 1623
FID L 11 556
FID L 12 556
FID L 13 540
FID L 14 505
FID L 15 556
FID L 16 556
SNT TOP T 594 1
FID C 4 909
FID C 5 548
FID C 3 2375
SNT TOP B 181 1
FID C 6 552
FID C 7 163
FID C 8 1622
SNT VIA
FID H 0 1257
FID C 4 907
FID C 6 551
FID C 3 2370
FID C 8 1621
FID L 11 555
FID L 12 555
FID L 13 539
FID L 14 504
FID L 15 555
FID L 16 555
SNT TRC
FID C 3 2366
FID C 3 2367
FID C 3 2368
FID C 3 2369
SNT TRC
FID C 8 1618
FID C 8 1619
FID C 8 1620
SNT TRC
FID C 3 2371
FID C 3 2372
FID C 3 2373
# NET 138
NET SMA3_SIG_IO_CONN 
SNT TOP T 106 0
FID H 0 0
FID C 4 912
FID C 6 555
FID C 3 2384
FID C 8 1625
FID L 11 558
FID L 12 558
FID L 13 542
FID L 14 507
FID L 15 558
FID L 16 558
SNT TOP T 274 1
FID C 4 910
FID C 5 549
FID C 3 2378
SNT TOP T 594 2
FID C 4 913
FID C 5 550
FID C 3 2385
SNT VIA
FID H 0 1255
FID C 4 911
FID C 6 554
FID C 3 2379
FID C 8 1624
FID L 11 557
FID L 12 557
FID L 13 541
FID L 14 506
FID L 15 557
FID L 16 557
SNT TRC
FID C 3 2376
FID C 3 2377
SNT TRC
FID C 3 2380
SNT TRC
FID C 3 2381
FID C 3 2382
FID C 3 2383
# NET 139
NET FT4232_FPGA_TMS 
SNT TOP T 6 13
FID C 4 548
FID C 5 355
FID C 3 1484
SNT TOP T 602 4
FID C 4 549
FID C 5 356
FID C 3 1485
SNT TOP B 310 0
FID C 6 324
FID C 7 106
FID C 8 788
SNT TOP B 443 1
FID C 6 323
FID C 7 105
FID C 8 786
SNT VIA
FID H 0 288
FID C 4 547
FID C 6 321
FID C 3 1483
FID C 10 293
FID C 8 780
FID L 11 358
FID L 12 358
FID L 13 342
FID L 14 307
FID L 15 358
FID L 16 358
SNT VIA
FID H 0 2241
FID C 4 550
FID C 6 322
FID C 3 1486
FID C 10 294
FID C 8 785
FID L 11 359
FID L 12 359
FID L 13 343
FID L 14 308
FID L 15 359
FID L 16 359
SNT TRC
FID C 10 247
FID C 10 248
FID C 10 249
FID C 10 250
FID C 10 251
FID C 10 252
FID C 10 253
FID C 10 254
FID C 10 255
FID C 10 256
FID C 10 257
FID C 10 258
FID C 10 259
FID C 10 260
FID C 10 261
FID C 10 262
FID C 10 263
FID C 10 264
FID C 10 265
FID C 10 266
FID C 10 267
FID C 10 268
FID C 10 269
FID C 10 270
FID C 10 271
FID C 10 272
FID C 10 273
FID C 10 274
FID C 10 275
FID C 10 276
FID C 10 277
FID C 10 278
FID C 10 279
FID C 10 280
FID C 10 281
FID C 10 282
FID C 10 283
FID C 10 284
FID C 10 285
FID C 10 286
FID C 10 287
FID C 10 288
FID C 10 289
FID C 10 290
FID C 10 291
FID C 10 292
SNT TRC
FID C 3 1479
FID C 3 1480
FID C 3 1481
FID C 3 1482
SNT TRC
FID C 8 781
FID C 8 782
FID C 8 783
FID C 8 784
SNT TRC
FID C 3 1487
SNT TRC
FID C 8 787
# NET 140
NET FT4232_FPGA_TDI 
SNT TOP T 6 4
FID C 4 556
FID C 5 359
FID C 3 1503
SNT TOP T 602 8
FID C 4 557
FID C 5 360
FID C 3 1505
SNT TOP B 309 0
FID C 6 330
FID C 7 109
FID C 8 813
SNT TOP B 443 2
FID C 6 331
FID C 7 110
FID C 8 814
SNT VIA
FID H 0 286
FID C 4 555
FID C 6 329
FID C 3 1502
FID C 10 359
FID C 8 808
FID L 11 362
FID L 12 362
FID L 13 346
FID L 14 311
FID L 15 362
FID L 16 362
SNT VIA
FID H 0 2239
FID C 4 558
FID C 6 332
FID C 3 1506
FID C 10 360
FID C 8 815
FID L 11 363
FID L 12 363
FID L 13 347
FID L 14 312
FID L 15 363
FID L 16 363
SNT TRC
FID C 8 803
FID C 8 804
FID C 8 805
FID C 8 806
FID C 8 807
SNT TRC
FID C 10 346
FID C 10 347
FID C 10 348
FID C 10 349
FID C 10 350
FID C 10 351
FID C 10 352
FID C 10 353
FID C 10 354
FID C 10 355
FID C 10 356
FID C 10 357
FID C 10 358
SNT TRC
FID C 3 1497
FID C 3 1498
FID C 3 1499
FID C 3 1500
FID C 3 1501
SNT TRC
FID C 8 809
FID C 8 810
FID C 8 811
FID C 8 812
SNT TRC
FID C 3 1504
# NET 141
NET FT4232_FPGA_TCK 
SNT TOP T 6 1
FID C 4 560
FID C 5 361
FID C 3 1511
SNT TOP T 602 0
FID C 4 561
FID C 5 362
FID C 3 1512
SNT TOP B 303 0
FID C 6 335
FID C 7 112
FID C 8 826
SNT TOP B 442 1
FID C 6 334
FID C 7 111
FID C 8 825
SNT VIA
FID H 0 285
FID C 4 559
FID C 6 333
FID C 3 1510
FID C 10 394
FID C 8 819
FID L 11 364
FID L 12 364
FID L 13 348
FID L 14 313
FID L 15 364
FID L 16 364
SNT VIA
FID H 0 2238
FID C 4 562
FID C 6 336
FID C 3 1513
FID C 10 395
FID C 8 827
FID L 11 365
FID L 12 365
FID L 13 349
FID L 14 314
FID L 15 365
FID L 16 365
SNT TRC
FID C 10 361
FID C 10 362
FID C 10 363
FID C 10 364
FID C 10 365
FID C 10 366
FID C 10 367
FID C 10 368
FID C 10 369
FID C 10 370
FID C 10 371
FID C 10 372
FID C 10 373
FID C 10 374
FID C 10 375
FID C 10 376
FID C 10 377
FID C 10 378
FID C 10 379
FID C 10 380
FID C 10 381
FID C 10 382
FID C 10 383
FID C 10 384
FID C 10 385
FID C 10 386
FID C 10 387
FID C 10 388
FID C 10 389
FID C 10 390
FID C 10 391
FID C 10 392
FID C 10 393
SNT TRC
FID C 8 816
FID C 8 817
FID C 8 818
SNT TRC
FID C 3 1507
FID C 3 1508
FID C 3 1509
SNT TRC
FID C 8 820
FID C 8 821
FID C 8 822
FID C 8 823
FID C 8 824
SNT TRC
FID C 3 1514
# NET 142
NET FT4232_FPGA_TDO 
SNT TOP T 6 10
FID C 4 552
FID C 5 357
FID C 3 1493
SNT TOP T 602 2
FID C 4 553
FID C 5 358
FID C 3 1494
SNT TOP B 301 0
FID C 6 326
FID C 7 107
FID C 8 800
SNT TOP B 442 2
FID C 6 327
FID C 7 108
FID C 8 801
SNT VIA
FID H 0 287
FID C 4 551
FID C 6 325
FID C 3 1492
FID C 10 344
FID C 8 794
FID L 11 360
FID L 12 360
FID L 13 344
FID L 14 309
FID L 15 360
FID L 16 360
SNT VIA
FID H 0 2240
FID C 4 554
FID C 6 328
FID C 3 1495
FID C 10 345
FID C 8 802
FID L 11 361
FID L 12 361
FID L 13 345
FID L 14 310
FID L 15 361
FID L 16 361
SNT TRC
FID C 10 295
FID C 10 296
FID C 10 297
FID C 10 298
FID C 10 299
FID C 10 300
FID C 10 301
FID C 10 302
FID C 10 303
FID C 10 304
FID C 10 305
FID C 10 306
FID C 10 307
FID C 10 308
FID C 10 309
FID C 10 310
FID C 10 311
FID C 10 312
FID C 10 313
FID C 10 314
FID C 10 315
FID C 10 316
FID C 10 317
FID C 10 318
FID C 10 319
FID C 10 320
FID C 10 321
FID C 10 322
FID C 10 323
FID C 10 324
FID C 10 325
FID C 10 326
FID C 10 327
FID C 10 328
FID C 10 329
FID C 10 330
FID C 10 331
FID C 10 332
FID C 10 333
FID C 10 334
FID C 10 335
FID C 10 336
FID C 10 337
FID C 10 338
FID C 10 339
FID C 10 340
FID C 10 341
FID C 10 342
FID C 10 343
SNT TRC
FID C 8 789
FID C 8 790
FID C 8 791
FID C 8 792
FID C 8 793
SNT TRC
FID C 3 1488
FID C 3 1489
FID C 3 1490
FID C 3 1491
SNT TRC
FID C 8 795
FID C 8 796
FID C 8 797
FID C 8 798
FID C 8 799
SNT TRC
FID C 3 1496
# NET 143
NET UNNAMED_14_OPTICAL_I12_A 
SNT TOP T 440 0
FID C 4 2385
FID C 5 1385
FID C 3 5824
SNT TOP B 314 0
FID C 6 1701
FID C 7 612
FID C 8 4221
SNT VIA
FID H 0 1288
FID C 4 2384
FID C 6 1702
FID C 3 5822
FID C 8 4222
FID L 11 1375
FID L 12 1375
FID L 13 1143
FID L 14 1142
FID L 15 1375
FID L 16 1375
SNT TRC
FID C 8 4219
FID C 8 4220
SNT TRC
FID C 3 5823
# NET 144
NET LED_DATOUT3 
SNT TOP T 170 124
FID C 4 3850
FID C 5 1823
FID C 3 8295
SNT TOP T 440 1
FID C 4 3849
FID C 5 1822
FID C 3 8294
SNT VIA
FID H 0 1192
FID C 4 3848
FID C 6 2989
FID C 3 8293
FID C 9 2785
FID C 8 6278
FID L 11 1485
FID L 12 1485
FID L 13 2262
FID L 14 2261
FID L 15 1485
FID L 16 1485
SNT VIA
FID H 0 2385
FID C 3 8296
FID C 9 2786
FID C 8 6279
FID L 11 1486
FID L 12 1486
FID L 13 2263
FID L 14 2262
FID L 15 1486
FID L 16 1486
SNT TRC
FID C 9 2742
FID C 9 2743
FID C 9 2744
FID C 9 2745
FID C 9 2746
FID C 9 2747
FID C 9 2748
FID C 9 2749
FID C 9 2750
FID C 9 2751
FID C 9 2752
FID C 9 2753
FID C 9 2754
FID C 9 2755
FID C 9 2756
FID C 9 2757
FID C 9 2758
FID C 9 2759
FID C 9 2760
FID C 9 2761
FID C 9 2762
FID C 9 2763
FID C 9 2764
FID C 9 2765
FID C 9 2766
FID C 9 2767
FID C 9 2768
FID C 9 2769
FID C 9 2770
FID C 9 2771
FID C 9 2772
FID C 9 2773
FID C 9 2774
FID C 9 2775
FID C 9 2776
FID C 9 2777
FID C 9 2778
FID C 9 2779
FID C 9 2780
FID C 9 2781
FID C 9 2782
FID C 9 2783
FID C 9 2784
SNT TRC
FID C 3 8291
SNT TRC
FID C 3 8292
# NET 145
NET UNNAMED_14_OPTICAL_I138_A 
SNT TOP T 443 0
FID C 4 1027
FID C 5 621
FID C 3 2727
SNT TOP B 318 0
FID C 6 625
FID C 7 185
FID C 8 1850
SNT VIA
FID H 0 1291
FID C 4 1026
FID C 6 626
FID C 3 2726
FID C 8 1851
FID L 11 615
FID L 12 615
FID L 13 599
FID L 14 564
FID L 15 615
FID L 16 615
SNT TRC
FID C 8 1848
FID C 8 1849
SNT TRC
FID C 3 2725
# NET 146
NET FPGA_USR_LED1 
SNT TOP T 170 12
FID C 4 1233
FID C 5 745
FID C 3 3226
SNT TOP T 443 1
FID C 4 1232
FID C 5 744
FID C 3 3225
SNT VIA
FID H 0 1170
FID C 4 1231
FID C 6 744
FID C 3 3224
FID C 9 1687
FID C 8 2212
FID L 11 740
FID L 12 740
FID L 13 724
FID L 14 689
FID L 15 740
FID L 16 740
SNT VIA
FID H 0 1412
FID C 4 1230
FID C 6 743
FID C 3 3220
FID C 9 1653
FID C 8 2211
FID L 11 739
FID L 12 739
FID L 13 723
FID L 14 688
FID L 15 739
FID L 16 739
SNT TRC
FID C 3 3221
FID C 3 3222
SNT TRC
FID C 9 1654
FID C 9 1655
FID C 9 1656
FID C 9 1657
FID C 9 1658
FID C 9 1659
FID C 9 1660
FID C 9 1661
FID C 9 1662
FID C 9 1663
FID C 9 1664
FID C 9 1665
FID C 9 1666
FID C 9 1667
FID C 9 1668
FID C 9 1669
FID C 9 1670
FID C 9 1671
FID C 9 1672
FID C 9 1673
FID C 9 1674
FID C 9 1675
FID C 9 1676
FID C 9 1677
FID C 9 1678
FID C 9 1679
FID C 9 1680
FID C 9 1681
FID C 9 1682
FID C 9 1683
FID C 9 1684
FID C 9 1685
FID C 9 1686
SNT TRC
FID C 3 3223
# NET 147
NET UNNAMED_14_OPTICAL_I139_A 
SNT TOP T 442 0
FID C 4 1196
FID C 5 718
FID C 3 3111
SNT TOP B 319 0
FID C 6 711
FID C 7 190
FID C 8 2154
SNT VIA
FID H 0 1292
FID C 4 1195
FID C 6 712
FID C 3 3110
FID C 8 2155
FID L 11 704
FID L 12 704
FID L 13 688
FID L 14 653
FID L 15 704
FID L 16 704
SNT TRC
FID C 8 2152
FID C 8 2153
SNT TRC
FID C 3 3109
# NET 148
NET FPGA_USR_LED0 
SNT TOP T 170 13
FID C 4 1236
FID C 5 747
FID C 3 3232
SNT TOP T 442 1
FID C 4 1235
FID C 5 746
FID C 3 3230
SNT VIA
FID H 0 1169
FID C 4 1234
FID C 6 745
FID C 3 3229
FID C 9 1735
FID C 8 2213
FID L 11 741
FID L 12 741
FID L 13 725
FID L 14 690
FID L 15 741
FID L 16 741
SNT VIA
FID H 0 2374
FID C 3 3231
FID C 9 1736
FID C 8 2214
FID L 11 742
FID L 12 742
FID L 13 726
FID L 14 691
FID L 15 742
FID L 16 742
SNT TRC
FID C 3 3227
SNT TRC
FID C 9 1688
FID C 9 1689
FID C 9 1690
FID C 9 1691
FID C 9 1692
FID C 9 1693
FID C 9 1694
FID C 9 1695
FID C 9 1696
FID C 9 1697
FID C 9 1698
FID C 9 1699
FID C 9 1700
FID C 9 1701
FID C 9 1702
FID C 9 1703
FID C 9 1704
FID C 9 1705
FID C 9 1706
FID C 9 1707
FID C 9 1708
FID C 9 1709
FID C 9 1710
FID C 9 1711
FID C 9 1712
FID C 9 1713
FID C 9 1714
FID C 9 1715
FID C 9 1716
FID C 9 1717
FID C 9 1718
FID C 9 1719
FID C 9 1720
FID C 9 1721
FID C 9 1722
FID C 9 1723
FID C 9 1724
FID C 9 1725
FID C 9 1726
FID C 9 1727
FID C 9 1728
FID C 9 1729
FID C 9 1730
FID C 9 1731
FID C 9 1732
FID C 9 1733
FID C 9 1734
SNT TRC
FID C 3 3228
# NET 149
NET UNNAMED_14_OPTICAL_I289_A 
SNT TOP T 433 0
FID C 4 411
FID C 5 285
FID C 3 971
SNT TOP B 306 0
FID C 6 213
FID C 7 68
FID C 8 500
SNT VIA
FID H 0 1299
FID C 4 410
FID C 6 214
FID C 3 970
FID C 8 501
FID L 11 286
FID L 12 286
FID L 13 270
FID L 14 235
FID L 15 286
FID L 16 286
SNT TRC
FID C 8 498
FID C 8 499
SNT TRC
FID C 3 969
# NET 150
NET UNNAMED_14_LED4PV14_I265_1 
SNT TOP T 110 0
FID C 4 782
FID C 5 483
FID C 3 2105
SNT TOP T 296 1
FID C 4 783
FID C 5 484
FID C 3 2106
SNT TOP T 297 1
FID C 4 784
FID C 5 485
FID C 3 2108
SNT VIA
FID H 0 1272
FID C 4 781
FID C 6 476
FID C 3 2104
FID C 8 1345
FID L 11 477
FID L 12 477
FID L 13 461
FID L 14 426
FID L 15 477
FID L 16 477
SNT TRC
FID C 3 2099
FID C 3 2100
FID C 3 2101
FID C 3 2102
SNT TRC
FID C 3 2103
SNT TRC
FID C 3 2107
# NET 151
NET UNNAMED_14_LED4PV14_I265_3 
SNT TOP T 110 2
FID C 4 778
FID C 5 480
FID C 3 2095
SNT TOP T 298 1
FID C 4 779
FID C 5 481
FID C 3 2096
SNT TOP T 320 1
FID C 4 780
FID C 5 482
FID C 3 2098
SNT VIA
FID H 0 1273
FID C 4 777
FID C 6 475
FID C 3 2092
FID C 8 1344
FID L 11 476
FID L 12 476
FID L 13 460
FID L 14 425
FID L 15 476
FID L 16 476
SNT TRC
FID C 3 2089
FID C 3 2090
FID C 3 2091
SNT TRC
FID C 3 2093
FID C 3 2094
SNT TRC
FID C 3 2097
# NET 152
NET UNNAMED_14_LED4PV14_I265_4 
SNT TOP T 110 3
FID C 4 776
FID C 5 479
FID C 3 2088
SNT TOP T 318 1
FID C 4 775
FID C 5 478
FID C 3 2087
SNT TOP T 319 1
FID C 4 774
FID C 5 477
FID C 3 2085
SNT VIA
FID H 0 1274
FID C 4 773
FID C 6 474
FID C 3 2084
FID C 8 1343
FID L 11 475
FID L 12 475
FID L 13 459
FID L 14 424
FID L 15 475
FID L 16 475
SNT TRC
FID C 3 2080
FID C 3 2081
SNT TRC
FID C 3 2082
FID C 3 2083
SNT TRC
FID C 3 2086
# NET 153
NET UNNAMED_14_LED4PV14_I266_1 
SNT TOP T 112 0
FID C 4 772
FID C 5 476
FID C 3 2079
SNT TOP T 299 1
FID C 4 770
FID C 5 475
FID C 3 2074
SNT TOP T 300 1
FID C 4 769
FID C 5 474
FID C 3 2072
SNT VIA
FID H 0 721
FID C 4 768
FID C 6 472
FID C 3 2071
FID C 8 1341
FID L 11 473
FID L 12 473
FID L 13 457
FID L 14 422
FID L 15 473
FID L 16 473
SNT VIA
FID H 0 1275
FID C 4 771
FID C 6 473
FID C 3 2078
FID C 8 1342
FID L 11 474
FID L 12 474
FID L 13 458
FID L 14 423
FID L 15 474
FID L 16 474
SNT TRC
FID C 8 1332
FID C 8 1333
FID C 8 1334
FID C 8 1335
FID C 8 1336
FID C 8 1337
FID C 8 1338
FID C 8 1339
FID C 8 1340
SNT TRC
FID C 3 2069
FID C 3 2070
SNT TRC
FID C 3 2073
SNT TRC
FID C 3 2075
FID C 3 2076
FID C 3 2077
# NET 154
NET UNNAMED_14_LED4PV14_I266_3 
SNT TOP T 112 2
FID C 4 767
FID C 5 473
FID C 3 2068
SNT TOP T 301 1
FID C 4 765
FID C 5 472
FID C 3 2063
SNT TOP T 323 1
FID C 4 764
FID C 5 471
FID C 3 2061
SNT VIA
FID H 0 722
FID C 4 763
FID C 6 470
FID C 3 2060
FID C 8 1330
FID L 11 471
FID L 12 471
FID L 13 455
FID L 14 420
FID L 15 471
FID L 16 471
SNT VIA
FID H 0 1276
FID C 4 766
FID C 6 471
FID C 3 2067
FID C 8 1331
FID L 11 472
FID L 12 472
FID L 13 456
FID L 14 421
FID L 15 472
FID L 16 472
SNT TRC
FID C 8 1321
FID C 8 1322
FID C 8 1323
FID C 8 1324
FID C 8 1325
FID C 8 1326
FID C 8 1327
FID C 8 1328
FID C 8 1329
SNT TRC
FID C 3 2057
FID C 3 2058
FID C 3 2059
SNT TRC
FID C 3 2062
SNT TRC
FID C 3 2064
FID C 3 2065
FID C 3 2066
# NET 155
NET UNNAMED_14_LED4PV14_I266_4 
SNT TOP T 112 3
FID C 4 762
FID C 5 470
FID C 3 2056
SNT TOP T 321 1
FID C 4 760
FID C 5 469
FID C 3 2052
SNT TOP T 322 1
FID C 4 759
FID C 5 468
FID C 3 2050
SNT VIA
FID H 0 723
FID C 4 758
FID C 6 468
FID C 3 2049
FID C 8 1319
FID L 11 469
FID L 12 469
FID L 13 453
FID L 14 418
FID L 15 469
FID L 16 469
SNT VIA
FID H 0 1277
FID C 4 761
FID C 6 469
FID C 3 2055
FID C 8 1320
FID L 11 470
FID L 12 470
FID L 13 454
FID L 14 419
FID L 15 470
FID L 16 470
SNT TRC
FID C 8 1309
FID C 8 1310
FID C 8 1311
FID C 8 1312
FID C 8 1313
FID C 8 1314
FID C 8 1315
FID C 8 1316
FID C 8 1317
FID C 8 1318
SNT TRC
FID C 3 2047
FID C 3 2048
SNT TRC
FID C 3 2051
SNT TRC
FID C 3 2053
FID C 3 2054
# NET 156
NET UNNAMED_14_LED4PV14_I267_1 
SNT TOP T 114 0
FID C 4 757
FID C 5 467
FID C 3 2046
SNT TOP T 291 1
FID C 4 755
FID C 5 465
FID C 3 2043
SNT TOP T 292 1
FID C 4 756
FID C 5 466
FID C 3 2045
SNT VIA
FID H 0 1278
FID C 4 754
FID C 6 467
FID C 3 2042
FID C 8 1308
FID L 11 468
FID L 12 468
FID L 13 452
FID L 14 417
FID L 15 468
FID L 16 468
SNT TRC
FID C 3 2034
FID C 3 2035
FID C 3 2036
SNT TRC
FID C 3 2037
FID C 3 2038
FID C 3 2039
FID C 3 2040
FID C 3 2041
SNT TRC
FID C 3 2044
# NET 157
NET UNNAMED_14_LED4PV14_I267_3 
SNT TOP T 114 2
FID C 4 753
FID C 5 464
FID C 3 2033
SNT TOP T 290 1
FID C 4 751
FID C 5 462
FID C 3 2030
SNT TOP T 312 1
FID C 4 752
FID C 5 463
FID C 3 2032
SNT VIA
FID H 0 1279
FID C 4 750
FID C 6 466
FID C 3 2028
FID C 8 1307
FID L 11 467
FID L 12 467
FID L 13 451
FID L 14 416
FID L 15 467
FID L 16 467
SNT TRC
FID C 3 2024
FID C 3 2025
FID C 3 2026
FID C 3 2027
SNT TRC
FID C 3 2029
SNT TRC
FID C 3 2031
# NET 158
NET UNNAMED_14_LED4PV14_I267_4 
SNT TOP T 114 3
FID C 4 749
FID C 5 461
FID C 3 2023
SNT TOP T 313 1
FID C 4 748
FID C 5 460
FID C 3 2022
SNT TOP T 314 1
FID C 4 747
FID C 5 459
FID C 3 2020
SNT VIA
FID H 0 1280
FID C 4 746
FID C 6 465
FID C 3 2019
FID C 8 1306
FID L 11 466
FID L 12 466
FID L 13 450
FID L 14 415
FID L 15 466
FID L 16 466
SNT TRC
FID C 3 2015
FID C 3 2016
FID C 3 2017
SNT TRC
FID C 3 2018
SNT TRC
FID C 3 2021
# NET 159
NET UNNAMED_14_LED4PV14_I268_1 
SNT TOP T 111 0
FID C 4 745
FID C 5 458
FID C 3 2014
SNT TOP T 294 1
FID C 4 743
FID C 5 457
FID C 3 2010
SNT TOP T 295 1
FID C 4 742
FID C 5 456
FID C 3 2008
SNT VIA
FID H 0 724
FID C 4 741
FID C 6 463
FID C 3 2007
FID C 8 1304
FID L 11 464
FID L 12 464
FID L 13 448
FID L 14 413
FID L 15 464
FID L 16 464
SNT VIA
FID H 0 1281
FID C 4 744
FID C 6 464
FID C 3 2013
FID C 8 1305
FID L 11 465
FID L 12 465
FID L 13 449
FID L 14 414
FID L 15 465
FID L 16 465
SNT TRC
FID C 8 1292
FID C 8 1293
FID C 8 1294
FID C 8 1295
FID C 8 1296
FID C 8 1297
FID C 8 1298
FID C 8 1299
FID C 8 1300
FID C 8 1301
FID C 8 1302
FID C 8 1303
SNT TRC
FID C 3 2004
FID C 3 2005
FID C 3 2006
SNT TRC
FID C 3 2009
SNT TRC
FID C 3 2011
FID C 3 2012
# NET 160
NET UNNAMED_14_LED4PV14_I268_3 
SNT TOP T 111 2
FID C 4 740
FID C 5 455
FID C 3 2003
SNT TOP T 293 1
FID C 4 738
FID C 5 454
FID C 3 1998
SNT TOP T 315 1
FID C 4 737
FID C 5 453
FID C 3 1996
SNT VIA
FID H 0 725
FID C 4 736
FID C 6 461
FID C 3 1995
FID C 8 1290
FID L 11 462
FID L 12 462
FID L 13 446
FID L 14 411
FID L 15 462
FID L 16 462
SNT VIA
FID H 0 1282
FID C 4 739
FID C 6 462
FID C 3 2002
FID C 8 1291
FID L 11 463
FID L 12 463
FID L 13 447
FID L 14 412
FID L 15 463
FID L 16 463
SNT TRC
FID C 8 1286
FID C 8 1287
FID C 8 1288
FID C 8 1289
SNT TRC
FID C 3 1992
FID C 3 1993
FID C 3 1994
SNT TRC
FID C 3 1997
SNT TRC
FID C 3 1999
FID C 3 2000
FID C 3 2001
# NET 161
NET UNNAMED_14_LED4PV14_I268_4 
SNT TOP T 111 3
FID C 4 735
FID C 5 452
FID C 3 1991
SNT TOP T 316 1
FID C 4 732
FID C 5 450
FID C 3 1985
SNT TOP T 317 1
FID C 4 733
FID C 5 451
FID C 3 1987
SNT VIA
FID H 0 726
FID C 4 731
FID C 6 459
FID C 3 1984
FID C 8 1284
FID L 11 460
FID L 12 460
FID L 13 444
FID L 14 409
FID L 15 460
FID L 16 460
SNT VIA
FID H 0 1283
FID C 4 734
FID C 6 460
FID C 3 1990
FID C 8 1285
FID L 11 461
FID L 12 461
FID L 13 445
FID L 14 410
FID L 15 461
FID L 16 461
SNT TRC
FID C 8 1280
FID C 8 1281
FID C 8 1282
FID C 8 1283
SNT TRC
FID C 3 1982
FID C 3 1983
SNT TRC
FID C 3 1986
SNT TRC
FID C 3 1988
FID C 3 1989
# NET 162
NET UNNAMED_14_LED4PV14_I269_1 
SNT TOP T 113 0
FID C 4 730
FID C 5 449
FID C 3 1981
SNT TOP T 286 1
FID C 4 728
FID C 5 447
FID C 3 1979
SNT TOP T 289 1
FID C 4 729
FID C 5 448
FID C 3 1980
SNT VIA
FID H 0 1284
FID C 4 727
FID C 6 458
FID C 3 1977
FID C 8 1279
FID L 11 459
FID L 12 459
FID L 13 443
FID L 14 408
FID L 15 459
FID L 16 459
SNT TRC
FID C 3 1970
FID C 3 1971
FID C 3 1972
FID C 3 1973
SNT TRC
FID C 3 1974
FID C 3 1975
FID C 3 1976
SNT TRC
FID C 3 1978
# NET 163
NET UNNAMED_14_LED4PV14_I269_3 
SNT TOP T 113 2
FID C 4 724
FID C 5 444
FID C 3 1967
SNT TOP T 284 1
FID C 4 726
FID C 5 446
FID C 3 1969
SNT TOP T 285 1
FID C 4 725
FID C 5 445
FID C 3 1968
SNT VIA
FID H 0 1285
FID C 4 723
FID C 6 457
FID C 3 1965
FID C 8 1278
FID L 11 458
FID L 12 458
FID L 13 442
FID L 14 407
FID L 15 458
FID L 16 458
SNT TRC
FID C 3 1961
FID C 3 1962
FID C 3 1963
SNT TRC
FID C 3 1964
SNT TRC
FID C 3 1966
# NET 164
NET UNNAMED_14_LED4PV14_I269_4 
SNT TOP T 113 3
FID C 4 720
FID C 5 441
FID C 3 1958
SNT TOP T 287 1
FID C 4 721
FID C 5 442
FID C 3 1959
SNT TOP T 288 1
FID C 4 722
FID C 5 443
FID C 3 1960
SNT VIA
FID H 0 1286
FID C 4 719
FID C 6 456
FID C 3 1956
FID C 8 1277
FID L 11 457
FID L 12 457
FID L 13 441
FID L 14 406
FID L 15 457
FID L 16 457
SNT TRC
FID C 3 1952
FID C 3 1953
SNT TRC
FID C 3 1954
FID C 3 1955
SNT TRC
FID C 3 1957
# NET 165
NET UNNAMED_14_OPTICAL_I191_A 
SNT TOP T 435 0
FID C 4 834
FID C 5 509
FID C 3 2206
SNT TOP B 223 0
FID C 6 512
FID C 7 160
FID C 8 1489
SNT VIA
FID H 0 1297
FID C 4 833
FID C 6 513
FID C 3 2205
FID C 8 1490
FID L 11 506
FID L 12 506
FID L 13 490
FID L 14 455
FID L 15 506
FID L 16 506
SNT TRC
FID C 8 1487
FID C 8 1488
SNT TRC
FID C 3 2204
# NET 166
NET UNNAMED_14_OPTICAL_I11_A 
SNT TOP T 446 0
FID C 4 2387
FID C 5 1386
FID C 3 5827
SNT TOP B 326 0
FID C 6 1703
FID C 7 613
FID C 8 4225
SNT VIA
FID H 0 1287
FID C 4 2386
FID C 6 1704
FID C 3 5826
FID C 8 4226
FID L 11 1376
FID L 12 1376
FID L 13 1144
FID L 14 1143
FID L 15 1376
FID L 16 1376
SNT TRC
FID C 8 4223
FID C 8 4224
SNT TRC
FID C 3 5825
# NET 167
NET LED_DATOUT2 
SNT TOP T 170 123
FID C 4 3853
FID C 5 1825
FID C 3 8302
SNT TOP T 446 1
FID C 4 3852
FID C 5 1824
FID C 3 8300
SNT VIA
FID H 0 1191
FID C 4 3851
FID C 6 2990
FID C 3 8299
FID C 9 2834
FID C 8 6280
FID L 11 1487
FID L 12 1487
FID L 13 2264
FID L 14 2263
FID L 15 1487
FID L 16 1487
SNT VIA
FID H 0 2384
FID C 3 8301
FID C 9 2835
FID C 8 6281
FID L 11 1488
FID L 12 1488
FID L 13 2265
FID L 14 2264
FID L 15 1488
FID L 16 1488
SNT TRC
FID C 9 2787
FID C 9 2788
FID C 9 2789
FID C 9 2790
FID C 9 2791
FID C 9 2792
FID C 9 2793
FID C 9 2794
FID C 9 2795
FID C 9 2796
FID C 9 2797
FID C 9 2798
FID C 9 2799
FID C 9 2800
FID C 9 2801
FID C 9 2802
FID C 9 2803
FID C 9 2804
FID C 9 2805
FID C 9 2806
FID C 9 2807
FID C 9 2808
FID C 9 2809
FID C 9 2810
FID C 9 2811
FID C 9 2812
FID C 9 2813
FID C 9 2814
FID C 9 2815
FID C 9 2816
FID C 9 2817
FID C 9 2818
FID C 9 2819
FID C 9 2820
FID C 9 2821
FID C 9 2822
FID C 9 2823
FID C 9 2824
FID C 9 2825
FID C 9 2826
FID C 9 2827
FID C 9 2828
FID C 9 2829
FID C 9 2830
FID C 9 2831
FID C 9 2832
FID C 9 2833
SNT TRC
FID C 3 8297
SNT TRC
FID C 3 8298
# NET 168
NET UNNAMED_14_OPTICAL_I194_A 
SNT TOP T 434 0
FID C 4 832
FID C 5 508
FID C 3 2203
SNT TOP B 224 0
FID C 6 510
FID C 7 159
FID C 8 1485
SNT VIA
FID H 0 1298
FID C 4 831
FID C 6 511
FID C 3 2202
FID C 8 1486
FID L 11 505
FID L 12 505
FID L 13 489
FID L 14 454
FID L 15 505
FID L 16 505
SNT TRC
FID C 8 1483
FID C 8 1484
SNT TRC
FID C 3 2201
# NET 169
NET UNNAMED_14_OPTICAL_I136_A 
SNT TOP T 436 0
FID C 4 2389
FID C 5 1387
FID C 3 5830
SNT TOP B 327 0
FID C 6 1705
FID C 7 614
FID C 8 4229
SNT VIA
FID H 0 1289
FID C 4 2388
FID C 6 1706
FID C 3 5829
FID C 8 4230
FID L 11 1377
FID L 12 1377
FID L 13 1145
FID L 14 1144
FID L 15 1377
FID L 16 1377
SNT TRC
FID C 8 4227
FID C 8 4228
SNT TRC
FID C 3 5828
# NET 170
NET LED_DATOUT1 
SNT TOP T 170 100
FID C 4 3856
FID C 5 1827
FID C 3 8308
SNT TOP T 436 1
FID C 4 3855
FID C 5 1826
FID C 3 8306
SNT VIA
FID H 0 1190
FID C 4 3854
FID C 6 2991
FID C 3 8305
FID C 9 2876
FID C 8 6282
FID L 11 1489
FID L 12 1489
FID L 13 2266
FID L 14 2265
FID L 15 1489
FID L 16 1489
SNT VIA
FID H 0 2383
FID C 3 8307
FID C 9 2877
FID C 8 6283
FID L 11 1490
FID L 12 1490
FID L 13 2267
FID L 14 2266
FID L 15 1490
FID L 16 1490
SNT TRC
FID C 9 2836
FID C 9 2837
FID C 9 2838
FID C 9 2839
FID C 9 2840
FID C 9 2841
FID C 9 2842
FID C 9 2843
FID C 9 2844
FID C 9 2845
FID C 9 2846
FID C 9 2847
FID C 9 2848
FID C 9 2849
FID C 9 2850
FID C 9 2851
FID C 9 2852
FID C 9 2853
FID C 9 2854
FID C 9 2855
FID C 9 2856
FID C 9 2857
FID C 9 2858
FID C 9 2859
FID C 9 2860
FID C 9 2861
FID C 9 2862
FID C 9 2863
FID C 9 2864
FID C 9 2865
FID C 9 2866
FID C 9 2867
FID C 9 2868
FID C 9 2869
FID C 9 2870
FID C 9 2871
FID C 9 2872
FID C 9 2873
FID C 9 2874
FID C 9 2875
SNT TRC
FID C 3 8303
SNT TRC
FID C 3 8304
# NET 171
NET UNNAMED_14_OPTICAL_I137_A 
SNT TOP T 438 0
FID C 4 2383
FID C 5 1384
FID C 3 5821
SNT TOP B 330 0
FID C 6 1699
FID C 7 611
FID C 8 4217
SNT VIA
FID H 0 1290
FID C 4 2382
FID C 6 1700
FID C 3 5820
FID C 8 4218
FID L 11 1374
FID L 12 1374
FID L 13 1142
FID L 14 1141
FID L 15 1374
FID L 16 1374
SNT TRC
FID C 8 4215
FID C 8 4216
SNT TRC
FID C 3 5819
# NET 172
NET LED_DATOUT0 
SNT TOP T 170 78
FID C 4 3859
FID C 5 1829
FID C 3 8314
SNT TOP T 438 1
FID C 4 3858
FID C 5 1828
FID C 3 8312
SNT VIA
FID H 0 1189
FID C 4 3857
FID C 6 2992
FID C 3 8311
FID C 9 2925
FID C 8 6284
FID L 11 1491
FID L 12 1491
FID L 13 2268
FID L 14 2267
FID L 15 1491
FID L 16 1491
SNT VIA
FID H 0 2382
FID C 3 8313
FID C 9 2926
FID C 8 6285
FID L 11 1492
FID L 12 1492
FID L 13 2269
FID L 14 2268
FID L 15 1492
FID L 16 1492
SNT TRC
FID C 3 8309
SNT TRC
FID C 9 2878
FID C 9 2879
FID C 9 2880
FID C 9 2881
FID C 9 2882
FID C 9 2883
FID C 9 2884
FID C 9 2885
FID C 9 2886
FID C 9 2887
FID C 9 2888
FID C 9 2889
FID C 9 2890
FID C 9 2891
FID C 9 2892
FID C 9 2893
FID C 9 2894
FID C 9 2895
FID C 9 2896
FID C 9 2897
FID C 9 2898
FID C 9 2899
FID C 9 2900
FID C 9 2901
FID C 9 2902
FID C 9 2903
FID C 9 2904
FID C 9 2905
FID C 9 2906
FID C 9 2907
FID C 9 2908
FID C 9 2909
FID C 9 2910
FID C 9 2911
FID C 9 2912
FID C 9 2913
FID C 9 2914
FID C 9 2915
FID C 9 2916
FID C 9 2917
FID C 9 2918
FID C 9 2919
FID C 9 2920
FID C 9 2921
FID C 9 2922
FID C 9 2923
FID C 9 2924
SNT TRC
FID C 3 8310
# NET 173
NET UNNAMED_14_OPTICAL_I143_A 
SNT TOP T 444 0
FID C 4 1855
FID C 5 1107
FID C 3 4606
SNT TOP B 322 0
FID C 6 1247
FID C 7 424
FID C 8 3286
SNT VIA
FID H 0 1296
FID C 4 1854
FID C 6 1248
FID C 3 4605
FID C 8 3287
FID L 11 1090
FID L 12 1090
FID L 13 943
FID L 14 893
FID L 15 1090
FID L 16 1090
SNT TRC
FID C 8 3284
FID C 8 3285
SNT TRC
FID C 3 4603
FID C 3 4604
# NET 174
NET UNNAMED_14_OPTICAL_I140_A 
SNT TOP T 437 0
FID C 4 1851
FID C 5 1105
FID C 3 4598
SNT TOP B 328 0
FID C 6 1243
FID C 7 422
FID C 8 3278
SNT VIA
FID H 0 1293
FID C 4 1850
FID C 6 1244
FID C 3 4597
FID C 8 3279
FID L 11 1088
FID L 12 1088
FID L 13 941
FID L 14 891
FID L 15 1088
FID L 16 1088
SNT TRC
FID C 8 3276
FID C 8 3277
SNT TRC
FID C 3 4596
# NET 175
NET UNNAMED_14_OPTICAL_I141_A 
SNT TOP T 441 0
FID C 4 1853
FID C 5 1106
FID C 3 4602
SNT TOP B 323 0
FID C 6 1245
FID C 7 423
FID C 8 3282
SNT VIA
FID H 0 1294
FID C 4 1852
FID C 6 1246
FID C 3 4601
FID C 8 3283
FID L 11 1089
FID L 12 1089
FID L 13 942
FID L 14 892
FID L 15 1089
FID L 16 1089
SNT TRC
FID C 8 3280
FID C 8 3281
SNT TRC
FID C 3 4599
FID C 3 4600
# NET 176
NET UNNAMED_14_OPTICAL_I142_A 
SNT TOP T 445 0
FID C 4 1857
FID C 5 1108
FID C 3 4609
SNT TOP B 320 0
FID C 6 1249
FID C 7 425
FID C 8 3290
SNT VIA
FID H 0 1295
FID C 4 1856
FID C 6 1250
FID C 3 4608
FID C 8 3291
FID L 11 1091
FID L 12 1091
FID L 13 944
FID L 14 894
FID L 15 1091
FID L 16 1091
SNT TRC
FID C 8 3288
FID C 8 3289
SNT TRC
FID C 3 4607
# NET 177
NET UNNAMED_14_OPTICAL_I292_A 
SNT TOP T 439 0
FID C 4 1859
FID C 5 1109
FID C 3 4613
SNT TOP B 312 0
FID C 6 1252
FID C 7 426
FID C 8 3294
SNT VIA
FID H 0 2272
FID C 4 1858
FID C 6 1251
FID C 3 4610
FID C 8 3292
FID L 11 1092
FID L 12 1092
FID L 13 945
FID L 14 895
FID L 15 1092
FID L 16 1092
SNT TRC
FID C 8 3293
SNT TRC
FID C 3 4611
FID C 3 4612
# NET 178
NET UNNAMED_527_FUSE_I244_1 
SNT TOP B 5 2
FID C 6 581
FID C 7 174
FID C 8 1672
SNT TOP B 113 0
FID C 6 583
FID C 7 175
FID C 8 1684
SNT TOP B 117 1
FID C 6 584
FID C 7 176
FID C 8 1687
SNT VIA
FID C 6 582
FID C 8 1683
SNT TRC
FID C 8 1673
FID C 8 1674
FID C 8 1675
FID C 8 1676
SNT TRC
FID C 8 1677
FID C 8 1678
FID C 8 1679
FID C 8 1680
FID C 8 1681
FID C 8 1682
SNT TRC
FID C 8 1685
FID C 8 1686
# NET 179
NET CARD_PRESENT 
SNT TOP T 203 0
FID C 4 3958
FID C 5 1884
FID C 3 8684
SNT TOP T 605 0
FID C 6 3097
FID C 8 6892
SNT TOP B 120 0
FID C 6 3096
FID C 7 901
FID C 8 6888
SNT VIA
FID H 0 205
FID C 4 3957
FID C 6 3094
FID C 3 8680
FID C 10 4130
FID C 8 6883
FID L 11 1566
FID L 12 1566
FID L 13 2343
FID L 14 2342
FID L 15 1566
FID L 16 1566
SNT VIA
FID H 0 2153
FID C 4 3959
FID C 6 3095
FID C 3 8685
FID C 10 4135
FID C 8 6884
FID L 11 1567
FID L 12 1567
FID L 13 2344
FID L 14 2343
FID L 15 1567
FID L 16 1567
SNT TRC
FID C 3 8681
FID C 3 8682
FID C 3 8683
SNT TRC
FID C 10 4131
FID C 10 4132
FID C 10 4133
FID C 10 4134
SNT TRC
FID C 8 6885
FID C 8 6886
FID C 8 6887
SNT TRC
FID C 8 6889
FID C 8 6890
FID C 8 6891
# NET 180
NET PCIE_CONN_TCK 
SNT TOP T 605 4
FID C 6 2955
FID C 8 6135
SNT TOP B 217 0
FID C 6 2952
FID C 7 853
FID C 8 6120
SNT VIA
FID C 6 2954
FID C 8 6130
SNT VIA
FID H 0 330
FID C 4 3805
FID C 6 2951
FID C 3 8151
FID C 9 2580
FID C 8 6119
FID L 11 1457
FID L 12 1457
FID L 13 2234
FID L 14 2233
FID L 15 1457
FID L 16 1457
SNT VIA
FID H 0 2247
FID C 4 3806
FID C 6 2953
FID C 3 8152
FID C 9 2581
FID C 8 6121
FID L 11 1458
FID L 12 1458
FID L 13 2235
FID L 14 2234
FID L 15 1458
FID L 16 1458
SNT TRC
FID C 9 2524
FID C 9 2525
FID C 9 2526
FID C 9 2527
FID C 9 2528
FID C 9 2529
FID C 9 2530
FID C 9 2531
FID C 9 2532
FID C 9 2533
FID C 9 2534
FID C 9 2535
FID C 9 2536
FID C 9 2537
FID C 9 2538
FID C 9 2539
FID C 9 2540
FID C 9 2541
FID C 9 2542
FID C 9 2543
FID C 9 2544
FID C 9 2545
FID C 9 2546
FID C 9 2547
FID C 9 2548
FID C 9 2549
FID C 9 2550
FID C 9 2551
FID C 9 2552
FID C 9 2553
FID C 9 2554
FID C 9 2555
FID C 9 2556
FID C 9 2557
FID C 9 2558
FID C 9 2559
FID C 9 2560
FID C 9 2561
FID C 9 2562
FID C 9 2563
FID C 9 2564
FID C 9 2565
FID C 9 2566
FID C 9 2567
FID C 9 2568
FID C 9 2569
FID C 9 2570
FID C 9 2571
FID C 9 2572
FID C 9 2573
FID C 9 2574
FID C 9 2575
FID C 9 2576
FID C 9 2577
FID C 9 2578
FID C 9 2579
SNT TRC
FID C 8 6112
FID C 8 6113
FID C 8 6114
FID C 8 6115
FID C 8 6116
FID C 8 6117
FID C 8 6118
SNT TRC
FID C 8 6122
FID C 8 6123
FID C 8 6124
FID C 8 6125
FID C 8 6126
FID C 8 6127
FID C 8 6128
FID C 8 6129
SNT TRC
FID C 8 6131
FID C 8 6132
FID C 8 6133
FID C 8 6134
# NET 181
NET PCIE_CONN_TDI 
SNT TOP T 605 5
FID C 6 2947
FID C 8 6092
SNT TOP B 215 0
FID C 6 2950
FID C 7 852
FID C 8 6111
SNT VIA
FID C 6 2946
FID C 8 6085
SNT VIA
FID H 0 331
FID C 4 3804
FID C 6 2949
FID C 3 8150
FID C 9 2523
FID C 8 6110
FID L 11 1456
FID L 12 1456
FID L 13 2233
FID L 14 2232
FID L 15 1456
FID L 16 1456
SNT VIA
FID H 0 2248
FID C 4 3803
FID C 6 2948
FID C 3 8149
FID C 9 2522
FID C 8 6093
FID L 11 1455
FID L 12 1455
FID L 13 2232
FID L 14 2231
FID L 15 1455
FID L 16 1455
SNT TRC
FID C 9 2501
FID C 9 2502
FID C 9 2503
FID C 9 2504
FID C 9 2505
FID C 9 2506
FID C 9 2507
FID C 9 2508
FID C 9 2509
FID C 9 2510
FID C 9 2511
FID C 9 2512
FID C 9 2513
FID C 9 2514
FID C 9 2515
FID C 9 2516
FID C 9 2517
FID C 9 2518
FID C 9 2519
FID C 9 2520
FID C 9 2521
SNT TRC
FID C 8 6082
FID C 8 6083
FID C 8 6084
SNT TRC
FID C 8 6086
FID C 8 6087
FID C 8 6088
FID C 8 6089
FID C 8 6090
FID C 8 6091
SNT TRC
FID C 8 6094
FID C 8 6095
FID C 8 6096
FID C 8 6097
FID C 8 6098
FID C 8 6099
FID C 8 6100
FID C 8 6101
FID C 8 6102
FID C 8 6103
FID C 8 6104
FID C 8 6105
FID C 8 6106
FID C 8 6107
FID C 8 6108
FID C 8 6109
# NET 182
NET PCIE_CONN_TDO 
SNT TOP T 605 6
FID C 6 2944
FID C 8 6071
SNT TOP B 216 0
FID C 6 2941
FID C 7 851
FID C 8 6068
SNT VIA
FID C 6 2945
FID C 8 6077
SNT VIA
FID H 0 332
FID C 4 3802
FID C 6 2943
FID C 3 8148
FID C 10 3531
FID C 8 6070
FID L 11 1454
FID L 12 1454
FID L 13 2231
FID L 14 2230
FID L 15 1454
FID L 16 1454
SNT VIA
FID H 0 333
FID C 4 3801
FID C 6 2942
FID C 3 8147
FID C 9 2500
FID C 10 3530
FID C 8 6069
FID L 11 1453
FID L 12 1453
FID L 13 2230
FID L 14 2229
FID L 15 1453
FID L 16 1453
SNT VIA
FID H 0 334
FID C 4 3800
FID C 6 2940
FID C 3 8146
FID C 9 2499
FID C 8 6067
FID L 11 1452
FID L 12 1452
FID L 13 2229
FID L 14 2228
FID L 15 1452
FID L 16 1452
SNT TRC
FID C 10 3508
FID C 10 3509
FID C 10 3510
FID C 10 3511
FID C 10 3512
FID C 10 3513
FID C 10 3514
FID C 10 3515
FID C 10 3516
FID C 10 3517
FID C 10 3518
FID C 10 3519
FID C 10 3520
FID C 10 3521
FID C 10 3522
FID C 10 3523
FID C 10 3524
FID C 10 3525
FID C 10 3526
FID C 10 3527
FID C 10 3528
FID C 10 3529
SNT TRC
FID C 9 2481
FID C 9 2482
FID C 9 2483
FID C 9 2484
FID C 9 2485
FID C 9 2486
FID C 9 2487
FID C 9 2488
FID C 9 2489
FID C 9 2490
FID C 9 2491
FID C 9 2492
FID C 9 2493
FID C 9 2494
FID C 9 2495
FID C 9 2496
FID C 9 2497
FID C 9 2498
SNT TRC
FID C 8 6053
FID C 8 6054
FID C 8 6055
FID C 8 6056
FID C 8 6057
FID C 8 6058
FID C 8 6059
FID C 8 6060
FID C 8 6061
FID C 8 6062
FID C 8 6063
FID C 8 6064
FID C 8 6065
FID C 8 6066
SNT TRC
FID C 8 6072
FID C 8 6073
FID C 8 6074
FID C 8 6075
FID C 8 6076
SNT TRC
FID C 8 6078
FID C 8 6079
FID C 8 6080
FID C 8 6081
# NET 183
NET PCIE_CONN_TMS 
SNT TOP T 605 7
FID C 6 2939
FID C 8 6052
SNT TOP B 214 0
FID C 6 2937
FID C 7 850
FID C 8 6040
SNT VIA
FID C 6 2938
FID C 8 6046
SNT VIA
FID H 0 335
FID C 4 3799
FID C 6 2936
FID C 3 8145
FID C 9 2480
FID C 8 6039
FID L 11 1451
FID L 12 1451
FID L 13 2228
FID L 14 2227
FID L 15 1451
FID L 16 1451
SNT VIA
FID H 0 2249
FID C 4 3798
FID C 6 2935
FID C 3 8144
FID C 9 2479
FID C 8 5986
FID L 11 1450
FID L 12 1450
FID L 13 2227
FID L 14 2226
FID L 15 1450
FID L 16 1450
SNT TRC
FID C 9 2450
FID C 9 2451
FID C 9 2452
FID C 9 2453
FID C 9 2454
FID C 9 2455
FID C 9 2456
FID C 9 2457
FID C 9 2458
FID C 9 2459
FID C 9 2460
FID C 9 2461
FID C 9 2462
FID C 9 2463
FID C 9 2464
FID C 9 2465
FID C 9 2466
FID C 9 2467
FID C 9 2468
FID C 9 2469
FID C 9 2470
FID C 9 2471
FID C 9 2472
FID C 9 2473
FID C 9 2474
FID C 9 2475
FID C 9 2476
FID C 9 2477
FID C 9 2478
SNT TRC
FID C 8 5987
FID C 8 5988
FID C 8 5989
FID C 8 5990
FID C 8 5991
FID C 8 5992
FID C 8 5993
FID C 8 5994
FID C 8 5995
FID C 8 5996
FID C 8 5997
FID C 8 5998
FID C 8 5999
FID C 8 6000
FID C 8 6001
FID C 8 6002
FID C 8 6003
FID C 8 6004
FID C 8 6005
FID C 8 6006
FID C 8 6007
FID C 8 6008
FID C 8 6009
FID C 8 6010
FID C 8 6011
FID C 8 6012
FID C 8 6013
FID C 8 6014
FID C 8 6015
FID C 8 6016
FID C 8 6017
FID C 8 6018
FID C 8 6019
FID C 8 6020
FID C 8 6021
FID C 8 6022
FID C 8 6023
FID C 8 6024
FID C 8 6025
FID C 8 6026
FID C 8 6027
FID C 8 6028
FID C 8 6029
FID C 8 6030
FID C 8 6031
FID C 8 6032
FID C 8 6033
FID C 8 6034
FID C 8 6035
FID C 8 6036
FID C 8 6037
FID C 8 6038
SNT TRC
FID C 8 6041
FID C 8 6042
FID C 8 6043
FID C 8 6044
FID C 8 6045
SNT TRC
FID C 8 6047
FID C 8 6048
FID C 8 6049
FID C 8 6050
FID C 8 6051
# NET 184
NET PCIE_CONN_PERST_N 
SNT TOP T 201 0
FID C 4 3808
FID C 5 1803
FID C 3 8159
SNT TOP T 202 1
FID C 4 3810
FID C 5 1805
FID C 3 8166
SNT TOP T 597 1
FID C 4 3809
FID C 5 1804
FID C 3 8160
SNT TOP T 605 10
FID C 6 2956
FID C 8 6140
SNT TOP B 8 0
FID H 0 173
FID C 6 2957
FID C 3 8153
FID C 9 2587
FID C 8 6141
FID L 11 1459
FID L 12 1459
FID L 13 2236
FID L 14 2235
FID L 15 1459
FID L 16 1459
SNT VIA
FID H 0 1417
FID C 4 3807
FID C 6 2958
FID C 3 8154
FID C 9 2588
FID C 8 6142
FID L 11 1460
FID L 12 1460
FID L 13 2237
FID L 14 2236
FID L 15 1460
FID L 16 1460
SNT TRC
FID C 8 6136
FID C 8 6137
FID C 8 6138
FID C 8 6139
SNT TRC
FID C 9 2582
FID C 9 2583
FID C 9 2584
FID C 9 2585
FID C 9 2586
SNT TRC
FID C 3 8155
FID C 3 8156
FID C 3 8157
SNT TRC
FID C 3 8158
SNT TRC
FID C 3 8161
FID C 3 8162
FID C 3 8163
FID C 3 8164
FID C 3 8165
# NET 185
NET PCIE_CONN_SMCLK 
SNT TOP T 183 2
FID C 4 2249
FID C 5 1337
FID C 3 5563
SNT TOP T 605 36
FID C 4 2247
FID C 3 5559
SNT VIA
FID H 0 1418
FID C 4 2246
FID C 6 1552
FID C 3 5555
FID C 10 3293
FID C 8 3944
FID L 11 1292
FID L 12 1292
FID L 13 1103
FID L 14 1073
FID L 15 1292
FID L 16 1292
SNT VIA
FID H 0 2246
FID C 4 2248
FID C 6 1553
FID C 3 5560
FID C 10 3310
FID C 8 3945
FID L 11 1293
FID L 12 1293
FID L 13 1104
FID L 14 1074
FID L 15 1293
FID L 16 1293
SNT TRC
FID C 3 5556
FID C 3 5557
FID C 3 5558
SNT TRC
FID C 10 3294
FID C 10 3295
FID C 10 3296
FID C 10 3297
FID C 10 3298
FID C 10 3299
FID C 10 3300
FID C 10 3301
FID C 10 3302
FID C 10 3303
FID C 10 3304
FID C 10 3305
FID C 10 3306
FID C 10 3307
FID C 10 3308
FID C 10 3309
SNT TRC
FID C 3 5561
FID C 3 5562
# NET 186
NET PCIE_CONN_SMDAT 
SNT TOP T 183 5
FID C 4 2244
FID C 5 1336
FID C 3 5551
SNT TOP T 605 37
FID C 4 2245
FID C 3 5554
SNT VIA
FID H 0 1197
FID C 4 2243
FID C 6 1551
FID C 3 5548
FID C 10 3292
FID C 8 3943
FID L 11 1291
FID L 12 1291
FID L 13 1102
FID L 14 1072
FID L 15 1291
FID L 16 1291
SNT VIA
FID H 0 1419
FID C 4 2242
FID C 6 1550
FID C 3 5547
FID C 10 3285
FID C 8 3942
FID L 11 1290
FID L 12 1290
FID L 13 1101
FID L 14 1071
FID L 15 1290
FID L 16 1290
SNT TRC
FID C 10 3286
FID C 10 3287
FID C 10 3288
FID C 10 3289
FID C 10 3290
FID C 10 3291
SNT TRC
FID C 3 5549
FID C 3 5550
SNT TRC
FID C 3 5552
FID C 3 5553
# NET 187
NET CPU_TX_PCIE_MGT_0_RXP ;0,1=24,2=23,3=0
SNT TOP T 170 73
FID C 4 3935
FID C 5 1874
FID C 3 8610
SNT TOP T 605 45
FID C 4 3937
FID C 3 8627
SNT VIA
FID H 0 2203
FID C 4 3936
FID C 6 3076
FID C 3 8611
FID C 8 6790
FID L 11 1547
FID L 12 1547
FID L 13 2324
FID L 14 2323
FID L 15 1547
FID L 16 1547
SNT VIA
FID H 0 2556
FID C 3 8609
FID C 8 6789
FID L 11 1546
FID L 12 1546
FID L 13 2323
FID L 14 2322
FID L 15 1546
FID L 16 1546
SNT TRC
FID C 3 8608
SNT TRC
FID C 8 6752
FID C 8 6753
FID C 8 6754
FID C 8 6755
FID C 8 6756
FID C 8 6757
FID C 8 6758
FID C 8 6759
FID C 8 6760
FID C 8 6761
FID C 8 6762
FID C 8 6763
FID C 8 6764
FID C 8 6765
FID C 8 6766
FID C 8 6767
FID C 8 6768
FID C 8 6769
FID C 8 6770
FID C 8 6771
FID C 8 6772
FID C 8 6773
FID C 8 6774
FID C 8 6775
FID C 8 6776
FID C 8 6777
FID C 8 6778
FID C 8 6779
FID C 8 6780
FID C 8 6781
FID C 8 6782
FID C 8 6783
FID C 8 6784
FID C 8 6785
FID C 8 6786
FID C 8 6787
FID C 8 6788
SNT TRC
FID C 3 8612
FID C 3 8613
FID C 3 8614
FID C 3 8615
FID C 3 8616
FID C 3 8617
FID C 3 8618
FID C 3 8619
FID C 3 8620
FID C 3 8621
FID C 3 8622
FID C 3 8623
FID C 3 8624
FID C 3 8625
FID C 3 8626
# NET 188
NET CPU_TX_PCIE_MGT_0_RXN ;0,1=24,2=23,3=0
SNT TOP T 170 7
FID C 4 3939
FID C 5 1875
FID C 3 8631
SNT TOP T 605 46
FID C 4 3940
FID C 3 8647
SNT VIA
FID H 0 2202
FID C 4 3938
FID C 6 3077
FID C 3 8628
FID C 8 6791
FID L 11 1548
FID L 12 1548
FID L 13 2325
FID L 14 2324
FID L 15 1548
FID L 16 1548
SNT VIA
FID H 0 2555
FID C 3 8630
FID C 8 6821
FID L 11 1549
FID L 12 1549
FID L 13 2326
FID L 14 2325
FID L 15 1549
FID L 16 1549
SNT TRC
FID C 3 8629
SNT TRC
FID C 8 6792
FID C 8 6793
FID C 8 6794
FID C 8 6795
FID C 8 6796
FID C 8 6797
FID C 8 6798
FID C 8 6799
FID C 8 6800
FID C 8 6801
FID C 8 6802
FID C 8 6803
FID C 8 6804
FID C 8 6805
FID C 8 6806
FID C 8 6807
FID C 8 6808
FID C 8 6809
FID C 8 6810
FID C 8 6811
FID C 8 6812
FID C 8 6813
FID C 8 6814
FID C 8 6815
FID C 8 6816
FID C 8 6817
FID C 8 6818
FID C 8 6819
FID C 8 6820
SNT TRC
FID C 3 8632
FID C 3 8633
FID C 3 8634
FID C 3 8635
FID C 3 8636
FID C 3 8637
FID C 3 8638
FID C 3 8639
FID C 3 8640
FID C 3 8641
FID C 3 8642
FID C 3 8643
FID C 3 8644
FID C 3 8645
FID C 3 8646
# NET 189
NET UNNAMED_3_CONN64PGF_I61_PRSNT21 
SNT TOP T 203 1
FID C 4 2381
FID C 5 1383
FID C 3 5818
SNT TOP T 605 48
FID C 4 2379
FID C 3 5814
SNT VIA
FID H 0 1947
FID C 4 2378
FID C 6 1697
FID C 3 5811
FID C 10 3400
FID C 8 4213
FID L 11 1372
FID L 12 1372
FID L 13 1140
FID L 14 1139
FID L 15 1372
FID L 16 1372
SNT VIA
FID H 0 2180
FID C 4 2380
FID C 6 1698
FID C 3 5815
FID C 10 3401
FID C 8 4214
FID L 11 1373
FID L 12 1373
FID L 13 1141
FID L 14 1140
FID L 15 1373
FID L 16 1373
SNT TRC
FID C 10 3398
FID C 10 3399
SNT TRC
FID C 3 5812
FID C 3 5813
SNT TRC
FID C 3 5816
FID C 3 5817
# NET 190
NET CPU_TX_PCIE_MGT_1_RXP ;0,1=22,2=21,3=0
SNT TOP T 170 120
FID C 4 3929
FID C 5 1872
FID C 3 8579
SNT TOP T 605 50
FID C 4 3931
FID C 3 8592
SNT VIA
FID H 0 2205
FID C 4 3930
FID C 6 3074
FID C 3 8580
FID C 8 6717
FID L 11 1543
FID L 12 1543
FID L 13 2320
FID L 14 2319
FID L 15 1543
FID L 16 1543
SNT VIA
FID H 0 2557
FID C 3 8578
FID C 8 6716
FID L 11 1542
FID L 12 1542
FID L 13 2319
FID L 14 2318
FID L 15 1542
FID L 16 1542
SNT TRC
FID C 3 8577
SNT TRC
FID C 8 6678
FID C 8 6679
FID C 8 6680
FID C 8 6681
FID C 8 6682
FID C 8 6683
FID C 8 6684
FID C 8 6685
FID C 8 6686
FID C 8 6687
FID C 8 6688
FID C 8 6689
FID C 8 6690
FID C 8 6691
FID C 8 6692
FID C 8 6693
FID C 8 6694
FID C 8 6695
FID C 8 6696
FID C 8 6697
FID C 8 6698
FID C 8 6699
FID C 8 6700
FID C 8 6701
FID C 8 6702
FID C 8 6703
FID C 8 6704
FID C 8 6705
FID C 8 6706
FID C 8 6707
FID C 8 6708
FID C 8 6709
FID C 8 6710
FID C 8 6711
FID C 8 6712
FID C 8 6713
FID C 8 6714
FID C 8 6715
SNT TRC
FID C 3 8581
FID C 3 8582
FID C 3 8583
FID C 3 8584
FID C 3 8585
FID C 3 8586
FID C 3 8587
FID C 3 8588
FID C 3 8589
FID C 3 8590
FID C 3 8591
# NET 191
NET CPU_TX_PCIE_MGT_1_RXN ;0,1=22,2=21,3=0
SNT TOP T 170 98
FID C 4 3932
FID C 5 1873
FID C 3 8595
SNT TOP T 605 51
FID C 4 3934
FID C 3 8607
SNT VIA
FID H 0 2148
FID C 3 8593
FID C 8 6750
FID L 11 1544
FID L 12 1544
FID L 13 2321
FID L 14 2320
FID L 15 1544
FID L 16 1544
SNT VIA
FID H 0 2204
FID C 4 3933
FID C 6 3075
FID C 3 8596
FID C 8 6751
FID L 11 1545
FID L 12 1545
FID L 13 2322
FID L 14 2321
FID L 15 1545
FID L 16 1545
SNT TRC
FID C 8 6718
FID C 8 6719
FID C 8 6720
FID C 8 6721
FID C 8 6722
FID C 8 6723
FID C 8 6724
FID C 8 6725
FID C 8 6726
FID C 8 6727
FID C 8 6728
FID C 8 6729
FID C 8 6730
FID C 8 6731
FID C 8 6732
FID C 8 6733
FID C 8 6734
FID C 8 6735
FID C 8 6736
FID C 8 6737
FID C 8 6738
FID C 8 6739
FID C 8 6740
FID C 8 6741
FID C 8 6742
FID C 8 6743
FID C 8 6744
FID C 8 6745
FID C 8 6746
FID C 8 6747
FID C 8 6748
FID C 8 6749
SNT TRC
FID C 3 8594
SNT TRC
FID C 3 8597
FID C 3 8598
FID C 3 8599
FID C 3 8600
FID C 3 8601
FID C 3 8602
FID C 3 8603
FID C 3 8604
FID C 3 8605
FID C 3 8606
# NET 192
NET CPU_TX_PCIE_MGT_2_RXP ;0,1=20,2=19,3=0
SNT TOP T 170 75
FID C 4 3923
FID C 5 1870
FID C 3 8551
SNT TOP T 605 54
FID C 4 3925
FID C 3 8562
SNT VIA
FID H 0 2207
FID C 4 3924
FID C 6 3072
FID C 3 8552
FID C 8 6645
FID L 11 1539
FID L 12 1539
FID L 13 2316
FID L 14 2315
FID L 15 1539
FID L 16 1539
SNT VIA
FID H 0 2559
FID C 3 8550
FID C 8 6644
FID L 11 1538
FID L 12 1538
FID L 13 2315
FID L 14 2314
FID L 15 1538
FID L 16 1538
SNT TRC
FID C 3 8549
SNT TRC
FID C 8 6605
FID C 8 6606
FID C 8 6607
FID C 8 6608
FID C 8 6609
FID C 8 6610
FID C 8 6611
FID C 8 6612
FID C 8 6613
FID C 8 6614
FID C 8 6615
FID C 8 6616
FID C 8 6617
FID C 8 6618
FID C 8 6619
FID C 8 6620
FID C 8 6621
FID C 8 6622
FID C 8 6623
FID C 8 6624
FID C 8 6625
FID C 8 6626
FID C 8 6627
FID C 8 6628
FID C 8 6629
FID C 8 6630
FID C 8 6631
FID C 8 6632
FID C 8 6633
FID C 8 6634
FID C 8 6635
FID C 8 6636
FID C 8 6637
FID C 8 6638
FID C 8 6639
FID C 8 6640
FID C 8 6641
FID C 8 6642
FID C 8 6643
SNT TRC
FID C 3 8553
FID C 3 8554
FID C 3 8555
FID C 3 8556
FID C 3 8557
FID C 3 8558
FID C 3 8559
FID C 3 8560
FID C 3 8561
# NET 193
NET CPU_TX_PCIE_MGT_2_RXN ;0,1=20,2=19,3=0
SNT TOP T 170 9
FID C 4 3926
FID C 5 1871
FID C 3 8565
SNT TOP T 605 55
FID C 4 3928
FID C 3 8576
SNT VIA
FID H 0 2206
FID C 4 3927
FID C 6 3073
FID C 3 8566
FID C 8 6677
FID L 11 1541
FID L 12 1541
FID L 13 2318
FID L 14 2317
FID L 15 1541
FID L 16 1541
SNT VIA
FID H 0 2558
FID C 3 8564
FID C 8 6676
FID L 11 1540
FID L 12 1540
FID L 13 2317
FID L 14 2316
FID L 15 1540
FID L 16 1540
SNT TRC
FID C 3 8563
SNT TRC
FID C 8 6646
FID C 8 6647
FID C 8 6648
FID C 8 6649
FID C 8 6650
FID C 8 6651
FID C 8 6652
FID C 8 6653
FID C 8 6654
FID C 8 6655
FID C 8 6656
FID C 8 6657
FID C 8 6658
FID C 8 6659
FID C 8 6660
FID C 8 6661
FID C 8 6662
FID C 8 6663
FID C 8 6664
FID C 8 6665
FID C 8 6666
FID C 8 6667
FID C 8 6668
FID C 8 6669
FID C 8 6670
FID C 8 6671
FID C 8 6672
FID C 8 6673
FID C 8 6674
FID C 8 6675
SNT TRC
FID C 3 8567
FID C 3 8568
FID C 3 8569
FID C 3 8570
FID C 3 8571
FID C 3 8572
FID C 3 8573
FID C 3 8574
FID C 3 8575
# NET 194
NET CPU_TX_PCIE_MGT_3_RXP ;0,1=18,2=17,3=0
SNT TOP T 170 118
FID C 4 3917
FID C 5 1868
FID C 3 8521
SNT TOP T 605 58
FID C 4 3919
FID C 3 8533
SNT VIA
FID H 0 2209
FID C 4 3918
FID C 6 3070
FID C 3 8522
FID C 8 6576
FID L 11 1535
FID L 12 1535
FID L 13 2312
FID L 14 2311
FID L 15 1535
FID L 16 1535
SNT VIA
FID H 0 2561
FID C 3 8520
FID C 8 6575
FID L 11 1534
FID L 12 1534
FID L 13 2311
FID L 14 2310
FID L 15 1534
FID L 16 1534
SNT TRC
FID C 3 8519
SNT TRC
FID C 8 6543
FID C 8 6544
FID C 8 6545
FID C 8 6546
FID C 8 6547
FID C 8 6548
FID C 8 6549
FID C 8 6550
FID C 8 6551
FID C 8 6552
FID C 8 6553
FID C 8 6554
FID C 8 6555
FID C 8 6556
FID C 8 6557
FID C 8 6558
FID C 8 6559
FID C 8 6560
FID C 8 6561
FID C 8 6562
FID C 8 6563
FID C 8 6564
FID C 8 6565
FID C 8 6566
FID C 8 6567
FID C 8 6568
FID C 8 6569
FID C 8 6570
FID C 8 6571
FID C 8 6572
FID C 8 6573
FID C 8 6574
SNT TRC
FID C 3 8523
FID C 3 8524
FID C 3 8525
FID C 3 8526
FID C 3 8527
FID C 3 8528
FID C 3 8529
FID C 3 8530
FID C 3 8531
FID C 3 8532
# NET 195
NET CPU_TX_PCIE_MGT_3_RXN ;0,1=18,2=17,3=0
SNT TOP T 170 96
FID C 4 3920
FID C 5 1869
FID C 3 8536
SNT TOP T 605 59
FID C 4 3922
FID C 3 8548
SNT VIA
FID H 0 2208
FID C 4 3921
FID C 6 3071
FID C 3 8537
FID C 8 6604
FID L 11 1537
FID L 12 1537
FID L 13 2314
FID L 14 2313
FID L 15 1537
FID L 16 1537
SNT VIA
FID H 0 2560
FID C 3 8535
FID C 8 6603
FID L 11 1536
FID L 12 1536
FID L 13 2313
FID L 14 2312
FID L 15 1536
FID L 16 1536
SNT TRC
FID C 3 8534
SNT TRC
FID C 8 6577
FID C 8 6578
FID C 8 6579
FID C 8 6580
FID C 8 6581
FID C 8 6582
FID C 8 6583
FID C 8 6584
FID C 8 6585
FID C 8 6586
FID C 8 6587
FID C 8 6588
FID C 8 6589
FID C 8 6590
FID C 8 6591
FID C 8 6592
FID C 8 6593
FID C 8 6594
FID C 8 6595
FID C 8 6596
FID C 8 6597
FID C 8 6598
FID C 8 6599
FID C 8 6600
FID C 8 6601
FID C 8 6602
SNT TRC
FID C 3 8538
FID C 3 8539
FID C 3 8540
FID C 3 8541
FID C 3 8542
FID C 3 8543
FID C 3 8544
FID C 3 8545
FID C 3 8546
FID C 3 8547
# NET 196
NET UNNAMED_3_CONN64PGF_I61_PRSNT22 
SNT TOP T 605 62
FID C 4 2376
FID C 3 5809
SNT TOP B 120 1
FID C 6 1695
FID C 7 610
FID C 8 4211
SNT VIA
FID H 0 2273
FID C 4 2375
FID C 6 1694
FID C 3 5803
FID C 9 2296
FID C 8 4208
FID L 11 1370
FID L 12 1370
FID L 13 1138
FID L 14 1137
FID L 15 1370
FID L 16 1370
SNT VIA
FID H 0 2274
FID C 4 2377
FID C 6 1696
FID C 3 5810
FID C 9 2306
FID C 8 4212
FID L 11 1371
FID L 12 1371
FID L 13 1139
FID L 14 1138
FID L 15 1371
FID L 16 1371
SNT TRC
FID C 8 4209
FID C 8 4210
SNT TRC
FID C 3 5804
FID C 3 5805
FID C 3 5806
FID C 3 5807
FID C 3 5808
SNT TRC
FID C 9 2297
FID C 9 2298
FID C 9 2299
FID C 9 2300
FID C 9 2301
FID C 9 2302
FID C 9 2303
FID C 9 2304
FID C 9 2305
# NET 197
NET FT4232_CHD_TX 
SNT TOP T 601 0
FID C 4 567
FID C 5 364
FID C 3 1525
SNT TOP T 601 2
FID C 4 565
FID C 5 363
FID C 3 1523
SNT TOP B 344 1
FID C 6 340
FID C 7 113
FID C 8 831
SNT VIA
FID H 0 282
FID C 4 568
FID C 6 341
FID C 3 1526
FID C 9 610
FID C 8 832
FID L 11 369
FID L 12 369
FID L 13 353
FID L 14 318
FID L 15 369
FID L 16 369
SNT VIA
FID H 0 283
FID C 4 563
FID C 6 337
FID C 3 1521
FID C 9 607
FID C 10 414
FID C 8 828
FID L 11 366
FID L 12 366
FID L 13 350
FID L 14 315
FID L 15 366
FID L 16 366
SNT VIA
FID H 0 284
FID C 4 564
FID C 6 338
FID C 3 1522
FID C 9 608
FID C 10 415
FID C 8 829
FID L 11 367
FID L 12 367
FID L 13 351
FID L 14 316
FID L 15 367
FID L 16 367
SNT VIA
FID H 0 2237
FID C 4 566
FID C 6 339
FID C 3 1524
FID C 9 609
FID C 8 830
FID L 11 368
FID L 12 368
FID L 13 352
FID L 14 317
FID L 15 368
FID L 16 368
SNT TRC
FID C 10 396
FID C 10 397
FID C 10 398
FID C 10 399
FID C 10 400
FID C 10 401
FID C 10 402
FID C 10 403
FID C 10 404
FID C 10 405
FID C 10 406
FID C 10 407
FID C 10 408
FID C 10 409
FID C 10 410
FID C 10 411
FID C 10 412
FID C 10 413
SNT TRC
FID C 3 1515
FID C 3 1516
FID C 3 1517
SNT TRC
FID C 3 1518
FID C 3 1519
FID C 3 1520
SNT TRC
FID C 9 583
FID C 9 584
FID C 9 585
FID C 9 586
FID C 9 587
FID C 9 588
FID C 9 589
FID C 9 590
FID C 9 591
FID C 9 592
SNT TRC
FID C 9 593
FID C 9 594
FID C 9 595
FID C 9 596
FID C 9 597
FID C 9 598
FID C 9 599
FID C 9 600
FID C 9 601
FID C 9 602
FID C 9 603
FID C 9 604
FID C 9 605
FID C 9 606
SNT TRC
FID C 8 833
FID C 8 834
# NET 198
NET DBG_UART_MAC_RX 
SNT TOP T 601 1
FID C 4 981
FID C 5 598
FID C 3 2571
SNT TOP B 300 1
FID C 6 597
FID C 7 180
FID C 8 1737
SNT VIA
FID H 0 2224
FID C 4 982
FID C 6 598
FID C 3 2573
FID C 8 1738
FID L 11 585
FID L 12 585
FID L 13 569
FID L 14 534
FID L 15 585
FID L 16 585
SNT TRC
FID C 8 1728
FID C 8 1729
FID C 8 1730
FID C 8 1731
FID C 8 1732
FID C 8 1733
FID C 8 1734
FID C 8 1735
FID C 8 1736
SNT TRC
FID C 3 2572
# NET 199
NET DBG_UART_GPS_RXD 
SNT TOP T 399 0
FID C 4 986
FID C 5 601
FID C 3 2627
SNT TOP T 601 3
FID C 4 988
FID C 5 602
FID C 3 2630
SNT VIA
FID H 0 1103
FID C 4 987
FID C 6 600
FID C 3 2629
FID C 8 1740
FID L 11 587
FID L 12 587
FID L 13 571
FID L 14 536
FID L 15 587
FID L 16 587
SNT TRC
FID C 3 2618
FID C 3 2619
FID C 3 2620
FID C 3 2621
FID C 3 2622
FID C 3 2623
FID C 3 2624
FID C 3 2625
FID C 3 2626
SNT TRC
FID C 3 2628
# NET 200
NET FT4232_CHD_RX 
SNT TOP T 601 4
FID C 4 571
FID C 5 365
FID C 3 1535
SNT TOP T 601 6
FID C 4 573
FID C 5 366
FID C 3 1537
SNT TOP B 346 1
FID C 6 345
FID C 7 114
FID C 8 840
SNT VIA
FID H 0 279
FID C 4 574
FID C 6 346
FID C 3 1538
FID C 9 677
FID C 8 841
FID L 11 373
FID L 12 373
FID L 13 357
FID L 14 322
FID L 15 373
FID L 16 373
SNT VIA
FID H 0 280
FID C 4 569
FID C 6 342
FID C 3 1533
FID C 9 674
FID C 10 459
FID C 8 837
FID L 11 370
FID L 12 370
FID L 13 354
FID L 14 319
FID L 15 370
FID L 16 370
SNT VIA
FID H 0 281
FID C 4 570
FID C 6 343
FID C 3 1534
FID C 9 675
FID C 10 460
FID C 8 838
FID L 11 371
FID L 12 371
FID L 13 355
FID L 14 320
FID L 15 371
FID L 16 371
SNT VIA
FID H 0 1171
FID C 4 572
FID C 6 344
FID C 3 1536
FID C 9 676
FID C 8 839
FID L 11 372
FID L 12 372
FID L 13 356
FID L 14 321
FID L 15 372
FID L 16 372
SNT TRC
FID C 10 416
FID C 10 417
FID C 10 418
FID C 10 419
FID C 10 420
FID C 10 421
FID C 10 422
FID C 10 423
FID C 10 424
FID C 10 425
FID C 10 426
FID C 10 427
FID C 10 428
FID C 10 429
FID C 10 430
FID C 10 431
FID C 10 432
FID C 10 433
FID C 10 434
FID C 10 435
FID C 10 436
FID C 10 437
FID C 10 438
FID C 10 439
FID C 10 440
FID C 10 441
FID C 10 442
FID C 10 443
FID C 10 444
FID C 10 445
FID C 10 446
FID C 10 447
FID C 10 448
FID C 10 449
FID C 10 450
FID C 10 451
FID C 10 452
FID C 10 453
FID C 10 454
FID C 10 455
FID C 10 456
FID C 10 457
FID C 10 458
SNT TRC
FID C 3 1527
FID C 3 1528
FID C 3 1529
SNT TRC
FID C 3 1530
FID C 3 1531
FID C 3 1532
SNT TRC
FID C 9 611
FID C 9 612
FID C 9 613
FID C 9 614
FID C 9 615
FID C 9 616
FID C 9 617
FID C 9 618
SNT TRC
FID C 9 619
FID C 9 620
FID C 9 621
FID C 9 622
FID C 9 623
FID C 9 624
FID C 9 625
FID C 9 626
FID C 9 627
FID C 9 628
FID C 9 629
FID C 9 630
FID C 9 631
FID C 9 632
FID C 9 633
FID C 9 634
FID C 9 635
FID C 9 636
FID C 9 637
FID C 9 638
FID C 9 639
FID C 9 640
FID C 9 641
FID C 9 642
FID C 9 643
FID C 9 644
FID C 9 645
FID C 9 646
FID C 9 647
FID C 9 648
FID C 9 649
FID C 9 650
FID C 9 651
FID C 9 652
FID C 9 653
FID C 9 654
FID C 9 655
FID C 9 656
FID C 9 657
FID C 9 658
FID C 9 659
FID C 9 660
FID C 9 661
FID C 9 662
FID C 9 663
FID C 9 664
FID C 9 665
FID C 9 666
FID C 9 667
FID C 9 668
FID C 9 669
FID C 9 670
FID C 9 671
FID C 9 672
FID C 9 673
SNT TRC
FID C 8 835
FID C 8 836
# NET 201
NET DBG_UART_MAC_TX 
SNT TOP T 601 5
FID C 4 979
FID C 5 597
FID C 3 2569
SNT TOP B 299 1
FID C 6 596
FID C 7 179
FID C 8 1727
SNT VIA
FID H 0 1105
FID C 4 980
FID C 6 595
FID C 3 2570
FID C 8 1726
FID L 11 584
FID L 12 584
FID L 13 568
FID L 14 533
FID L 15 584
FID L 16 584
SNT TRC
FID C 8 1724
FID C 8 1725
SNT TRC
FID C 3 2566
FID C 3 2567
FID C 3 2568
# NET 202
NET DBG_UART_GPS_TXD 
SNT TOP T 396 0
FID C 4 983
FID C 5 599
FID C 3 2614
SNT TOP T 601 7
FID C 4 985
FID C 5 600
FID C 3 2617
SNT VIA
FID H 0 1104
FID C 4 984
FID C 6 599
FID C 3 2616
FID C 8 1739
FID L 11 586
FID L 12 586
FID L 13 570
FID L 14 535
FID L 15 586
FID L 16 586
SNT TRC
FID C 3 2574
FID C 3 2575
FID C 3 2576
FID C 3 2577
FID C 3 2578
FID C 3 2579
FID C 3 2580
FID C 3 2581
FID C 3 2582
FID C 3 2583
FID C 3 2584
FID C 3 2585
FID C 3 2586
FID C 3 2587
FID C 3 2588
FID C 3 2589
FID C 3 2590
FID C 3 2591
FID C 3 2592
FID C 3 2593
FID C 3 2594
FID C 3 2595
FID C 3 2596
FID C 3 2597
FID C 3 2598
FID C 3 2599
FID C 3 2600
FID C 3 2601
FID C 3 2602
FID C 3 2603
FID C 3 2604
FID C 3 2605
FID C 3 2606
FID C 3 2607
FID C 3 2608
FID C 3 2609
FID C 3 2610
FID C 3 2611
FID C 3 2612
FID C 3 2613
SNT TRC
FID C 3 2615
# NET 203
NET FPGA_CFG_INIT_N 
SNT TOP T 18 0
FID H 0 171
FID C 6 780
FID C 3 3329
FID C 9 1833
FID C 10 2422
FID C 8 2344
FID L 11 777
FID L 12 777
FID L 13 761
FID L 14 726
FID L 15 777
FID L 16 777
SNT TOP T 170 407
FID C 4 1286
FID C 5 774
FID C 3 3332
SNT TOP T 349 1
FID C 4 1282
FID C 5 772
FID C 3 3325
SNT TOP T 381 0
FID C 4 1287
FID C 5 775
FID C 3 3338
SNT TOP T 601 9
FID C 4 1284
FID C 5 773
FID C 3 3327
SNT TOP B 230 0
FID C 6 782
FID C 7 207
FID C 8 2348
SNT TOP B 243 1
FID C 6 781
FID C 7 206
FID C 8 2347
SNT VIA
FID H 0 218
FID C 4 1279
FID C 6 776
FID C 3 3322
FID C 8 2340
FID L 11 773
FID L 12 773
FID L 13 757
FID L 14 722
FID L 15 773
FID L 16 773
SNT VIA
FID H 0 219
FID C 4 1285
FID C 6 783
FID C 3 3330
FID C 10 2423
FID C 8 2349
FID L 11 778
FID L 12 778
FID L 13 762
FID L 14 727
FID L 15 778
FID L 16 778
SNT VIA
FID H 0 220
FID C 4 1288
FID C 6 784
FID C 3 3339
FID C 9 1834
FID C 8 2351
FID L 11 780
FID L 12 780
FID L 13 764
FID L 14 729
FID L 15 780
FID L 16 780
SNT VIA
FID H 0 1110
FID C 4 1280
FID C 6 777
FID C 3 3323
FID C 9 1830
FID C 8 2341
FID L 11 774
FID L 12 774
FID L 13 758
FID L 14 723
FID L 15 774
FID L 16 774
SNT VIA
FID H 0 1406
FID C 4 1281
FID C 6 778
FID C 3 3324
FID C 9 1831
FID C 8 2342
FID L 11 775
FID L 12 775
FID L 13 759
FID L 14 724
FID L 15 775
FID L 16 775
SNT VIA
FID H 0 2230
FID C 4 1283
FID C 6 779
FID C 3 3326
FID C 9 1832
FID C 8 2343
FID L 11 776
FID L 12 776
FID L 13 760
FID L 14 725
FID L 15 776
FID L 16 776
SNT VIA
FID H 0 2349
FID C 3 3333
FID C 10 2424
FID C 8 2350
FID L 11 779
FID L 12 779
FID L 13 763
FID L 14 728
FID L 15 779
FID L 16 779
SNT TRC
FID C 10 2411
FID C 10 2412
FID C 10 2413
FID C 10 2414
SNT TRC
FID C 8 2323
FID C 8 2324
FID C 8 2325
FID C 8 2326
FID C 8 2327
FID C 8 2328
FID C 8 2329
FID C 8 2330
FID C 8 2331
FID C 8 2332
FID C 8 2333
FID C 8 2334
SNT TRC
FID C 8 2335
FID C 8 2336
FID C 8 2337
FID C 8 2338
FID C 8 2339
SNT TRC
FID C 9 1781
FID C 9 1782
FID C 9 1783
FID C 9 1784
FID C 9 1785
FID C 9 1786
FID C 9 1787
FID C 9 1788
FID C 9 1789
FID C 9 1790
FID C 9 1791
FID C 9 1792
FID C 9 1793
FID C 9 1794
FID C 9 1795
FID C 9 1796
SNT TRC
FID C 3 3318
FID C 3 3319
SNT TRC
FID C 9 1797
FID C 9 1798
FID C 9 1799
FID C 9 1800
FID C 9 1801
FID C 9 1802
FID C 9 1803
FID C 9 1804
FID C 9 1805
FID C 9 1806
SNT TRC
FID C 9 1807
FID C 9 1808
FID C 9 1809
FID C 9 1810
FID C 9 1811
FID C 9 1812
FID C 9 1813
FID C 9 1814
FID C 9 1815
FID C 9 1816
FID C 9 1817
FID C 9 1818
FID C 9 1819
FID C 9 1820
FID C 9 1821
FID C 9 1822
FID C 9 1823
FID C 9 1824
FID C 9 1825
FID C 9 1826
FID C 9 1827
FID C 9 1828
FID C 9 1829
SNT TRC
FID C 10 2415
FID C 10 2416
FID C 10 2417
FID C 10 2418
FID C 10 2419
FID C 10 2420
FID C 10 2421
SNT TRC
FID C 3 3320
FID C 3 3321
SNT TRC
FID C 3 3328
SNT TRC
FID C 8 2345
FID C 8 2346
SNT TRC
FID C 3 3331
SNT TRC
FID C 3 3334
FID C 3 3335
FID C 3 3336
FID C 3 3337
# NET 204
NET CONN_MICRO_USB_DM ;1=1,3=0
SNT TOP T 179 5
FID C 4 1296
FID C 5 781
FID C 3 3420
SNT TOP T 600 3
FID C 4 1294
FID C 5 779
FID C 3 3405
SNT TOP T 603 1
FID C 4 1295
FID C 5 780
FID C 3 3406
SNT VIA
FID H 0 2311
FID H 1 6
FID C 4 1297
FID C 6 787
FID C 3 3421
FID C 10 2545
FID C 8 2354
FID L 11 783
FID L 12 783
FID L 13 767
FID L 14 732
FID L 15 783
FID L 16 783
SNT VIA
FID H 0 2312
FID H 1 7
FID C 4 1298
FID C 6 788
FID C 3 3482
FID C 10 2546
FID C 8 2355
FID L 11 784
FID L 12 784
FID L 13 768
FID L 14 733
FID L 15 784
FID L 16 784
SNT TRC
FID C 3 3396
FID C 3 3397
FID C 3 3398
FID C 3 3399
FID C 3 3400
FID C 3 3401
FID C 3 3402
FID C 3 3403
FID C 3 3404
SNT TRC
FID C 3 3407
FID C 3 3408
FID C 3 3409
FID C 3 3410
FID C 3 3411
FID C 3 3412
FID C 3 3413
FID C 3 3414
FID C 3 3415
FID C 3 3416
FID C 3 3417
FID C 3 3418
FID C 3 3419
SNT TRC
FID C 10 2459
FID C 10 2460
FID C 10 2461
FID C 10 2462
FID C 10 2463
FID C 10 2464
FID C 10 2465
FID C 10 2466
FID C 10 2467
FID C 10 2468
FID C 10 2469
FID C 10 2470
FID C 10 2471
FID C 10 2472
FID C 10 2473
FID C 10 2474
FID C 10 2475
FID C 10 2476
FID C 10 2477
FID C 10 2478
FID C 10 2479
FID C 10 2480
FID C 10 2481
FID C 10 2482
FID C 10 2483
FID C 10 2484
FID C 10 2485
FID C 10 2486
FID C 10 2487
FID C 10 2488
FID C 10 2489
FID C 10 2490
FID C 10 2491
FID C 10 2492
FID C 10 2493
FID C 10 2494
FID C 10 2495
FID C 10 2496
FID C 10 2497
FID C 10 2498
FID C 10 2499
FID C 10 2500
FID C 10 2501
FID C 10 2502
FID C 10 2503
FID C 10 2504
FID C 10 2505
FID C 10 2506
FID C 10 2507
FID C 10 2508
FID C 10 2509
FID C 10 2510
FID C 10 2511
FID C 10 2512
FID C 10 2513
FID C 10 2514
FID C 10 2515
FID C 10 2516
FID C 10 2517
FID C 10 2518
FID C 10 2519
FID C 10 2520
FID C 10 2521
FID C 10 2522
FID C 10 2523
FID C 10 2524
FID C 10 2525
FID C 10 2526
FID C 10 2527
FID C 10 2528
FID C 10 2529
FID C 10 2530
FID C 10 2531
FID C 10 2532
FID C 10 2533
FID C 10 2534
FID C 10 2535
FID C 10 2536
FID C 10 2537
FID C 10 2538
FID C 10 2539
FID C 10 2540
FID C 10 2541
FID C 10 2542
FID C 10 2543
FID C 10 2544
SNT TRC
FID C 3 3422
FID C 3 3423
FID C 3 3424
FID C 3 3425
FID C 3 3426
FID C 3 3427
FID C 3 3428
FID C 3 3429
FID C 3 3430
FID C 3 3431
FID C 3 3432
FID C 3 3433
FID C 3 3434
FID C 3 3435
FID C 3 3436
FID C 3 3437
FID C 3 3438
FID C 3 3439
FID C 3 3440
FID C 3 3441
FID C 3 3442
FID C 3 3443
FID C 3 3444
FID C 3 3445
FID C 3 3446
FID C 3 3447
FID C 3 3448
FID C 3 3449
FID C 3 3450
FID C 3 3451
FID C 3 3452
FID C 3 3453
FID C 3 3454
FID C 3 3455
FID C 3 3456
FID C 3 3457
FID C 3 3458
FID C 3 3459
FID C 3 3460
FID C 3 3461
FID C 3 3462
FID C 3 3463
FID C 3 3464
FID C 3 3465
FID C 3 3466
FID C 3 3467
FID C 3 3468
FID C 3 3469
FID C 3 3470
FID C 3 3471
FID C 3 3472
FID C 3 3473
FID C 3 3474
FID C 3 3475
FID C 3 3476
FID C 3 3477
FID C 3 3478
FID C 3 3479
FID C 3 3480
FID C 3 3481
# NET 205
NET CONN_MICRO_USB_DP ;1=1,3=0
SNT TOP T 179 4
FID C 4 1290
FID C 5 776
FID C 3 3369
SNT TOP T 600 5
FID C 4 1292
FID C 5 777
FID C 3 3394
SNT TOP T 603 2
FID C 4 1293
FID C 5 778
FID C 3 3395
SNT VIA
FID H 0 2313
FID H 1 8
FID C 4 1289
FID C 6 785
FID C 3 3368
FID C 10 2457
FID C 8 2352
FID L 11 781
FID L 12 781
FID L 13 765
FID L 14 730
FID L 15 781
FID L 16 781
SNT VIA
FID H 0 2314
FID H 1 9
FID C 4 1291
FID C 6 786
FID C 3 3370
FID C 10 2458
FID C 8 2353
FID L 11 782
FID L 12 782
FID L 13 766
FID L 14 731
FID L 15 782
FID L 16 782
SNT TRC
FID C 3 3340
FID C 3 3341
FID C 3 3342
FID C 3 3343
FID C 3 3344
FID C 3 3345
FID C 3 3346
FID C 3 3347
SNT TRC
FID C 10 2425
FID C 10 2426
FID C 10 2427
FID C 10 2428
FID C 10 2429
FID C 10 2430
FID C 10 2431
FID C 10 2432
FID C 10 2433
FID C 10 2434
FID C 10 2435
FID C 10 2436
FID C 10 2437
FID C 10 2438
FID C 10 2439
FID C 10 2440
FID C 10 2441
FID C 10 2442
FID C 10 2443
FID C 10 2444
FID C 10 2445
FID C 10 2446
FID C 10 2447
FID C 10 2448
FID C 10 2449
FID C 10 2450
FID C 10 2451
FID C 10 2452
FID C 10 2453
FID C 10 2454
FID C 10 2455
FID C 10 2456
SNT TRC
FID C 3 3348
FID C 3 3349
FID C 3 3350
FID C 3 3351
FID C 3 3352
FID C 3 3353
FID C 3 3354
FID C 3 3355
FID C 3 3356
FID C 3 3357
FID C 3 3358
FID C 3 3359
FID C 3 3360
FID C 3 3361
FID C 3 3362
FID C 3 3363
FID C 3 3364
FID C 3 3365
FID C 3 3366
FID C 3 3367
SNT TRC
FID C 3 3371
FID C 3 3372
FID C 3 3373
FID C 3 3374
FID C 3 3375
FID C 3 3376
FID C 3 3377
FID C 3 3378
FID C 3 3379
FID C 3 3380
FID C 3 3381
FID C 3 3382
FID C 3 3383
FID C 3 3384
FID C 3 3385
FID C 3 3386
FID C 3 3387
FID C 3 3388
FID C 3 3389
FID C 3 3390
FID C 3 3391
FID C 3 3392
FID C 3 3393
# NET 206
NET UNNAMED_524_CONNUSB14PGH4FRATH_ 
SNT TOP T 1 2
FID H 0 11
FID C 4 385
FID C 6 196
FID C 3 914
FID C 8 465
FID L 11 277
FID L 12 277
FID L 13 261
FID L 14 226
FID L 15 277
FID L 16 277
SNT TOP T 257 0
FID C 4 384
FID C 5 268
FID C 3 913
SNT VIA
FID H 0 1313
FID C 4 383
FID C 6 195
FID C 3 912
FID C 8 464
FID L 11 276
FID L 12 276
FID L 13 260
FID L 14 225
FID L 15 276
FID L 16 276
SNT TRC
FID C 8 459
FID C 8 460
FID C 8 461
FID C 8 462
FID C 8 463
SNT TRC
FID C 3 911
# NET 207
NET FT_USB_DP ;1=0,3=0
SNT TOP T 1 3
FID H 0 12
FID C 4 466
FID C 6 254
FID C 3 1168
FID C 9 126
FID C 8 576
FID L 11 313
FID L 12 313
FID L 13 297
FID L 14 262
FID L 15 313
FID L 16 313
SNT TOP T 1 10
FID H 0 19
FID C 4 468
FID C 6 255
FID C 3 1170
FID C 9 127
FID C 8 577
FID L 11 314
FID L 12 314
FID L 13 298
FID L 14 263
FID L 15 314
FID L 16 314
SNT TOP T 261 0
FID C 4 465
FID C 5 317
FID C 3 1123
SNT TOP T 599 5
FID C 4 467
FID C 5 318
FID C 3 1169
SNT VIA
FID H 0 2317
FID H 1 12
FID C 4 463
FID C 6 252
FID C 3 1114
FID C 10 168
FID C 8 574
FID L 11 311
FID L 12 311
FID L 13 295
FID L 14 260
FID L 15 311
FID L 16 311
SNT VIA
FID H 0 2318
FID H 1 13
FID C 4 464
FID C 6 253
FID C 3 1115
FID C 10 169
FID C 8 575
FID L 11 312
FID L 12 312
FID L 13 296
FID L 14 261
FID L 15 312
FID L 16 312
SNT TRC
FID C 3 1116
FID C 3 1117
FID C 3 1118
FID C 3 1119
FID C 3 1120
FID C 3 1121
FID C 3 1122
SNT TRC
FID C 10 170
FID C 10 171
FID C 10 172
FID C 10 173
FID C 10 174
FID C 10 175
FID C 10 176
FID C 10 177
FID C 10 178
FID C 10 179
FID C 10 180
FID C 10 181
FID C 10 182
FID C 10 183
FID C 10 184
FID C 10 185
FID C 10 186
FID C 10 187
FID C 10 188
SNT TRC
FID C 9 115
FID C 9 116
FID C 9 117
FID C 9 118
FID C 9 119
FID C 9 120
FID C 9 121
FID C 9 122
FID C 9 123
FID C 9 124
FID C 9 125
SNT TRC
FID C 3 1124
FID C 3 1125
FID C 3 1126
FID C 3 1127
FID C 3 1128
FID C 3 1129
FID C 3 1130
FID C 3 1131
FID C 3 1132
FID C 3 1133
FID C 3 1134
FID C 3 1135
FID C 3 1136
FID C 3 1137
FID C 3 1138
FID C 3 1139
FID C 3 1140
FID C 3 1141
FID C 3 1142
FID C 3 1143
FID C 3 1144
FID C 3 1145
FID C 3 1146
FID C 3 1147
FID C 3 1148
FID C 3 1149
FID C 3 1150
FID C 3 1151
FID C 3 1152
FID C 3 1153
FID C 3 1154
FID C 3 1155
FID C 3 1156
SNT TRC
FID C 3 1157
FID C 3 1158
FID C 3 1159
FID C 3 1160
FID C 3 1161
FID C 3 1162
FID C 3 1163
FID C 3 1164
FID C 3 1165
FID C 3 1166
FID C 3 1167
# NET 208
NET FT_USB_DM ;1=0,3=0
SNT TOP T 1 4
FID H 0 13
FID C 4 472
FID C 6 258
FID C 3 1205
FID C 9 134
FID C 8 580
FID L 11 317
FID L 12 317
FID L 13 301
FID L 14 266
FID L 15 317
FID L 16 317
SNT TOP T 1 11
FID H 0 20
FID C 4 473
FID C 6 259
FID C 3 1206
FID C 9 135
FID C 8 581
FID L 11 318
FID L 12 318
FID L 13 302
FID L 14 267
FID L 15 318
FID L 16 318
SNT TOP T 260 0
FID C 4 471
FID C 5 319
FID C 3 1180
SNT TOP T 599 3
FID C 4 474
FID C 5 320
FID C 3 1207
SNT VIA
FID H 0 2315
FID H 1 10
FID C 4 470
FID C 6 257
FID C 3 1172
FID C 10 190
FID C 8 579
FID L 11 316
FID L 12 316
FID L 13 300
FID L 14 265
FID L 15 316
FID L 16 316
SNT VIA
FID H 0 2316
FID H 1 11
FID C 4 469
FID C 6 256
FID C 3 1171
FID C 10 189
FID C 8 578
FID L 11 315
FID L 12 315
FID L 13 299
FID L 14 264
FID L 15 315
FID L 16 315
SNT TRC
FID C 3 1173
FID C 3 1174
FID C 3 1175
FID C 3 1176
FID C 3 1177
FID C 3 1178
FID C 3 1179
SNT TRC
FID C 10 191
FID C 10 192
FID C 10 193
FID C 10 194
FID C 10 195
FID C 10 196
FID C 10 197
FID C 10 198
FID C 10 199
FID C 10 200
FID C 10 201
FID C 10 202
FID C 10 203
FID C 10 204
FID C 10 205
FID C 10 206
FID C 10 207
FID C 10 208
FID C 10 209
SNT TRC
FID C 9 128
FID C 9 129
FID C 9 130
FID C 9 131
FID C 9 132
FID C 9 133
SNT TRC
FID C 3 1181
FID C 3 1182
FID C 3 1183
FID C 3 1184
FID C 3 1185
FID C 3 1186
FID C 3 1187
FID C 3 1188
SNT TRC
FID C 3 1189
FID C 3 1190
FID C 3 1191
FID C 3 1192
FID C 3 1193
FID C 3 1194
FID C 3 1195
FID C 3 1196
FID C 3 1197
FID C 3 1198
FID C 3 1199
FID C 3 1200
FID C 3 1201
FID C 3 1202
FID C 3 1203
FID C 3 1204
# NET 209
NET UNNAMED_524_CONNUSB14PGH4FRAT_1 
SNT TOP T 1 9
FID H 0 18
FID C 4 382
FID C 6 194
FID C 3 910
FID C 8 458
FID L 11 275
FID L 12 275
FID L 13 259
FID L 14 224
FID L 15 275
FID L 16 275
SNT TOP T 256 0
FID C 4 381
FID C 5 267
FID C 3 909
SNT VIA
FID H 0 1314
FID C 4 380
FID C 6 193
FID C 3 908
FID C 8 457
FID L 11 274
FID L 12 274
FID L 13 258
FID L 14 223
FID L 15 274
FID L 16 274
SNT TRC
FID C 3 903
FID C 3 904
SNT TRC
FID C 3 905
FID C 3 906
FID C 3 907
# NET 210
NET UNNAMED_127_G2001028301_I427_4 
SNT TOP T 602 3
FID C 4 2229
FID C 5 1327
FID C 3 5516
SNT TOP B 302 1
FID C 6 1536
FID C 7 544
FID C 8 3910
SNT VIA
FID H 0 2271
FID C 4 2228
FID C 6 1535
FID C 3 5515
FID C 8 3909
FID L 11 1285
FID L 12 1285
FID L 13 1096
FID L 14 1066
FID L 15 1285
FID L 16 1285
SNT TRC
FID C 8 3907
FID C 8 3908
SNT TRC
FID C 3 5513
FID C 3 5514
# NET 211
NET SN_EEPROM_WP 
SNT TOP T 45 0
FID H 0 131
FID C 6 220
FID C 3 992
FID C 9 98
FID C 8 511
FID L 11 294
FID L 12 294
FID L 13 278
FID L 14 243
FID L 15 294
FID L 16 294
SNT TOP T 105 0
FID C 4 422
FID C 5 291
FID C 3 993
SNT TOP T 133 4
FID C 4 424
FID C 5 293
FID C 3 999
SNT TOP T 334 1
FID C 4 423
FID C 5 292
FID C 3 998
SNT TOP B 203 0
FID C 6 222
FID C 7 70
FID C 8 513
SNT TOP B 221 1
FID C 6 221
FID C 7 69
FID C 8 512
SNT VIA
FID H 0 717
FID C 4 421
FID C 6 219
FID C 3 988
FID C 9 81
FID C 10 131
FID C 8 508
FID L 11 293
FID L 12 293
FID L 13 277
FID L 14 242
FID L 15 293
FID L 16 293
SNT VIA
FID H 0 2270
FID C 4 425
FID C 6 223
FID C 3 1000
FID C 10 145
FID C 8 516
FID L 11 295
FID L 12 295
FID L 13 279
FID L 14 244
FID L 15 295
FID L 16 295
SNT TRC
FID C 10 132
FID C 10 133
FID C 10 134
FID C 10 135
FID C 10 136
FID C 10 137
FID C 10 138
FID C 10 139
FID C 10 140
FID C 10 141
FID C 10 142
FID C 10 143
FID C 10 144
SNT TRC
FID C 9 82
FID C 9 83
FID C 9 84
FID C 9 85
FID C 9 86
FID C 9 87
FID C 9 88
FID C 9 89
FID C 9 90
FID C 9 91
FID C 9 92
FID C 9 93
FID C 9 94
FID C 9 95
FID C 9 96
FID C 9 97
SNT TRC
FID C 8 509
FID C 8 510
SNT TRC
FID C 3 989
FID C 3 990
FID C 3 991
SNT TRC
FID C 3 994
FID C 3 995
SNT TRC
FID C 8 514
FID C 8 515
SNT TRC
FID C 3 996
FID C 3 997
# NET 212
NET SEC_EEPROM_WP 
SNT TOP T 7 6
FID C 4 429
FID C 5 295
FID C 3 1010
SNT TOP T 44 0
FID H 0 138
FID C 6 227
FID C 3 1009
FID C 10 167
FID C 8 527
FID L 11 298
FID L 12 298
FID L 13 282
FID L 14 247
FID L 15 298
FID L 16 298
SNT TOP T 105 2
FID C 4 427
FID C 5 294
FID C 3 1005
SNT TOP B 196 1
FID C 6 228
FID C 7 72
FID C 8 528
SNT TOP B 222 1
FID C 6 229
FID C 7 73
FID C 8 529
SNT TOP B 225 0
FID C 6 226
FID C 7 71
FID C 8 526
SNT VIA
FID H 0 347
FID C 4 426
FID C 6 224
FID C 3 1001
FID C 9 99
FID C 10 146
FID C 8 517
FID L 11 296
FID L 12 296
FID L 13 280
FID L 14 245
FID L 15 296
FID L 16 296
SNT VIA
FID H 0 2172
FID C 4 428
FID C 6 225
FID C 3 1006
FID C 9 114
FID C 8 518
FID L 11 297
FID L 12 297
FID L 13 281
FID L 14 246
FID L 15 297
FID L 16 297
SNT TRC
FID C 10 147
FID C 10 148
FID C 10 149
FID C 10 150
FID C 10 151
FID C 10 152
FID C 10 153
FID C 10 154
FID C 10 155
FID C 10 156
FID C 10 157
FID C 10 158
FID C 10 159
FID C 10 160
FID C 10 161
FID C 10 162
FID C 10 163
FID C 10 164
FID C 10 165
FID C 10 166
SNT TRC
FID C 9 100
FID C 9 101
FID C 9 102
FID C 9 103
FID C 9 104
FID C 9 105
FID C 9 106
FID C 9 107
FID C 9 108
FID C 9 109
FID C 9 110
FID C 9 111
FID C 9 112
FID C 9 113
SNT TRC
FID C 3 1002
FID C 3 1003
FID C 3 1004
SNT TRC
FID C 8 519
FID C 8 520
FID C 8 521
SNT TRC
FID C 8 522
FID C 8 523
SNT TRC
FID C 8 524
FID C 8 525
SNT TRC
FID C 3 1007
FID C 3 1008
# NET 213
NET SMA_ANALOG_TUNING_IN 
SNT TOP T 593 1
FID C 4 1199
FID C 5 719
FID C 3 3116
SNT TOP B 200 1
FID C 6 718
FID C 7 193
FID C 8 2170
SNT VIA
FID H 0 716
FID C 4 1197
FID C 6 716
FID C 3 3114
FID C 10 2127
FID C 8 2167
FID L 11 705
FID L 12 705
FID L 13 689
FID L 14 654
FID L 15 705
FID L 16 705
SNT VIA
FID H 0 1258
FID C 4 1198
FID C 6 717
FID C 3 3115
FID C 10 2128
FID C 8 2168
FID L 11 706
FID L 12 706
FID L 13 690
FID L 14 655
FID L 15 706
FID L 16 706
SNT TRC
FID C 10 2115
FID C 10 2116
FID C 10 2117
FID C 10 2118
FID C 10 2119
FID C 10 2120
FID C 10 2121
FID C 10 2122
FID C 10 2123
FID C 10 2124
FID C 10 2125
FID C 10 2126
SNT TRC
FID C 3 3112
FID C 3 3113
SNT TRC
FID C 8 2169
# NET 214
NET UNNAMED_16_CONNHDR2X6FSSMT_I161 
SNT TOP T 0 0
FID C 4 409
FID C 5 284
FID C 3 968
SNT TOP B 146 1
FID C 6 211
FID C 7 67
FID C 8 496
SNT VIA
FID H 0 1302
FID C 4 408
FID C 6 212
FID C 3 967
FID C 8 497
FID L 11 285
FID L 12 285
FID L 13 269
FID L 14 234
FID L 15 285
FID L 16 285
SNT TRC
FID C 8 494
FID C 8 495
SNT TRC
FID C 3 965
FID C 3 966
# NET 215
NET UNNAMED_16_CONNHDR2X6FSSMT_I1_1 
SNT TOP T 0 1
FID C 4 407
FID C 5 283
FID C 3 964
SNT TOP B 142 0
FID C 6 209
FID C 7 66
FID C 8 490
SNT VIA
FID H 0 1303
FID C 4 406
FID C 6 210
FID C 3 963
FID C 8 493
FID L 11 284
FID L 12 284
FID L 13 268
FID L 14 233
FID L 15 284
FID L 16 284
SNT TRC
FID C 8 491
FID C 8 492
SNT TRC
FID C 3 960
FID C 3 961
FID C 3 962
# NET 216
NET UNNAMED_16_CONNHDR2X6FSSMT_I1_2 
SNT TOP T 0 2
FID C 4 405
FID C 5 282
FID C 3 959
SNT TOP B 147 1
FID C 6 207
FID C 7 65
FID C 8 488
SNT VIA
FID H 0 1304
FID C 4 404
FID C 6 208
FID C 3 958
FID C 8 489
FID L 11 283
FID L 12 283
FID L 13 267
FID L 14 232
FID L 15 283
FID L 16 283
SNT TRC
FID C 8 486
FID C 8 487
SNT TRC
FID C 3 957
# NET 217
NET UNNAMED_16_CONNHDR2X6FSSMT_I1_3 
SNT TOP T 0 3
FID C 4 403
FID C 5 281
FID C 3 956
SNT TOP B 143 0
FID C 6 205
FID C 7 64
FID C 8 482
SNT VIA
FID H 0 1305
FID C 4 402
FID C 6 206
FID C 3 955
FID C 8 485
FID L 11 282
FID L 12 282
FID L 13 266
FID L 14 231
FID L 15 282
FID L 16 282
SNT TRC
FID C 3 953
FID C 3 954
SNT TRC
FID C 8 483
FID C 8 484
# NET 218
NET UNNAMED_16_CONNHDR2X6FSSMT_I1_6 
SNT TOP T 0 4
FID C 4 396
FID C 5 278
FID C 3 941
SNT TOP B 148 1
FID C 6 199
FID C 7 61
FID C 8 472
SNT VIA
FID H 0 1308
FID C 4 397
FID C 6 200
FID C 3 944
FID C 8 473
FID L 11 279
FID L 12 279
FID L 13 263
FID L 14 228
FID L 15 279
FID L 16 279
SNT TRC
FID C 3 942
FID C 3 943
SNT TRC
FID C 8 470
FID C 8 471
# NET 219
NET UNNAMED_16_CONNHDR2X6FSSMT_I1_7 
SNT TOP T 0 5
FID C 4 394
FID C 5 277
FID C 3 938
SNT TOP B 144 0
FID C 6 197
FID C 7 60
FID C 8 468
SNT VIA
FID H 0 1309
FID C 4 395
FID C 6 198
FID C 3 940
FID C 8 469
FID L 11 278
FID L 12 278
FID L 13 262
FID L 14 227
FID L 15 278
FID L 16 278
SNT TRC
FID C 8 466
FID C 8 467
SNT TRC
FID C 3 939
# NET 220
NET UNNAMED_16_CONNHDR2X6FSSMT_I1_4 
SNT TOP T 0 6
FID C 4 401
FID C 5 280
FID C 3 952
SNT TOP B 149 1
FID C 6 203
FID C 7 63
FID C 8 478
SNT VIA
FID H 0 1306
FID C 4 400
FID C 6 204
FID C 3 951
FID C 8 481
FID L 11 281
FID L 12 281
FID L 13 265
FID L 14 230
FID L 15 281
FID L 16 281
SNT TRC
FID C 8 479
FID C 8 480
SNT TRC
FID C 3 949
FID C 3 950
# NET 221
NET UNNAMED_16_CONNHDR2X6FSSMT_I1_5 
SNT TOP T 0 7
FID C 4 399
FID C 5 279
FID C 3 948
SNT TOP B 145 0
FID C 6 201
FID C 7 62
FID C 8 474
SNT VIA
FID H 0 1307
FID C 4 398
FID C 6 202
FID C 3 947
FID C 8 477
FID L 11 280
FID L 12 280
FID L 13 264
FID L 14 229
FID L 15 280
FID L 16 280
SNT TRC
FID C 8 475
FID C 8 476
SNT TRC
FID C 3 945
FID C 3 946
# NET 222
NET UNNAMED_5_CONNHDR2X2MSSMT_I126_ 
SNT TOP T 104 0
FID C 4 718
FID C 5 440
FID C 3 1948
SNT TOP B 210 0
FID C 6 455
FID C 7 150
FID C 8 1273
SNT VIA
FID H 0 1328
FID C 4 717
FID C 6 454
FID C 3 1947
FID C 8 1272
FID L 11 456
FID L 12 456
FID L 13 440
FID L 14 405
FID L 15 456
FID L 16 456
SNT TRC
FID C 8 1270
FID C 8 1271
SNT TRC
FID C 3 1944
FID C 3 1945
FID C 3 1946
# NET 223
NET EEPROM_SDA 
SNT TOP T 104 1
FID C 4 701
FID C 5 431
FID C 3 1900
SNT TOP T 329 1
FID C 4 700
FID C 5 430
FID C 3 1899
SNT TOP T 330 1
FID C 4 699
FID C 5 429
FID C 3 1898
SNT TOP T 335 0
FID C 4 703
FID C 5 432
FID C 3 1902
SNT TOP B 198 1
FID C 6 436
FID C 7 140
FID C 8 1231
SNT TOP B 204 1
FID C 6 437
FID C 7 141
FID C 8 1232
SNT TOP B 331 0
FID C 6 439
FID C 7 142
FID C 8 1234
SNT VIA
FID H 0 212
FID C 4 702
FID C 6 435
FID C 3 1901
FID C 10 744
FID C 8 1230
FID L 11 447
FID L 12 447
FID L 13 431
FID L 14 396
FID L 15 447
FID L 16 447
SNT VIA
FID H 0 213
FID C 4 705
FID C 6 440
FID C 3 1904
FID C 10 746
FID C 8 1235
FID L 11 449
FID L 12 449
FID L 13 433
FID L 14 398
FID L 15 449
FID L 16 449
SNT VIA
FID H 0 2228
FID C 4 704
FID C 6 438
FID C 3 1903
FID C 10 745
FID C 8 1233
FID L 11 448
FID L 12 448
FID L 13 432
FID L 14 397
FID L 15 448
FID L 16 448
SNT TRC
FID C 10 729
FID C 10 730
FID C 10 731
FID C 10 732
FID C 10 733
FID C 10 734
FID C 10 735
FID C 10 736
SNT TRC
FID C 8 1223
FID C 8 1224
FID C 8 1225
SNT TRC
FID C 8 1226
FID C 8 1227
SNT TRC
FID C 8 1228
FID C 8 1229
SNT TRC
FID C 3 1887
FID C 3 1888
SNT TRC
FID C 3 1889
FID C 3 1890
FID C 3 1891
SNT TRC
FID C 10 737
FID C 10 738
FID C 10 739
FID C 10 740
FID C 10 741
FID C 10 742
FID C 10 743
SNT TRC
FID C 3 1892
FID C 3 1893
FID C 3 1894
FID C 3 1895
FID C 3 1896
SNT TRC
FID C 3 1897
# NET 224
NET UNNAMED_5_CONNHDR2X2MSSMT_I12_1 
SNT TOP T 104 2
FID C 4 716
FID C 5 439
FID C 3 1943
SNT TOP B 185 0
FID C 6 453
FID C 7 149
FID C 8 1269
SNT VIA
FID H 0 1329
FID C 4 715
FID C 6 452
FID C 3 1942
FID C 8 1268
FID L 11 455
FID L 12 455
FID L 13 439
FID L 14 404
FID L 15 455
FID L 16 455
SNT TRC
FID C 3 1940
FID C 3 1941
SNT TRC
FID C 8 1266
FID C 8 1267
# NET 225
NET EEPROM_SCL 
SNT TOP T 7 5
FID C 4 714
FID C 5 438
FID C 3 1937
SNT TOP T 104 3
FID C 4 706
FID C 5 433
FID C 3 1924
SNT TOP T 133 0
FID C 4 708
FID C 5 434
FID C 3 1931
SNT TOP T 327 1
FID C 4 710
FID C 5 436
FID C 3 1933
SNT TOP T 328 1
FID C 4 709
FID C 5 435
FID C 3 1932
SNT TOP T 333 1
FID C 4 711
FID C 5 437
FID C 3 1934
SNT TOP B 197 1
FID C 6 442
FID C 7 143
FID C 8 1239
SNT VIA
FID H 0 210
FID C 4 707
FID C 6 441
FID C 3 1925
FID C 10 787
FID C 8 1238
FID L 11 450
FID L 12 450
FID L 13 434
FID L 14 399
FID L 15 450
FID L 16 450
SNT VIA
FID H 0 211
FID C 4 713
FID C 6 444
FID C 3 1936
FID C 10 789
FID C 8 1241
FID L 11 452
FID L 12 452
FID L 13 436
FID L 14 401
FID L 15 452
FID L 16 452
SNT VIA
FID H 0 2227
FID C 4 712
FID C 6 443
FID C 3 1935
FID C 10 788
FID C 8 1240
FID L 11 451
FID L 12 451
FID L 13 435
FID L 14 400
FID L 15 451
FID L 16 451
SNT TRC
FID C 8 1236
FID C 8 1237
SNT TRC
FID C 10 747
FID C 10 748
FID C 10 749
FID C 10 750
FID C 10 751
FID C 10 752
FID C 10 753
FID C 10 754
FID C 10 755
FID C 10 756
FID C 10 757
FID C 10 758
FID C 10 759
FID C 10 760
FID C 10 761
FID C 10 762
FID C 10 763
FID C 10 764
FID C 10 765
FID C 10 766
FID C 10 767
FID C 10 768
FID C 10 769
FID C 10 770
FID C 10 771
FID C 10 772
FID C 10 773
FID C 10 774
FID C 10 775
FID C 10 776
FID C 10 777
FID C 10 778
SNT TRC
FID C 3 1905
FID C 3 1906
FID C 3 1907
FID C 3 1908
FID C 3 1909
FID C 3 1910
FID C 3 1911
FID C 3 1912
FID C 3 1913
FID C 3 1914
SNT TRC
FID C 3 1915
FID C 3 1916
FID C 3 1917
FID C 3 1918
SNT TRC
FID C 3 1919
SNT TRC
FID C 10 779
FID C 10 780
FID C 10 781
FID C 10 782
FID C 10 783
FID C 10 784
FID C 10 785
FID C 10 786
SNT TRC
FID C 3 1920
FID C 3 1921
SNT TRC
FID C 3 1922
FID C 3 1923
SNT TRC
FID C 3 1926
FID C 3 1927
FID C 3 1928
FID C 3 1929
FID C 3 1930
# NET 226
NET ANALOG_TUNING_IN 
SNT TOP T 140 0
FID H 0 42
FID C 4 2258
FID C 6 1560
FID C 3 5598
FID C 8 3997
FID L 11 1298
FID L 12 1298
FID L 13 1109
FID L 14 1079
FID L 15 1298
FID L 16 1298
SNT TOP B 200 0
FID C 6 1561
FID C 7 554
FID C 8 4001
SNT TRC
FID C 8 3998
FID C 8 3999
FID C 8 4000
# NET 227
NET R_MAC_10MHZ_RF_OUT 
SNT TOP T 138 0
FID H 0 44
FID C 4 3780
FID C 6 2925
FID C 3 8094
FID C 9 2423
FID C 8 5973
FID L 11 1441
FID L 12 1441
FID L 13 2218
FID L 14 2217
FID L 15 1441
FID L 16 1441
SNT TOP B 167 0
FID C 6 2923
FID C 7 848
FID C 8 5971
SNT VIA
FID H 0 1218
FID C 4 3779
FID C 6 2924
FID C 3 8093
FID C 9 2422
FID C 8 5972
FID L 11 1440
FID L 12 1440
FID L 13 2217
FID L 14 2216
FID L 15 1440
FID L 16 1440
SNT TRC
FID C 9 2393
FID C 9 2394
FID C 9 2395
FID C 9 2396
FID C 9 2397
FID C 9 2398
FID C 9 2399
FID C 9 2400
FID C 9 2401
FID C 9 2402
FID C 9 2403
FID C 9 2404
FID C 9 2405
FID C 9 2406
FID C 9 2407
FID C 9 2408
FID C 9 2409
FID C 9 2410
FID C 9 2411
FID C 9 2412
FID C 9 2413
FID C 9 2414
FID C 9 2415
FID C 9 2416
FID C 9 2417
FID C 9 2418
FID C 9 2419
FID C 9 2420
FID C 9 2421
SNT TRC
FID C 8 5970
# NET 228
NET R_MAC_BITEOUT 
SNT TOP T 16 0
FID H 0 189
FID C 6 2922
FID C 3 8091
FID C 9 2392
FID C 8 5969
FID L 11 1439
FID L 12 1439
FID L 13 2216
FID L 14 2215
FID L 15 1439
FID L 16 1439
SNT TOP T 135 0
FID H 0 47
FID C 4 3777
FID C 6 2921
FID C 3 8088
FID C 9 2359
FID C 8 5968
FID L 11 1438
FID L 12 1438
FID L 13 2215
FID L 14 2214
FID L 15 1438
FID L 16 1438
SNT TOP T 379 0
FID C 4 3778
FID C 5 1790
FID C 3 8092
SNT TRC
FID C 9 2360
FID C 9 2361
FID C 9 2362
FID C 9 2363
FID C 9 2364
FID C 9 2365
FID C 9 2366
FID C 9 2367
FID C 9 2368
FID C 9 2369
FID C 9 2370
FID C 9 2371
FID C 9 2372
FID C 9 2373
FID C 9 2374
FID C 9 2375
FID C 9 2376
FID C 9 2377
FID C 9 2378
FID C 9 2379
FID C 9 2380
FID C 9 2381
FID C 9 2382
FID C 9 2383
FID C 9 2384
FID C 9 2385
FID C 9 2386
FID C 9 2387
FID C 9 2388
FID C 9 2389
FID C 9 2390
FID C 9 2391
SNT TRC
FID C 3 8089
FID C 3 8090
# NET 229
NET R_MAC_UART_TX_FPGA_RX 
SNT TOP T 136 0
FID H 0 48
FID C 4 3750
FID C 6 2901
FID C 3 7896
FID C 9 2315
FID C 8 5907
FID L 11 1425
FID L 12 1425
FID L 13 2202
FID L 14 2201
FID L 15 1425
FID L 16 1425
SNT TOP T 357 0
FID C 4 3752
FID C 5 1776
FID C 3 7909
SNT TOP B 299 0
FID C 6 2902
FID C 7 841
FID C 8 5919
SNT VIA
FID H 0 346
FID C 4 3753
FID C 6 2904
FID C 3 7910
FID C 9 2337
FID C 8 5921
FID L 11 1427
FID L 12 1427
FID L 13 2204
FID L 14 2203
FID L 15 1427
FID L 16 1427
SNT VIA
FID H 0 1220
FID C 4 3751
FID C 6 2903
FID C 3 7908
FID C 8 5920
FID L 11 1426
FID L 12 1426
FID L 13 2203
FID L 14 2202
FID L 15 1426
FID L 16 1426
SNT VIA
FID H 0 1431
FID C 4 3754
FID C 6 2905
FID C 3 7911
FID C 9 2338
FID C 8 5922
FID L 11 1428
FID L 12 1428
FID L 13 2205
FID L 14 2204
FID L 15 1428
FID L 16 1428
SNT VIA
FID H 0 2255
FID C 4 3749
FID C 6 2900
FID C 3 7895
FID C 9 2307
FID C 8 5906
FID L 11 1424
FID L 12 1424
FID L 13 2201
FID L 14 2200
FID L 15 1424
FID L 16 1424
SNT TRC
FID C 9 2308
FID C 9 2309
FID C 9 2310
FID C 9 2311
FID C 9 2312
FID C 9 2313
FID C 9 2314
SNT TRC
FID C 9 2316
FID C 9 2317
FID C 9 2318
FID C 9 2319
FID C 9 2320
FID C 9 2321
FID C 9 2322
FID C 9 2323
FID C 9 2324
FID C 9 2325
FID C 9 2326
FID C 9 2327
FID C 9 2328
FID C 9 2329
FID C 9 2330
FID C 9 2331
FID C 9 2332
FID C 9 2333
FID C 9 2334
FID C 9 2335
FID C 9 2336
SNT TRC
FID C 3 7897
FID C 3 7898
FID C 3 7899
FID C 3 7900
FID C 3 7901
FID C 3 7902
SNT TRC
FID C 8 5908
FID C 8 5909
SNT TRC
FID C 8 5910
FID C 8 5911
FID C 8 5912
FID C 8 5913
FID C 8 5914
FID C 8 5915
FID C 8 5916
FID C 8 5917
FID C 8 5918
SNT TRC
FID C 3 7903
FID C 3 7904
FID C 3 7905
FID C 3 7906
FID C 3 7907
# NET 230
NET R_MAC_UART_RX_FPGA_TX 
SNT TOP T 137 0
FID H 0 49
FID C 4 3760
FID C 6 2912
FID C 3 7951
FID C 9 2358
FID C 8 5939
FID L 11 1433
FID L 12 1433
FID L 13 2210
FID L 14 2209
FID L 15 1433
FID L 16 1433
SNT TOP T 358 0
FID C 4 3757
FID C 5 1777
FID C 3 7948
SNT TOP B 229 1
FID C 6 2910
FID C 7 843
FID C 8 5937
SNT TOP B 300 0
FID C 6 2908
FID C 7 842
FID C 8 5935
SNT VIA
FID H 0 344
FID C 4 3755
FID C 6 2906
FID C 3 7912
FID C 9 2339
FID C 8 5923
FID L 11 1429
FID L 12 1429
FID L 13 2206
FID L 14 2205
FID L 15 1429
FID L 16 1429
SNT VIA
FID H 0 345
FID C 4 3758
FID C 6 2909
FID C 3 7949
FID C 9 2347
FID C 8 5936
FID L 11 1431
FID L 12 1431
FID L 13 2208
FID L 14 2207
FID L 15 1431
FID L 16 1431
SNT VIA
FID H 0 1219
FID C 4 3756
FID C 6 2907
FID C 3 7947
FID C 8 5934
FID L 11 1430
FID L 12 1430
FID L 13 2207
FID L 14 2206
FID L 15 1430
FID L 16 1430
SNT VIA
FID H 0 1430
FID C 4 3759
FID C 6 2911
FID C 3 7950
FID C 9 2348
FID C 8 5938
FID L 11 1432
FID L 12 1432
FID L 13 2209
FID L 14 2208
FID L 15 1432
FID L 16 1432
SNT TRC
FID C 9 2340
FID C 9 2341
FID C 9 2342
FID C 9 2343
FID C 9 2344
FID C 9 2345
FID C 9 2346
SNT TRC
FID C 3 7913
FID C 3 7914
FID C 3 7915
FID C 3 7916
FID C 3 7917
FID C 3 7918
FID C 3 7919
FID C 3 7920
FID C 3 7921
FID C 3 7922
FID C 3 7923
FID C 3 7924
FID C 3 7925
FID C 3 7926
FID C 3 7927
FID C 3 7928
FID C 3 7929
FID C 3 7930
FID C 3 7931
FID C 3 7932
FID C 3 7933
FID C 3 7934
FID C 3 7935
FID C 3 7936
FID C 3 7937
FID C 3 7938
FID C 3 7939
FID C 3 7940
FID C 3 7941
FID C 3 7942
SNT TRC
FID C 3 7943
FID C 3 7944
FID C 3 7945
FID C 3 7946
SNT TRC
FID C 8 5924
FID C 8 5925
FID C 8 5926
FID C 8 5927
FID C 8 5928
SNT TRC
FID C 8 5929
FID C 8 5930
SNT TRC
FID C 8 5931
FID C 8 5932
FID C 8 5933
SNT TRC
FID C 9 2349
FID C 9 2350
FID C 9 2351
FID C 9 2352
FID C 9 2353
FID C 9 2354
FID C 9 2355
FID C 9 2356
FID C 9 2357
# NET 231
NET R_MAC_PPS_IN1P ;1=5,3=0
SNT TOP T 169 0
FID C 4 3767
FID C 5 1783
FID C 3 8009
SNT TOP T 364 1
FID C 4 3766
FID C 5 1782
FID C 3 8008
SNT TOP B 234 0
FID C 6 2913
FID C 7 844
FID C 8 5945
SNT VIA
FID H 0 1429
FID C 4 3765
FID C 6 2914
FID C 3 8007
FID C 8 5946
FID L 11 1434
FID L 12 1434
FID L 13 2211
FID L 14 2210
FID L 15 1434
FID L 16 1434
SNT TRC
FID C 8 5940
FID C 8 5941
FID C 8 5942
FID C 8 5943
FID C 8 5944
SNT TRC
FID C 3 7986
FID C 3 7987
FID C 3 7988
FID C 3 7989
FID C 3 7990
FID C 3 7991
FID C 3 7992
FID C 3 7993
SNT TRC
FID C 3 7994
FID C 3 7995
FID C 3 7996
FID C 3 7997
FID C 3 7998
FID C 3 7999
FID C 3 8000
FID C 3 8001
FID C 3 8002
FID C 3 8003
FID C 3 8004
FID C 3 8005
FID C 3 8006
# NET 232
NET R_MAC_USB_DP ;1=8,3=0
SNT TOP T 169 1
FID C 4 3746
FID C 5 1773
FID C 3 7883
SNT TOP T 209 0
FID C 4 3745
FID C 5 1772
FID C 3 7882
SNT TRC
FID C 3 7875
FID C 3 7876
FID C 3 7877
FID C 3 7878
FID C 3 7879
FID C 3 7880
FID C 3 7881
# NET 233
NET R_MAC_PPS_IN1N ;1=5,3=0
SNT TOP T 169 2
FID C 4 3770
FID C 5 1785
FID C 3 8035
SNT TOP T 366 1
FID C 4 3769
FID C 5 1784
FID C 3 8034
SNT TOP B 234 1
FID C 6 2915
FID C 7 845
FID C 8 5952
SNT VIA
FID H 0 1428
FID C 4 3768
FID C 6 2916
FID C 3 8033
FID C 8 5953
FID L 11 1435
FID L 12 1435
FID L 13 2212
FID L 14 2211
FID L 15 1435
FID L 16 1435
SNT TRC
FID C 8 5947
FID C 8 5948
FID C 8 5949
FID C 8 5950
FID C 8 5951
SNT TRC
FID C 3 8010
FID C 3 8011
FID C 3 8012
FID C 3 8013
FID C 3 8014
FID C 3 8015
FID C 3 8016
FID C 3 8017
FID C 3 8018
SNT TRC
FID C 3 8019
FID C 3 8020
FID C 3 8021
FID C 3 8022
FID C 3 8023
FID C 3 8024
FID C 3 8025
FID C 3 8026
FID C 3 8027
FID C 3 8028
FID C 3 8029
FID C 3 8030
FID C 3 8031
FID C 3 8032
# NET 234
NET R_MAC_USB_DM ;1=8,3=0
SNT TOP T 169 3
FID C 4 3748
FID C 5 1775
FID C 3 7894
SNT TOP T 208 0
FID C 4 3747
FID C 5 1774
FID C 3 7893
SNT TRC
FID C 3 7884
FID C 3 7885
FID C 3 7886
FID C 3 7887
FID C 3 7888
FID C 3 7889
FID C 3 7890
FID C 3 7891
FID C 3 7892
# NET 235
NET R_MAC_PPS_IN0P ;1=6,3=0
SNT TOP T 169 4
FID C 4 3772
FID C 5 1786
FID C 3 8061
SNT TOP T 367 1
FID C 4 3773
FID C 5 1787
FID C 3 8062
SNT TOP B 122 1
FID C 6 2917
FID C 7 846
FID C 8 5959
SNT VIA
FID H 0 1427
FID C 4 3771
FID C 6 2918
FID C 3 8036
FID C 8 5960
FID L 11 1436
FID L 12 1436
FID L 13 2213
FID L 14 2212
FID L 15 1436
FID L 16 1436
SNT TRC
FID C 8 5954
FID C 8 5955
FID C 8 5956
FID C 8 5957
FID C 8 5958
SNT TRC
FID C 3 8037
FID C 3 8038
FID C 3 8039
FID C 3 8040
FID C 3 8041
FID C 3 8042
FID C 3 8043
FID C 3 8044
FID C 3 8045
FID C 3 8046
FID C 3 8047
FID C 3 8048
FID C 3 8049
SNT TRC
FID C 3 8050
FID C 3 8051
FID C 3 8052
FID C 3 8053
FID C 3 8054
FID C 3 8055
FID C 3 8056
FID C 3 8057
FID C 3 8058
FID C 3 8059
FID C 3 8060
# NET 236
NET R_MAC_PPS_IN0N ;1=6,3=0
SNT TOP T 169 6
FID C 4 3775
FID C 5 1788
FID C 3 8086
SNT TOP T 369 1
FID C 4 3776
FID C 5 1789
FID C 3 8087
SNT TOP B 122 0
FID C 6 2919
FID C 7 847
FID C 8 5966
SNT VIA
FID H 0 1426
FID C 4 3774
FID C 6 2920
FID C 3 8063
FID C 8 5967
FID L 11 1437
FID L 12 1437
FID L 13 2214
FID L 14 2213
FID L 15 1437
FID L 16 1437
SNT TRC
FID C 8 5961
FID C 8 5962
FID C 8 5963
FID C 8 5964
FID C 8 5965
SNT TRC
FID C 3 8064
FID C 3 8065
FID C 3 8066
FID C 3 8067
FID C 3 8068
FID C 3 8069
FID C 3 8070
FID C 3 8071
FID C 3 8072
FID C 3 8073
FID C 3 8074
SNT TRC
FID C 3 8075
FID C 3 8076
FID C 3 8077
FID C 3 8078
FID C 3 8079
FID C 3 8080
FID C 3 8081
FID C 3 8082
FID C 3 8083
FID C 3 8084
FID C 3 8085
# NET 237
NET R_MAC_PPS_OUTP ;1=7,3=0
SNT TOP T 169 16
FID C 4 3762
FID C 5 1779
FID C 3 7968
SNT TOP T 210 1
FID C 4 3761
FID C 5 1778
FID C 3 7952
SNT TRC
FID C 3 7953
FID C 3 7954
FID C 3 7955
FID C 3 7956
FID C 3 7957
FID C 3 7958
FID C 3 7959
FID C 3 7960
FID C 3 7961
FID C 3 7962
FID C 3 7963
FID C 3 7964
FID C 3 7965
FID C 3 7966
FID C 3 7967
# NET 238
NET R_MAC_PPS_OUTN ;1=7,3=0
SNT TOP T 169 18
FID C 4 3764
FID C 5 1781
FID C 3 7985
SNT TOP T 196 1
FID C 4 3763
FID C 5 1780
FID C 3 7969
SNT TRC
FID C 3 7970
FID C 3 7971
FID C 3 7972
FID C 3 7973
FID C 3 7974
FID C 3 7975
FID C 3 7976
FID C 3 7977
FID C 3 7978
FID C 3 7979
FID C 3 7980
FID C 3 7981
FID C 3 7982
FID C 3 7983
FID C 3 7984
# NET 239
NET MAC_ALARM 
SNT TOP T 169 19
FID C 4 3829
FID C 5 1813
FID C 3 8226
SNT TOP T 197 0
FID C 4 3827
FID C 5 1812
FID C 3 8222
SNT TOP B 7 0
FID H 0 177
FID C 6 2975
FID C 3 8223
FID C 8 6222
FID L 11 1473
FID L 12 1473
FID L 13 2250
FID L 14 2249
FID L 15 1473
FID L 16 1473
SNT VIA
FID H 0 323
FID C 4 3828
FID C 6 2976
FID C 3 8224
FID C 8 6223
FID L 11 1474
FID L 12 1474
FID L 13 2251
FID L 14 2250
FID L 15 1474
FID L 16 1474
SNT TRC
FID C 3 8221
SNT TRC
FID C 8 6220
FID C 8 6221
SNT TRC
FID C 3 8225
# NET 240
NET GPS_UART_TXD 
SNT TOP T 167 2
FID C 4 3886
FID C 5 1851
FID C 3 8426
SNT TOP T 396 1
FID C 4 3884
FID C 5 1850
FID C 3 8424
SNT TOP B 292 1
FID C 6 3017
FID C 7 866
FID C 8 6358
SNT VIA
FID H 0 2161
FID C 4 3885
FID C 6 3018
FID C 3 8425
FID C 8 6359
FID L 11 1515
FID L 12 1515
FID L 13 2292
FID L 14 2291
FID L 15 1515
FID L 16 1515
SNT TRC
FID C 3 8418
FID C 3 8419
FID C 3 8420
FID C 3 8421
FID C 3 8422
SNT TRC
FID C 3 8423
SNT TRC
FID C 8 6357
# NET 241
NET GPS_RST_N 
SNT TOP T 49 0
FID H 0 118
FID C 6 3021
FID C 3 8457
FID C 8 6365
FID L 11 1517
FID L 12 1517
FID L 13 2294
FID L 14 2293
FID L 15 1517
FID L 16 1517
SNT TOP T 167 3
FID C 4 3893
FID C 5 1857
FID C 3 8458
SNT TOP T 397 0
FID C 4 3891
FID C 5 1855
FID C 3 8446
SNT TOP T 400 0
FID C 4 3892
FID C 5 1856
FID C 3 8448
SNT TOP B 294 1
FID C 6 3022
FID C 7 868
FID C 8 6366
SNT TRC
FID C 3 8447
SNT TRC
FID C 3 8449
FID C 3 8450
SNT TRC
FID C 8 6363
FID C 8 6364
SNT TRC
FID C 3 8451
FID C 3 8452
FID C 3 8453
FID C 3 8454
FID C 3 8455
FID C 3 8456
# NET 242
NET GPS_UART_RXD 
SNT TOP T 167 4
FID C 4 3890
FID C 5 1854
FID C 3 8445
SNT TOP T 395 1
FID C 4 3887
FID C 5 1852
FID C 3 8440
SNT TOP T 399 1
FID C 4 3888
FID C 5 1853
FID C 3 8443
SNT TOP B 290 1
FID C 6 3019
FID C 7 867
FID C 8 6360
SNT VIA
FID H 0 2160
FID C 4 3889
FID C 6 3020
FID C 3 8444
FID C 8 6362
FID L 11 1516
FID L 12 1516
FID L 13 2293
FID L 14 2292
FID L 15 1516
FID L 16 1516
SNT TRC
FID C 3 8427
FID C 3 8428
FID C 3 8429
FID C 3 8430
FID C 3 8431
FID C 3 8432
FID C 3 8433
FID C 3 8434
FID C 3 8435
FID C 3 8436
FID C 3 8437
FID C 3 8438
FID C 3 8439
SNT TRC
FID C 8 6361
SNT TRC
FID C 3 8441
SNT TRC
FID C 3 8442
# NET 243
NET GPSTP1_OUT 
SNT TOP T 167 5
FID C 4 3898
FID C 5 1860
FID C 3 8473
SNT TOP T 398 0
FID C 4 3896
FID C 5 1859
FID C 3 8469
SNT VIA
FID H 0 2159
FID C 4 3897
FID C 6 3025
FID C 3 8470
FID C 8 6370
FID L 11 1519
FID L 12 1519
FID L 13 2296
FID L 14 2295
FID L 15 1519
FID L 16 1519
SNT TRC
FID C 3 8464
FID C 3 8465
FID C 3 8466
FID C 3 8467
FID C 3 8468
SNT TRC
FID C 3 8471
FID C 3 8472
# NET 244
NET GPSTP2_OUT 
SNT TOP T 167 6
FID C 4 3895
FID C 5 1858
FID C 3 8463
SNT TOP B 293 1
FID C 6 3023
FID C 7 869
FID C 8 6368
SNT VIA
FID H 0 2242
FID C 4 3894
FID C 6 3024
FID C 3 8462
FID C 8 6369
FID L 11 1518
FID L 12 1518
FID L 13 2295
FID L 14 2294
FID L 15 1518
FID L 16 1518
SNT TRC
FID C 3 8459
FID C 3 8460
FID C 3 8461
SNT TRC
FID C 8 6367
# NET 245
NET FT_USB_DETECT 
SNT TOP T 15 0
FID C 4 478
FID C 5 323
FID C 3 1219
SNT TOP T 53 0
FID H 0 104
FID C 6 262
FID C 3 1212
FID C 9 160
FID C 8 589
FID L 11 319
FID L 12 319
FID L 13 303
FID L 14 268
FID L 15 319
FID L 16 319
SNT TOP T 237 1
FID C 4 475
FID C 5 321
FID C 3 1211
SNT TOP T 238 0
FID C 4 477
FID C 5 322
FID C 3 1218
SNT TOP B 151 0
FID C 6 260
FID C 7 84
FID C 8 586
SNT TOP B 173 0
FID C 6 263
FID C 7 86
FID C 8 590
SNT TOP B 228 1
FID C 6 261
FID C 7 85
FID C 8 588
SNT VIA
FID H 0 309
FID C 4 476
FID C 6 264
FID C 3 1213
FID C 9 161
FID C 8 591
FID L 11 320
FID L 12 320
FID L 13 304
FID L 14 269
FID L 15 320
FID L 16 320
SNT TRC
FID C 9 136
FID C 9 137
FID C 9 138
FID C 9 139
FID C 9 140
FID C 9 141
FID C 9 142
FID C 9 143
FID C 9 144
FID C 9 145
FID C 9 146
FID C 9 147
FID C 9 148
FID C 9 149
FID C 9 150
FID C 9 151
FID C 9 152
FID C 9 153
FID C 9 154
FID C 9 155
FID C 9 156
FID C 9 157
FID C 9 158
FID C 9 159
SNT TRC
FID C 8 582
FID C 8 583
FID C 8 584
SNT TRC
FID C 8 585
SNT TRC
FID C 3 1208
FID C 3 1209
FID C 3 1210
SNT TRC
FID C 8 587
SNT TRC
FID C 3 1214
FID C 3 1215
SNT TRC
FID C 3 1216
FID C 3 1217
# NET 246
NET UNNAMED_524_POWERMOS3PNCHV1_I44 
SNT TOP T 6 14
FID C 4 369
FID C 5 258
FID C 3 860
SNT TOP T 15 2
FID C 4 368
FID C 5 257
FID C 3 859
SNT TOP T 225 0
FID C 4 367
FID C 5 256
FID C 3 858
SNT TOP T 236 0
FID C 4 366
FID C 5 255
FID C 3 857
SNT VIA
FID H 0 1317
FID C 4 365
FID C 6 182
FID C 3 852
FID C 8 442
FID L 11 265
FID L 12 265
FID L 13 249
FID L 14 214
FID L 15 265
FID L 16 265
SNT TRC
FID C 3 848
FID C 3 849
SNT TRC
FID C 3 850
FID C 3 851
SNT TRC
FID C 3 853
FID C 3 854
FID C 3 855
SNT TRC
FID C 3 856
# NET 247
NET UNNAMED_527_POWERMOS3PNCHV1_I23 
SNT TOP B 4 2
FID C 6 578
FID C 7 172
FID C 8 1664
SNT TOP B 5 0
FID C 6 577
FID C 7 171
FID C 8 1659
SNT TOP B 240 1
FID C 6 580
FID C 7 173
FID C 8 1671
SNT VIA
FID C 6 579
FID C 8 1668
SNT TRC
FID C 8 1660
FID C 8 1661
FID C 8 1662
FID C 8 1663
SNT TRC
FID C 8 1665
FID C 8 1666
FID C 8 1667
SNT TRC
FID C 8 1669
FID C 8 1670
# NET 248
NET FPGA_OUT_SN_EEPROM_WP 
SNT TOP T 170 34
FID C 4 586
FID C 5 373
FID C 3 1569
SNT TOP B 221 0
FID C 6 352
FID C 7 115
FID C 8 908
SNT VIA
FID H 0 1165
FID C 4 585
FID C 6 351
FID C 3 1566
FID C 9 717
FID C 8 907
FID L 11 380
FID L 12 380
FID L 13 364
FID L 14 329
FID L 15 380
FID L 16 380
SNT VIA
FID H 0 2368
FID C 3 1568
FID C 9 718
FID C 8 909
FID L 11 381
FID L 12 381
FID L 13 365
FID L 14 330
FID L 15 381
FID L 16 381
SNT TRC
FID C 9 678
FID C 9 679
FID C 9 680
FID C 9 681
FID C 9 682
FID C 9 683
FID C 9 684
FID C 9 685
FID C 9 686
FID C 9 687
FID C 9 688
FID C 9 689
FID C 9 690
FID C 9 691
FID C 9 692
FID C 9 693
FID C 9 694
FID C 9 695
FID C 9 696
FID C 9 697
FID C 9 698
FID C 9 699
FID C 9 700
FID C 9 701
FID C 9 702
FID C 9 703
FID C 9 704
FID C 9 705
FID C 9 706
FID C 9 707
FID C 9 708
FID C 9 709
FID C 9 710
FID C 9 711
FID C 9 712
FID C 9 713
FID C 9 714
FID C 9 715
FID C 9 716
SNT TRC
FID C 8 905
FID C 8 906
SNT TRC
FID C 3 1567
# NET 249
NET FPGA_OUT_MACUSBPOWER_EN 
SNT TOP T 170 432
FID C 4 1949
FID C 5 1169
FID C 3 4956
SNT TOP B 246 0
FID C 6 1328
FID C 7 468
FID C 8 3519
SNT TOP B 248 0
FID C 6 1327
FID C 7 467
FID C 8 3517
SNT TOP B 444 0
FID C 6 1326
FID C 7 466
FID C 8 3516
SNT VIA
FID C 6 1325
FID C 8 3510
SNT VIA
FID H 0 259
FID C 4 1948
FID C 6 1324
FID C 3 4953
FID C 9 2108
FID C 8 3500
FID L 11 1138
FID L 12 1138
FID L 13 991
FID L 14 941
FID L 15 1138
FID L 16 1138
SNT VIA
FID H 0 2366
FID C 3 4954
FID C 9 2135
FID C 8 3507
FID L 11 1139
FID L 12 1139
FID L 13 992
FID L 14 942
FID L 15 1139
FID L 16 1139
SNT TRC
FID C 8 3501
FID C 8 3502
FID C 8 3503
FID C 8 3504
FID C 8 3505
FID C 8 3506
SNT TRC
FID C 9 2109
FID C 9 2110
FID C 9 2111
FID C 9 2112
FID C 9 2113
FID C 9 2114
FID C 9 2115
FID C 9 2116
FID C 9 2117
FID C 9 2118
FID C 9 2119
FID C 9 2120
FID C 9 2121
FID C 9 2122
FID C 9 2123
FID C 9 2124
FID C 9 2125
FID C 9 2126
FID C 9 2127
FID C 9 2128
FID C 9 2129
FID C 9 2130
FID C 9 2131
FID C 9 2132
FID C 9 2133
FID C 9 2134
SNT TRC
FID C 8 3508
FID C 8 3509
SNT TRC
FID C 8 3511
FID C 8 3512
FID C 8 3513
FID C 8 3514
FID C 8 3515
SNT TRC
FID C 8 3518
SNT TRC
FID C 3 4955
# NET 250
NET XP5R0V_USB_CONN_DET 
SNT TOP T 179 0
FID C 4 2002
FID C 5 1203
FID C 3 5100
SNT TOP T 207 1
FID C 4 2001
FID C 5 1202
FID C 3 5099
SNT TOP B 244 1
FID C 6 1376
FID C 7 493
FID C 8 3635
SNT TOP B 247 0
FID C 6 1375
FID C 7 492
FID C 8 3633
SNT TOP B 444 1
FID C 6 1373
FID C 7 491
FID C 8 3629
SNT VIA
FID H 0 1067
FID C 4 1999
FID C 6 1371
FID C 3 5092
FID C 9 2226
FID C 8 3621
FID L 11 1175
FID L 12 1175
FID L 13 1028
FID L 14 967
FID L 15 1175
FID L 16 1175
SNT VIA
FID H 0 1068
FID C 4 2003
FID C 6 1374
FID C 3 5101
FID C 10 3231
FID C 8 3632
FID L 11 1177
FID L 12 1177
FID L 13 1030
FID L 14 969
FID L 15 1177
FID L 16 1177
SNT VIA
FID H 0 1401
FID C 4 2000
FID C 6 1372
FID C 3 5093
FID C 9 2241
FID C 10 3230
FID C 8 3622
FID L 11 1176
FID L 12 1176
FID L 13 1029
FID L 14 968
FID L 15 1176
FID L 16 1176
SNT TRC
FID C 10 3215
FID C 10 3216
FID C 10 3217
FID C 10 3218
FID C 10 3219
FID C 10 3220
FID C 10 3221
FID C 10 3222
FID C 10 3223
FID C 10 3224
FID C 10 3225
FID C 10 3226
FID C 10 3227
FID C 10 3228
FID C 10 3229
SNT TRC
FID C 9 2227
FID C 9 2228
FID C 9 2229
FID C 9 2230
FID C 9 2231
FID C 9 2232
FID C 9 2233
FID C 9 2234
FID C 9 2235
FID C 9 2236
FID C 9 2237
FID C 9 2238
FID C 9 2239
FID C 9 2240
SNT TRC
FID C 3 5094
FID C 3 5095
FID C 3 5096
SNT TRC
FID C 3 5097
FID C 3 5098
SNT TRC
FID C 8 3623
FID C 8 3624
FID C 8 3625
FID C 8 3626
FID C 8 3627
FID C 8 3628
SNT TRC
FID C 8 3630
FID C 8 3631
SNT TRC
FID C 8 3634
# NET 251
NET UNNAMED_527_RESISTOR_I201_2 
SNT TOP B 247 1
FID C 6 1542
FID C 7 547
FID C 8 3925
SNT TOP B 249 0
FID C 6 1543
FID C 7 548
FID C 8 3926
SNT VIA
FID C 6 1541
FID C 8 3924
SNT TRC
FID C 8 3919
FID C 8 3920
SNT TRC
FID C 8 3921
FID C 8 3922
FID C 8 3923
# NET 252
NET UNNAMED_527_RESISTOR_I126_1 
SNT TOP T 179 1
FID C 4 2237
FID C 5 1332
FID C 3 5538
SNT TOP T 206 0
FID C 4 2238
FID C 5 1333
FID C 3 5539
SNT VIA
FID H 0 2281
FID C 4 2236
FID C 6 1544
FID C 3 5532
FID C 8 3927
FID L 11 1288
FID L 12 1288
FID L 13 1099
FID L 14 1069
FID L 15 1288
FID L 16 1288
SNT TRC
FID C 3 5533
FID C 3 5534
SNT TRC
FID C 3 5535
FID C 3 5536
FID C 3 5537
# NET 253
NET MUX_USB_DM ;1=8,3=0
SNT TOP T 179 9
FID C 4 2257
FID C 5 1341
FID C 3 5597
SNT TOP T 208 1
FID C 4 2254
FID C 5 1340
FID C 3 5594
SNT TOP B 239 0
FID C 6 1559
FID C 7 553
FID C 8 3996
SNT VIA
FID H 0 2212
FID C 4 2255
FID C 6 1557
FID C 3 5595
FID C 8 3994
FID L 11 1296
FID L 12 1296
FID L 13 1107
FID L 14 1077
FID L 15 1296
FID L 16 1296
SNT VIA
FID H 0 2213
FID C 4 2256
FID C 6 1558
FID C 3 5596
FID C 8 3995
FID L 11 1297
FID L 12 1297
FID L 13 1108
FID L 14 1078
FID L 15 1297
FID L 16 1297
SNT TRC
FID C 3 5581
FID C 3 5582
FID C 3 5583
FID C 3 5584
SNT TRC
FID C 8 3972
FID C 8 3973
FID C 8 3974
FID C 8 3975
FID C 8 3976
FID C 8 3977
FID C 8 3978
SNT TRC
FID C 8 3979
FID C 8 3980
FID C 8 3981
FID C 8 3982
FID C 8 3983
FID C 8 3984
FID C 8 3985
FID C 8 3986
FID C 8 3987
FID C 8 3988
FID C 8 3989
FID C 8 3990
FID C 8 3991
FID C 8 3992
FID C 8 3993
SNT TRC
FID C 3 5585
FID C 3 5586
FID C 3 5587
FID C 3 5588
FID C 3 5589
FID C 3 5590
FID C 3 5591
FID C 3 5592
FID C 3 5593
# NET 254
NET MAC_USB_DM ;1=8,3=0
SNT TOP T 170 365
FID C 4 3824
FID C 5 1810
FID C 3 8213
SNT TOP T 179 3
FID C 4 3825
FID C 5 1811
FID C 3 8214
SNT TOP B 20 1
FID C 6 2972
FID C 7 858
FID C 8 6208
SNT TOP B 239 1
FID C 6 2973
FID C 7 859
FID C 8 6212
SNT VIA
FID H 0 2210
FID C 4 3826
FID C 6 2974
FID C 3 8215
FID C 10 3629
FID C 8 6213
FID L 11 1472
FID L 12 1472
FID L 13 2249
FID L 14 2248
FID L 15 1472
FID L 16 1472
SNT VIA
FID H 0 2564
FID C 3 8211
FID C 10 3628
FID C 8 6211
FID L 11 1471
FID L 12 1471
FID L 13 2248
FID L 14 2247
FID L 15 1471
FID L 16 1471
SNT TRC
FID C 10 3609
FID C 10 3610
FID C 10 3611
FID C 10 3612
FID C 10 3613
FID C 10 3614
FID C 10 3615
FID C 10 3616
FID C 10 3617
FID C 10 3618
FID C 10 3619
FID C 10 3620
FID C 10 3621
FID C 10 3622
FID C 10 3623
FID C 10 3624
FID C 10 3625
FID C 10 3626
FID C 10 3627
SNT TRC
FID C 8 6209
FID C 8 6210
SNT TRC
FID C 3 8212
SNT TRC
FID C 8 6214
FID C 8 6215
FID C 8 6216
FID C 8 6217
FID C 8 6218
FID C 8 6219
SNT TRC
FID C 3 8216
FID C 3 8217
FID C 3 8218
FID C 3 8219
FID C 3 8220
# NET 255
NET MUX_USB_DP ;1=8,3=0
SNT TOP T 179 10
FID C 4 2253
FID C 5 1339
FID C 3 5580
SNT TOP T 209 1
FID C 4 2250
FID C 5 1338
FID C 3 5569
SNT TOP B 121 0
FID C 6 1555
FID C 7 552
FID C 8 3970
SNT VIA
FID H 0 2214
FID C 4 2251
FID C 6 1554
FID C 3 5578
FID C 8 3969
FID L 11 1294
FID L 12 1294
FID L 13 1105
FID L 14 1075
FID L 15 1294
FID L 16 1294
SNT VIA
FID H 0 2215
FID C 4 2252
FID C 6 1556
FID C 3 5579
FID C 8 3971
FID L 11 1295
FID L 12 1295
FID L 13 1106
FID L 14 1076
FID L 15 1295
FID L 16 1295
SNT TRC
FID C 3 5564
FID C 3 5565
FID C 3 5566
FID C 3 5567
FID C 3 5568
SNT TRC
FID C 8 3946
FID C 8 3947
FID C 8 3948
FID C 8 3949
FID C 8 3950
FID C 8 3951
FID C 8 3952
FID C 8 3953
FID C 8 3954
SNT TRC
FID C 8 3955
FID C 8 3956
FID C 8 3957
FID C 8 3958
FID C 8 3959
FID C 8 3960
FID C 8 3961
FID C 8 3962
FID C 8 3963
FID C 8 3964
FID C 8 3965
FID C 8 3966
FID C 8 3967
FID C 8 3968
SNT TRC
FID C 3 5570
FID C 3 5571
FID C 3 5572
FID C 3 5573
FID C 3 5574
FID C 3 5575
FID C 3 5576
FID C 3 5577
# NET 256
NET MAC_USB_DP ;1=8,3=0
SNT TOP T 170 343
FID C 4 3821
FID C 5 1808
FID C 3 8203
SNT TOP T 179 2
FID C 4 3822
FID C 5 1809
FID C 3 8204
SNT TOP B 21 1
FID C 6 2969
FID C 7 856
FID C 8 6193
SNT TOP B 121 1
FID C 6 2970
FID C 7 857
FID C 8 6197
SNT VIA
FID H 0 2211
FID C 4 3823
FID C 6 2971
FID C 3 8205
FID C 10 3608
FID C 8 6198
FID L 11 1470
FID L 12 1470
FID L 13 2247
FID L 14 2246
FID L 15 1470
FID L 16 1470
SNT VIA
FID H 0 2565
FID C 3 8201
FID C 10 3607
FID C 8 6196
FID L 11 1469
FID L 12 1469
FID L 13 2246
FID L 14 2245
FID L 15 1469
FID L 16 1469
SNT TRC
FID C 10 3532
FID C 10 3533
FID C 10 3534
FID C 10 3535
FID C 10 3536
FID C 10 3537
FID C 10 3538
FID C 10 3539
FID C 10 3540
FID C 10 3541
FID C 10 3542
FID C 10 3543
FID C 10 3544
FID C 10 3545
FID C 10 3546
FID C 10 3547
FID C 10 3548
FID C 10 3549
FID C 10 3550
FID C 10 3551
FID C 10 3552
FID C 10 3553
FID C 10 3554
FID C 10 3555
FID C 10 3556
FID C 10 3557
FID C 10 3558
FID C 10 3559
FID C 10 3560
FID C 10 3561
FID C 10 3562
FID C 10 3563
FID C 10 3564
FID C 10 3565
FID C 10 3566
FID C 10 3567
FID C 10 3568
FID C 10 3569
FID C 10 3570
FID C 10 3571
FID C 10 3572
FID C 10 3573
FID C 10 3574
FID C 10 3575
FID C 10 3576
FID C 10 3577
FID C 10 3578
FID C 10 3579
FID C 10 3580
FID C 10 3581
FID C 10 3582
FID C 10 3583
FID C 10 3584
FID C 10 3585
FID C 10 3586
FID C 10 3587
FID C 10 3588
FID C 10 3589
FID C 10 3590
FID C 10 3591
FID C 10 3592
FID C 10 3593
FID C 10 3594
FID C 10 3595
FID C 10 3596
FID C 10 3597
FID C 10 3598
FID C 10 3599
FID C 10 3600
FID C 10 3601
FID C 10 3602
FID C 10 3603
FID C 10 3604
FID C 10 3605
FID C 10 3606
SNT TRC
FID C 8 6194
FID C 8 6195
SNT TRC
FID C 3 8202
SNT TRC
FID C 8 6199
FID C 8 6200
FID C 8 6201
FID C 8 6202
FID C 8 6203
FID C 8 6204
FID C 8 6205
FID C 8 6206
FID C 8 6207
SNT TRC
FID C 3 8206
FID C 3 8207
FID C 3 8208
FID C 3 8209
FID C 3 8210
# NET 257
NET FPGA_IN_MAC_USB_OC_N 
SNT TOP T 170 300
FID C 4 1256
FID C 5 758
FID C 3 3272
SNT TOP B 241 1
FID C 6 758
FID C 7 199
FID C 8 2290
SNT TOP B 242 1
FID C 6 759
FID C 7 200
FID C 8 2292
SNT VIA
FID H 0 1129
FID C 4 1257
FID C 6 760
FID C 3 3274
FID C 10 2310
FID C 8 2293
FID L 11 759
FID L 12 759
FID L 13 743
FID L 14 708
FID L 15 759
FID L 16 759
SNT VIA
FID H 0 2353
FID C 3 3271
FID C 10 2309
FID C 8 2284
FID L 11 758
FID L 12 758
FID L 13 742
FID L 14 707
FID L 15 758
FID L 16 758
SNT TRC
FID C 10 2280
FID C 10 2281
FID C 10 2282
FID C 10 2283
FID C 10 2284
FID C 10 2285
FID C 10 2286
FID C 10 2287
FID C 10 2288
FID C 10 2289
FID C 10 2290
FID C 10 2291
FID C 10 2292
FID C 10 2293
FID C 10 2294
FID C 10 2295
FID C 10 2296
FID C 10 2297
FID C 10 2298
FID C 10 2299
FID C 10 2300
FID C 10 2301
FID C 10 2302
FID C 10 2303
FID C 10 2304
FID C 10 2305
FID C 10 2306
FID C 10 2307
FID C 10 2308
SNT TRC
FID C 8 2285
FID C 8 2286
FID C 8 2287
FID C 8 2288
FID C 8 2289
SNT TRC
FID C 8 2291
SNT TRC
FID C 3 3273
# NET 258
NET UNNAMED_14_RESISTOR_I58_2 
SNT TOP B 323 1
FID C 6 1241
FID C 7 420
FID C 8 3274
SNT TOP B 324 0
FID C 6 1242
FID C 7 421
FID C 8 3275
SNT VIA
FID C 6 1240
FID C 8 3270
SNT TRC
FID C 8 3267
FID C 8 3268
FID C 8 3269
SNT TRC
FID C 8 3271
FID C 8 3272
FID C 8 3273
# NET 259
NET UART_GPS_TX_FPGA_RX 
SNT TOP T 170 322
FID C 4 1875
FID C 5 1118
FID C 3 4650
SNT TOP B 291 1
FID C 6 1270
FID C 7 437
FID C 8 3333
SNT TOP B 292 0
FID C 6 1269
FID C 7 436
FID C 8 3332
SNT VIA
FID H 0 1261
FID C 4 1874
FID C 6 1268
FID C 3 4648
FID C 9 2073
FID C 8 3328
FID L 11 1099
FID L 12 1099
FID L 13 952
FID L 14 902
FID L 15 1099
FID L 16 1099
SNT VIA
FID H 0 2488
FID C 3 4651
FID C 9 2074
FID C 8 3334
FID L 11 1100
FID L 12 1100
FID L 13 953
FID L 14 903
FID L 15 1100
FID L 16 1100
SNT TRC
FID C 9 2053
FID C 9 2054
FID C 9 2055
FID C 9 2056
FID C 9 2057
FID C 9 2058
FID C 9 2059
FID C 9 2060
FID C 9 2061
FID C 9 2062
FID C 9 2063
FID C 9 2064
FID C 9 2065
FID C 9 2066
FID C 9 2067
FID C 9 2068
FID C 9 2069
FID C 9 2070
FID C 9 2071
FID C 9 2072
SNT TRC
FID C 8 3325
FID C 8 3326
FID C 8 3327
SNT TRC
FID C 8 3329
FID C 8 3330
FID C 8 3331
SNT TRC
FID C 3 4649
# NET 260
NET UART_GPS_RX_FPGA_TX 
SNT TOP T 170 349
FID C 4 1877
FID C 5 1119
FID C 3 4655
SNT TOP B 290 0
FID C 6 1272
FID C 7 438
FID C 8 3339
SNT VIA
FID H 0 720
FID C 4 1876
FID C 6 1271
FID C 3 4652
FID C 9 2106
FID C 8 3338
FID L 11 1101
FID L 12 1101
FID L 13 954
FID L 14 904
FID L 15 1101
FID L 16 1101
SNT VIA
FID H 0 2576
FID C 6 1273
FID C 3 4653
FID C 9 2107
FID C 8 3340
FID L 11 1102
FID L 12 1102
FID L 13 955
FID L 14 905
FID L 15 1102
FID L 16 1102
SNT TRC
FID C 9 2075
FID C 9 2076
FID C 9 2077
FID C 9 2078
FID C 9 2079
FID C 9 2080
FID C 9 2081
FID C 9 2082
FID C 9 2083
FID C 9 2084
FID C 9 2085
FID C 9 2086
FID C 9 2087
FID C 9 2088
FID C 9 2089
FID C 9 2090
FID C 9 2091
FID C 9 2092
FID C 9 2093
FID C 9 2094
FID C 9 2095
FID C 9 2096
FID C 9 2097
FID C 9 2098
FID C 9 2099
FID C 9 2100
FID C 9 2101
FID C 9 2102
FID C 9 2103
FID C 9 2104
FID C 9 2105
SNT TRC
FID C 8 3335
FID C 8 3336
FID C 8 3337
SNT TRC
FID C 3 4654
# NET 261
NET FPGA_IN_GPSTP2_OUT 
SNT TOP T 170 475
FID C 4 1268
FID C 5 766
FID C 3 3298
SNT TOP B 15 1
FID C 6 767
FID C 7 203
FID C 8 2307
SNT TOP B 293 0
FID C 6 768
FID C 7 204
FID C 8 2310
SNT VIA
FID H 0 229
FID C 4 1270
FID C 6 770
FID C 3 3301
FID C 10 2352
FID C 8 2314
FID L 11 767
FID L 12 767
FID L 13 751
FID L 14 716
FID L 15 767
FID L 16 767
SNT VIA
FID H 0 1125
FID C 4 1269
FID C 6 769
FID C 3 3300
FID C 10 2351
FID C 8 2313
FID L 11 766
FID L 12 766
FID L 13 750
FID L 14 715
FID L 15 766
FID L 16 766
SNT VIA
FID H 0 2352
FID C 3 3297
FID C 8 2312
FID L 11 765
FID L 12 765
FID L 13 749
FID L 14 714
FID L 15 765
FID L 16 765
SNT TRC
FID C 10 2331
FID C 10 2332
FID C 10 2333
FID C 10 2334
FID C 10 2335
FID C 10 2336
FID C 10 2337
FID C 10 2338
FID C 10 2339
FID C 10 2340
FID C 10 2341
FID C 10 2342
FID C 10 2343
FID C 10 2344
FID C 10 2345
FID C 10 2346
FID C 10 2347
FID C 10 2348
FID C 10 2349
FID C 10 2350
SNT TRC
FID C 8 2303
FID C 8 2304
FID C 8 2305
FID C 8 2306
SNT TRC
FID C 8 2308
FID C 8 2309
SNT TRC
FID C 8 2311
SNT TRC
FID C 3 3299
# NET 262
NET FPGA_OUT_GPS_RST_N 
SNT TOP T 170 477
FID C 4 1951
FID C 5 1171
FID C 3 4961
SNT TOP T 397 1
FID C 4 1950
FID C 5 1170
FID C 3 4958
SNT VIA
FID H 0 1149
FID C 4 1952
FID C 6 1329
FID C 3 4962
FID C 10 3114
FID C 8 3521
FID L 11 1141
FID L 12 1141
FID L 13 994
FID L 14 944
FID L 15 1141
FID L 16 1141
SNT VIA
FID H 0 2364
FID C 3 4959
FID C 10 3113
FID C 8 3520
FID L 11 1140
FID L 12 1140
FID L 13 993
FID L 14 943
FID L 15 1140
FID L 16 1140
SNT TRC
FID C 10 3098
FID C 10 3099
FID C 10 3100
FID C 10 3101
FID C 10 3102
FID C 10 3103
FID C 10 3104
FID C 10 3105
FID C 10 3106
FID C 10 3107
FID C 10 3108
FID C 10 3109
FID C 10 3110
FID C 10 3111
FID C 10 3112
SNT TRC
FID C 3 4957
SNT TRC
FID C 3 4960
# NET 263
NET FPGA_IN_GPSTP1_OUT 
SNT TOP T 170 453
FID C 4 1273
FID C 5 768
FID C 3 3308
SNT TOP T 398 1
FID C 4 1271
FID C 5 767
FID C 3 3302
SNT TOP B 16 1
FID C 6 771
FID C 7 205
FID C 8 2315
SNT VIA
FID H 0 1124
FID C 4 1272
FID C 6 772
FID C 3 3306
FID C 10 2376
FID C 8 2319
FID L 11 769
FID L 12 769
FID L 13 753
FID L 14 718
FID L 15 769
FID L 16 769
SNT VIA
FID H 0 2351
FID C 3 3305
FID C 10 2375
FID C 8 2318
FID L 11 768
FID L 12 768
FID L 13 752
FID L 14 717
FID L 15 768
FID L 16 768
SNT TRC
FID C 10 2353
FID C 10 2354
FID C 10 2355
FID C 10 2356
FID C 10 2357
FID C 10 2358
FID C 10 2359
FID C 10 2360
FID C 10 2361
FID C 10 2362
FID C 10 2363
FID C 10 2364
FID C 10 2365
FID C 10 2366
FID C 10 2367
FID C 10 2368
FID C 10 2369
FID C 10 2370
FID C 10 2371
FID C 10 2372
FID C 10 2373
FID C 10 2374
SNT TRC
FID C 8 2316
FID C 8 2317
SNT TRC
FID C 3 3303
FID C 3 3304
SNT TRC
FID C 3 3307
# NET 264
NET ANT1_OUT 
SNT TOP T 170 427
FID C 4 997
FID C 5 607
FID C 3 2654
SNT TOP T 272 0
FID C 4 1000
FID C 5 608
FID C 3 2658
SNT VIA
FID H 0 195
FID C 4 999
FID C 6 607
FID C 3 2657
FID C 10 1500
FID C 8 1763
FID L 11 596
FID L 12 596
FID L 13 580
FID L 14 545
FID L 15 596
FID L 16 596
SNT VIA
FID H 0 1084
FID C 4 998
FID C 6 606
FID C 3 2656
FID C 9 1172
FID C 10 1499
FID C 8 1762
FID L 11 595
FID L 12 595
FID L 13 579
FID L 14 544
FID L 15 595
FID L 16 595
SNT VIA
FID H 0 2105
FID C 3 2655
FID C 9 1171
FID C 8 1761
FID L 11 594
FID L 12 594
FID L 13 578
FID L 14 543
FID L 15 594
FID L 16 594
SNT TRC
FID C 9 1135
FID C 9 1136
FID C 9 1137
FID C 9 1138
FID C 9 1139
FID C 9 1140
FID C 9 1141
FID C 9 1142
FID C 9 1143
FID C 9 1144
FID C 9 1145
FID C 9 1146
FID C 9 1147
FID C 9 1148
FID C 9 1149
FID C 9 1150
FID C 9 1151
FID C 9 1152
FID C 9 1153
FID C 9 1154
FID C 9 1155
FID C 9 1156
FID C 9 1157
FID C 9 1158
FID C 9 1159
FID C 9 1160
FID C 9 1161
FID C 9 1162
FID C 9 1163
FID C 9 1164
FID C 9 1165
FID C 9 1166
FID C 9 1167
FID C 9 1168
FID C 9 1169
FID C 9 1170
SNT TRC
FID C 10 1476
FID C 10 1477
FID C 10 1478
FID C 10 1479
FID C 10 1480
FID C 10 1481
FID C 10 1482
FID C 10 1483
FID C 10 1484
FID C 10 1485
FID C 10 1486
FID C 10 1487
FID C 10 1488
FID C 10 1489
FID C 10 1490
FID C 10 1491
FID C 10 1492
FID C 10 1493
FID C 10 1494
FID C 10 1495
FID C 10 1496
FID C 10 1497
FID C 10 1498
SNT TRC
FID C 3 2649
FID C 3 2650
FID C 3 2651
FID C 3 2652
SNT TRC
FID C 3 2653
# NET 265
NET UNNAMED_12_74HCT2G125DPTSSOP8_6 
SNT TOP T 125 1
FID C 4 897
FID C 5 542
FID C 3 2341
SNT TOP T 272 1
FID C 4 898
FID C 5 543
FID C 3 2342
SNT TOP B 126 1
FID C 6 545
FID C 7 162
FID C 8 1612
SNT VIA
FID H 0 1265
FID C 4 896
FID C 6 546
FID C 3 2340
FID C 8 1613
FID L 11 550
FID L 12 550
FID L 13 534
FID L 14 499
FID L 15 550
FID L 16 550
SNT TRC
FID C 3 2335
FID C 3 2336
SNT TRC
FID C 8 1610
FID C 8 1611
SNT TRC
FID C 3 2337
FID C 3 2338
FID C 3 2339
# NET 266
NET ANT2_OUT 
SNT TOP T 170 449
FID C 4 992
FID C 5 604
FID C 3 2639
SNT TOP T 273 0
FID C 4 990
FID C 5 603
FID C 3 2635
SNT VIA
FID H 0 197
FID C 4 989
FID C 6 601
FID C 3 2634
FID C 10 1443
FID C 8 1741
FID L 11 588
FID L 12 588
FID L 13 572
FID L 14 537
FID L 15 588
FID L 16 588
SNT VIA
FID H 0 1086
FID C 4 991
FID C 6 602
FID C 3 2636
FID C 9 1133
FID C 10 1444
FID C 8 1742
FID L 11 589
FID L 12 589
FID L 13 573
FID L 14 538
FID L 15 589
FID L 16 589
SNT VIA
FID H 0 2341
FID C 3 2637
FID C 9 1134
FID C 8 1743
FID L 11 590
FID L 12 590
FID L 13 574
FID L 14 539
FID L 15 590
FID L 16 590
SNT TRC
FID C 9 1099
FID C 9 1100
FID C 9 1101
FID C 9 1102
FID C 9 1103
FID C 9 1104
FID C 9 1105
FID C 9 1106
FID C 9 1107
FID C 9 1108
FID C 9 1109
FID C 9 1110
FID C 9 1111
FID C 9 1112
FID C 9 1113
FID C 9 1114
FID C 9 1115
FID C 9 1116
FID C 9 1117
FID C 9 1118
FID C 9 1119
FID C 9 1120
FID C 9 1121
FID C 9 1122
FID C 9 1123
FID C 9 1124
FID C 9 1125
FID C 9 1126
FID C 9 1127
FID C 9 1128
FID C 9 1129
FID C 9 1130
FID C 9 1131
FID C 9 1132
SNT TRC
FID C 3 2631
FID C 3 2632
FID C 3 2633
SNT TRC
FID C 10 1429
FID C 10 1430
FID C 10 1431
FID C 10 1432
FID C 10 1433
FID C 10 1434
FID C 10 1435
FID C 10 1436
FID C 10 1437
FID C 10 1438
FID C 10 1439
FID C 10 1440
FID C 10 1441
FID C 10 1442
SNT TRC
FID C 3 2638
# NET 267
NET UNNAMED_12_74HCT2G125DPTSSOP8_9 
SNT TOP T 126 1
FID C 4 893
FID C 5 540
FID C 3 2332
SNT TOP T 273 1
FID C 4 895
FID C 5 541
FID C 3 2334
SNT TOP B 127 1
FID C 6 543
FID C 7 161
FID C 8 1608
SNT VIA
FID H 0 1266
FID C 4 894
FID C 6 544
FID C 3 2333
FID C 8 1609
FID L 11 549
FID L 12 549
FID L 13 533
FID L 14 498
FID L 15 549
FID L 16 549
SNT TRC
FID C 3 2329
FID C 3 2330
SNT TRC
FID C 3 2331
SNT TRC
FID C 8 1607
# NET 268
NET BF_SMA3_SIG_IO_CONN 
SNT TOP T 127 4
FID C 4 930
FID C 5 563
FID C 3 2439
SNT TOP T 127 5
FID C 4 929
FID C 5 562
FID C 3 2438
SNT TOP T 220 1
FID C 4 931
FID C 5 564
FID C 3 2440
SNT TOP T 274 0
FID C 4 932
FID C 5 565
FID C 3 2441
SNT VIA
FID H 0 1096
FID C 4 928
FID C 6 560
FID C 3 2433
FID C 8 1633
FID L 11 562
FID L 12 562
FID L 13 546
FID L 14 511
FID L 15 562
FID L 16 562
SNT TRC
FID C 3 2429
SNT TRC
FID C 3 2430
FID C 3 2431
FID C 3 2432
SNT TRC
FID C 3 2434
SNT TRC
FID C 3 2435
FID C 3 2436
FID C 3 2437
# NET 269
NET BF_SMA4_SIG_IO_CONN 
SNT TOP T 128 4
FID C 4 926
FID C 5 560
FID C 3 2427
SNT TOP T 128 5
FID C 4 925
FID C 5 559
FID C 3 2426
SNT TOP T 221 1
FID C 4 927
FID C 5 561
FID C 3 2428
SNT TOP B 181 0
FID C 6 558
FID C 7 164
FID C 8 1631
SNT VIA
FID H 0 1097
FID C 4 924
FID C 6 559
FID C 3 2420
FID C 8 1632
FID L 11 561
FID L 12 561
FID L 13 545
FID L 14 510
FID L 15 561
FID L 16 561
SNT TRC
FID C 3 2415
FID C 3 2416
SNT TRC
FID C 3 2417
FID C 3 2418
FID C 3 2419
SNT TRC
FID C 8 1628
FID C 8 1629
FID C 8 1630
SNT TRC
FID C 3 2421
FID C 3 2422
FID C 3 2423
FID C 3 2424
FID C 3 2425
# NET 270
NET FPGA_OUT_SMA1_LED_BLUE_N 
SNT TOP T 170 166
FID C 4 876
FID C 5 532
FID C 3 2297
SNT TOP T 297 0
FID C 4 878
FID C 5 533
FID C 3 2299
SNT VIA
FID H 0 267
FID C 4 879
FID C 6 534
FID C 3 2300
FID C 8 1597
FID L 11 539
FID L 12 539
FID L 13 523
FID L 14 488
FID L 15 539
FID L 16 539
SNT VIA
FID H 0 1153
FID C 4 877
FID C 6 533
FID C 3 2298
FID C 10 1297
FID C 8 1596
FID L 11 538
FID L 12 538
FID L 13 522
FID L 14 487
FID L 15 538
FID L 16 538
SNT VIA
FID H 0 2126
FID C 3 2295
FID C 10 1296
FID C 8 1580
FID L 11 537
FID L 12 537
FID L 13 521
FID L 14 486
FID L 15 537
FID L 16 537
SNT TRC
FID C 10 1276
FID C 10 1277
FID C 10 1278
FID C 10 1279
FID C 10 1280
FID C 10 1281
FID C 10 1282
FID C 10 1283
FID C 10 1284
FID C 10 1285
FID C 10 1286
FID C 10 1287
FID C 10 1288
FID C 10 1289
FID C 10 1290
FID C 10 1291
FID C 10 1292
FID C 10 1293
FID C 10 1294
FID C 10 1295
SNT TRC
FID C 3 2296
SNT TRC
FID C 8 1581
FID C 8 1582
FID C 8 1583
FID C 8 1584
FID C 8 1585
FID C 8 1586
FID C 8 1587
FID C 8 1588
FID C 8 1589
FID C 8 1590
FID C 8 1591
FID C 8 1592
FID C 8 1593
FID C 8 1594
FID C 8 1595
SNT TRC
FID C 3 2301
# NET 271
NET FPGA_OUT_SMA1_LED_GREEN_N 
SNT TOP T 170 167
FID C 4 873
FID C 5 530
FID C 3 2291
SNT TOP T 319 0
FID C 4 874
FID C 5 531
FID C 3 2292
SNT VIA
FID H 0 268
FID C 4 875
FID C 6 532
FID C 3 2293
FID C 8 1579
FID L 11 536
FID L 12 536
FID L 13 520
FID L 14 485
FID L 15 536
FID L 16 536
SNT VIA
FID H 0 1154
FID C 4 872
FID C 6 531
FID C 3 2290
FID C 10 1275
FID C 8 1578
FID L 11 535
FID L 12 535
FID L 13 519
FID L 14 484
FID L 15 535
FID L 16 535
SNT VIA
FID H 0 2127
FID C 3 2288
FID C 10 1274
FID C 8 1557
FID L 11 534
FID L 12 534
FID L 13 518
FID L 14 483
FID L 15 534
FID L 16 534
SNT TRC
FID C 10 1255
FID C 10 1256
FID C 10 1257
FID C 10 1258
FID C 10 1259
FID C 10 1260
FID C 10 1261
FID C 10 1262
FID C 10 1263
FID C 10 1264
FID C 10 1265
FID C 10 1266
FID C 10 1267
FID C 10 1268
FID C 10 1269
FID C 10 1270
FID C 10 1271
FID C 10 1272
FID C 10 1273
SNT TRC
FID C 3 2289
SNT TRC
FID C 8 1558
FID C 8 1559
FID C 8 1560
FID C 8 1561
FID C 8 1562
FID C 8 1563
FID C 8 1564
FID C 8 1565
FID C 8 1566
FID C 8 1567
FID C 8 1568
FID C 8 1569
FID C 8 1570
FID C 8 1571
FID C 8 1572
FID C 8 1573
FID C 8 1574
FID C 8 1575
FID C 8 1576
FID C 8 1577
SNT TRC
FID C 3 2294
# NET 272
NET BF_SMA2_SIG_IO_CONN 
SNT TOP T 126 4
FID C 4 917
FID C 5 553
FID C 3 2398
SNT TOP T 126 5
FID C 4 918
FID C 5 554
FID C 3 2399
SNT TOP T 223 1
FID C 4 916
FID C 5 552
FID C 3 2397
SNT TOP T 275 0
FID C 4 915
FID C 5 551
FID C 3 2396
SNT VIA
FID H 0 1095
FID C 4 914
FID C 6 556
FID C 3 2391
FID C 8 1626
FID L 11 559
FID L 12 559
FID L 13 543
FID L 14 508
FID L 15 559
FID L 16 559
SNT TRC
FID C 3 2386
FID C 3 2387
SNT TRC
FID C 3 2388
FID C 3 2389
FID C 3 2390
SNT TRC
FID C 3 2392
SNT TRC
FID C 3 2393
FID C 3 2394
FID C 3 2395
# NET 273
NET BF_SMA1_SIG_IO_CONN 
SNT TOP T 125 4
FID C 4 921
FID C 5 556
FID C 3 2412
SNT TOP T 125 5
FID C 4 922
FID C 5 557
FID C 3 2413
SNT TOP T 222 1
FID C 4 923
FID C 5 558
FID C 3 2414
SNT TOP T 276 0
FID C 4 920
FID C 5 555
FID C 3 2408
SNT VIA
FID H 0 1094
FID C 4 919
FID C 6 557
FID C 3 2403
FID C 8 1627
FID L 11 560
FID L 12 560
FID L 13 544
FID L 14 509
FID L 15 560
FID L 16 560
SNT TRC
FID C 3 2400
FID C 3 2401
FID C 3 2402
SNT TRC
FID C 3 2404
FID C 3 2405
SNT TRC
FID C 3 2406
FID C 3 2407
SNT TRC
FID C 3 2409
FID C 3 2410
FID C 3 2411
# NET 274
NET R_FT_USB_DM ;1=0
SNT TOP T 13 6
FID C 4 434
FID C 5 299
FID C 3 1030
SNT TOP T 260 1
FID C 4 435
FID C 5 300
FID C 3 1043
SNT TRC
FID C 3 1031
FID C 3 1032
FID C 3 1033
FID C 3 1034
FID C 3 1035
FID C 3 1036
FID C 3 1037
FID C 3 1038
FID C 3 1039
FID C 3 1040
FID C 3 1041
FID C 3 1042
# NET 275
NET R_FT_USB_DP ;1=0
SNT TOP T 13 7
FID C 4 432
FID C 5 297
FID C 3 1028
SNT TOP T 261 1
FID C 4 433
FID C 5 298
FID C 3 1029
SNT TRC
FID C 3 1015
FID C 3 1016
FID C 3 1017
FID C 3 1018
FID C 3 1019
FID C 3 1020
FID C 3 1021
FID C 3 1022
FID C 3 1023
FID C 3 1024
FID C 3 1025
FID C 3 1026
FID C 3 1027
# NET 276
NET XP12R0V_A_PG 
SNT TOP T 28 0
FID H 0 160
FID C 6 1199
FID C 3 4498
FID C 8 3178
FID L 11 1073
FID L 12 1073
FID L 13 926
FID L 14 876
FID L 15 1073
FID L 16 1073
SNT TOP T 189 9
FID C 4 1800
FID C 5 1069
FID C 3 4494
SNT TOP T 336 1
FID C 4 1802
FID C 5 1070
FID C 3 4504
SNT TOP T 427 0
FID C 4 1803
FID C 5 1071
FID C 3 4506
SNT VIA
FID H 0 2196
FID C 4 1801
FID C 6 1200
FID C 3 4503
FID C 8 3179
FID L 11 1074
FID L 12 1074
FID L 13 927
FID L 14 877
FID L 15 1074
FID L 16 1074
SNT TRC
FID C 3 4495
SNT TRC
FID C 3 4496
FID C 3 4497
SNT TRC
FID C 3 4499
FID C 3 4500
FID C 3 4501
FID C 3 4502
SNT TRC
FID C 3 4505
# NET 277
NET R_FT4232_CHD_TX 
SNT TOP T 13 47
FID C 4 453
FID C 5 310
FID C 3 1093
SNT TOP B 344 0
FID C 6 245
FID C 7 81
FID C 8 565
SNT VIA
FID H 0 1208
FID C 4 452
FID C 6 246
FID C 3 1092
FID C 8 566
FID L 11 307
FID L 12 307
FID L 13 291
FID L 14 256
FID L 15 307
FID L 16 307
SNT TRC
FID C 8 563
FID C 8 564
SNT TRC
FID C 3 1090
FID C 3 1091
# NET 278
NET R_FT4232_CHD_RX 
SNT TOP T 13 51
FID C 4 455
FID C 5 311
FID C 3 1097
SNT TOP B 345 0
FID C 6 247
FID C 7 82
FID C 8 568
SNT TOP B 346 0
FID C 6 248
FID C 7 83
FID C 8 570
SNT VIA
FID H 0 1207
FID C 4 454
FID C 6 249
FID C 3 1096
FID C 8 571
FID L 11 308
FID L 12 308
FID L 13 292
FID L 14 257
FID L 15 308
FID L 16 308
SNT TRC
FID C 3 1094
FID C 3 1095
SNT TRC
FID C 8 567
SNT TRC
FID C 8 569
# NET 279
NET FPGA_TCK 
SNT TOP T 170 429
FID C 4 3906
FID C 5 1863
FID C 3 8486
SNT TOP B 217 1
FID C 6 3040
FID C 7 880
FID C 8 6413
SNT TOP B 303 1
FID C 6 3042
FID C 7 882
FID C 8 6417
SNT TOP B 305 0
FID C 6 3041
FID C 7 881
FID C 8 6415
SNT VIA
FID H 0 2234
FID C 4 3905
FID C 6 3043
FID C 3 8485
FID C 10 3756
FID C 8 6418
FID L 11 1527
FID L 12 1527
FID L 13 2304
FID L 14 2303
FID L 15 1527
FID L 16 1527
SNT VIA
FID H 0 2371
FID C 3 8484
FID C 10 3755
FID C 8 6414
FID L 11 1526
FID L 12 1526
FID L 13 2303
FID L 14 2302
FID L 15 1526
FID L 16 1526
SNT TRC
FID C 10 3722
FID C 10 3723
FID C 10 3724
FID C 10 3725
FID C 10 3726
FID C 10 3727
FID C 10 3728
FID C 10 3729
FID C 10 3730
FID C 10 3731
FID C 10 3732
FID C 10 3733
FID C 10 3734
FID C 10 3735
FID C 10 3736
FID C 10 3737
FID C 10 3738
FID C 10 3739
FID C 10 3740
FID C 10 3741
FID C 10 3742
FID C 10 3743
FID C 10 3744
FID C 10 3745
FID C 10 3746
FID C 10 3747
FID C 10 3748
FID C 10 3749
FID C 10 3750
FID C 10 3751
FID C 10 3752
FID C 10 3753
FID C 10 3754
SNT TRC
FID C 8 6410
FID C 8 6411
SNT TRC
FID C 8 6412
SNT TRC
FID C 8 6416
SNT TRC
FID C 3 8487
# NET 280
NET FPGA_TDO 
SNT TOP B 216 1
FID C 6 3030
FID C 7 873
FID C 8 6382
SNT TOP B 227 0
FID C 6 3031
FID C 7 874
FID C 8 6391
SNT TOP B 301 1
FID C 6 3034
FID C 7 876
FID C 8 6394
SNT TOP B 304 1
FID C 6 3033
FID C 7 875
FID C 8 6393
SNT VIA
FID H 0 278
FID C 4 3901
FID C 6 3032
FID C 3 8478
FID C 10 3691
FID C 8 6392
FID L 11 1522
FID L 12 1522
FID L 13 2299
FID L 14 2298
FID L 15 1522
FID L 16 1522
SNT VIA
FID H 0 2236
FID C 4 3902
FID C 6 3035
FID C 3 8479
FID C 10 3692
FID C 8 6395
FID L 11 1523
FID L 12 1523
FID L 13 2300
FID L 14 2299
FID L 15 1523
FID L 16 1523
SNT TRC
FID C 10 3676
FID C 10 3677
FID C 10 3678
FID C 10 3679
FID C 10 3680
FID C 10 3681
FID C 10 3682
FID C 10 3683
FID C 10 3684
FID C 10 3685
FID C 10 3686
FID C 10 3687
FID C 10 3688
FID C 10 3689
FID C 10 3690
SNT TRC
FID C 8 6383
SNT TRC
FID C 8 6384
FID C 8 6385
FID C 8 6386
SNT TRC
FID C 8 6387
FID C 8 6388
FID C 8 6389
FID C 8 6390
SNT TRC
FID C 8 6396
FID C 8 6397
# NET 281
NET FPGA_TMS 
SNT TOP T 170 386
FID C 4 3900
FID C 5 1861
FID C 3 8477
SNT TOP B 214 1
FID C 6 3027
FID C 7 870
FID C 8 6378
SNT TOP B 310 1
FID C 6 3028
FID C 7 871
FID C 8 6379
SNT TOP B 317 1
FID C 6 3029
FID C 7 872
FID C 8 6380
SNT VIA
FID H 0 1168
FID C 4 3899
FID C 6 3026
FID C 3 8475
FID C 10 3675
FID C 8 6374
FID L 11 1521
FID L 12 1521
FID L 13 2298
FID L 14 2297
FID L 15 1521
FID L 16 1521
SNT VIA
FID H 0 2373
FID C 3 8474
FID C 10 3674
FID C 8 6373
FID L 11 1520
FID L 12 1520
FID L 13 2297
FID L 14 2296
FID L 15 1520
FID L 16 1520
SNT TRC
FID C 8 6371
FID C 8 6372
SNT TRC
FID C 10 3649
FID C 10 3650
FID C 10 3651
FID C 10 3652
FID C 10 3653
FID C 10 3654
FID C 10 3655
FID C 10 3656
FID C 10 3657
FID C 10 3658
FID C 10 3659
FID C 10 3660
FID C 10 3661
FID C 10 3662
FID C 10 3663
FID C 10 3664
FID C 10 3665
FID C 10 3666
FID C 10 3667
FID C 10 3668
FID C 10 3669
FID C 10 3670
FID C 10 3671
FID C 10 3672
FID C 10 3673
SNT TRC
FID C 3 8476
SNT TRC
FID C 8 6375
FID C 8 6376
FID C 8 6377
SNT TRC
FID C 8 6381
# NET 282
NET FPGA_TDI 
SNT TOP T 170 364
FID C 4 3904
FID C 5 1862
FID C 3 8483
SNT TOP B 215 1
FID C 6 3036
FID C 7 877
FID C 8 6398
SNT TOP B 309 1
FID C 6 3037
FID C 7 878
FID C 8 6407
SNT TOP B 316 1
FID C 6 3038
FID C 7 879
FID C 8 6408
SNT VIA
FID H 0 2235
FID C 4 3903
FID C 6 3039
FID C 3 8481
FID C 10 3721
FID C 8 6409
FID L 11 1525
FID L 12 1525
FID L 13 2302
FID L 14 2301
FID L 15 1525
FID L 16 1525
SNT VIA
FID H 0 2372
FID C 3 8480
FID C 10 3720
FID C 8 6403
FID L 11 1524
FID L 12 1524
FID L 13 2301
FID L 14 2300
FID L 15 1524
FID L 16 1524
SNT TRC
FID C 10 3693
FID C 10 3694
FID C 10 3695
FID C 10 3696
FID C 10 3697
FID C 10 3698
FID C 10 3699
FID C 10 3700
FID C 10 3701
FID C 10 3702
FID C 10 3703
FID C 10 3704
FID C 10 3705
FID C 10 3706
FID C 10 3707
FID C 10 3708
FID C 10 3709
FID C 10 3710
FID C 10 3711
FID C 10 3712
FID C 10 3713
FID C 10 3714
FID C 10 3715
FID C 10 3716
FID C 10 3717
FID C 10 3718
FID C 10 3719
SNT TRC
FID C 8 6399
SNT TRC
FID C 8 6400
FID C 8 6401
FID C 8 6402
SNT TRC
FID C 8 6404
FID C 8 6405
FID C 8 6406
SNT TRC
FID C 3 8482
# NET 283
NET XP1R0V_FPGA_PG 
SNT TOP T 25 0
FID H 0 163
FID C 6 1158
FID C 3 4400
FID C 10 2674
FID C 8 3104
FID L 11 1042
FID L 12 1042
FID L 13 914
FID L 14 845
FID L 15 1042
FID L 16 1042
SNT TOP T 389 0
FID C 4 1750
FID C 5 1041
FID C 3 4405
SNT TOP T 410 0
FID C 4 1748
FID C 5 1040
FID C 3 4402
SNT VIA
FID H 0 826
FID C 4 1749
FID C 6 1160
FID C 3 4404
FID C 8 3106
FID L 11 1044
FID L 12 1044
FID L 13 916
FID L 14 847
FID L 15 1044
FID L 16 1044
SNT VIA
FID H 0 2197
FID C 4 1747
FID C 6 1159
FID C 3 4401
FID C 10 2675
FID C 8 3105
FID L 11 1043
FID L 12 1043
FID L 13 915
FID L 14 846
FID L 15 1043
FID L 16 1043
SNT TRC
FID C 8 3092
FID C 8 3093
FID C 8 3094
FID C 8 3095
FID C 8 3096
FID C 8 3097
FID C 8 3098
FID C 8 3099
FID C 8 3100
FID C 8 3101
FID C 8 3102
FID C 8 3103
SNT TRC
FID C 10 2654
FID C 10 2655
FID C 10 2656
FID C 10 2657
FID C 10 2658
FID C 10 2659
FID C 10 2660
FID C 10 2661
FID C 10 2662
FID C 10 2663
FID C 10 2664
FID C 10 2665
FID C 10 2666
FID C 10 2667
FID C 10 2668
FID C 10 2669
FID C 10 2670
FID C 10 2671
FID C 10 2672
FID C 10 2673
SNT TRC
FID C 3 4397
FID C 3 4398
FID C 3 4399
SNT TRC
FID C 3 4403
# NET 284
NET XP1R2V_FPGA_PG 
SNT TOP T 24 0
FID H 0 165
FID C 6 1112
FID C 3 4265
FID C 8 2996
FID L 11 1004
FID L 12 1004
FID L 13 906
FID L 14 807
FID L 15 1004
FID L 16 1004
SNT TOP T 382 1
FID C 4 1682
FID C 5 994
FID C 3 4266
SNT TOP T 385 0
FID C 4 1683
FID C 5 995
FID C 3 4267
SNT TRC
FID C 3 4254
FID C 3 4255
FID C 3 4256
FID C 3 4257
FID C 3 4258
FID C 3 4259
FID C 3 4260
FID C 3 4261
FID C 3 4262
FID C 3 4263
SNT TRC
FID C 3 4264
# NET 285
NET XP1R8V_FPGA_PG 
SNT TOP T 23 0
FID H 0 166
FID C 6 1084
FID C 3 4175
FID C 10 2652
FID C 8 2956
FID L 11 983
FID L 12 983
FID L 13 885
FID L 14 796
FID L 15 983
FID L 16 983
SNT TOP T 403 1
FID C 4 1636
FID C 5 967
FID C 3 4174
SNT TOP B 220 0
FID C 6 1090
FID C 7 350
FID C 8 2969
SNT TOP B 251 0
FID C 6 1083
FID C 7 348
FID C 8 2955
SNT TOP B 254 0
FID C 6 1086
FID C 7 349
FID C 8 2965
SNT VIA
FID H 0 850
FID C 4 1640
FID C 6 1089
FID C 3 4179
FID C 9 2037
FID C 8 2968
FID L 11 987
FID L 12 987
FID L 13 889
FID L 14 800
FID L 15 987
FID L 16 987
SNT VIA
FID H 0 851
FID C 4 1639
FID C 6 1088
FID C 3 4178
FID C 8 2967
FID L 11 986
FID L 12 986
FID L 13 888
FID L 14 799
FID L 15 986
FID L 16 986
SNT VIA
FID H 0 852
FID C 4 1638
FID C 6 1087
FID C 3 4177
FID C 10 2653
FID C 8 2966
FID L 11 985
FID L 12 985
FID L 13 887
FID L 14 798
FID L 15 985
FID L 16 985
SNT VIA
FID H 0 2296
FID C 4 1637
FID C 6 1085
FID C 3 4176
FID C 9 2036
FID C 8 2962
FID L 11 984
FID L 12 984
FID L 13 886
FID L 14 797
FID L 15 984
FID L 16 984
SNT TRC
FID C 9 2019
FID C 9 2020
FID C 9 2021
FID C 9 2022
FID C 9 2023
FID C 9 2024
FID C 9 2025
FID C 9 2026
FID C 9 2027
FID C 9 2028
FID C 9 2029
FID C 9 2030
FID C 9 2031
FID C 9 2032
FID C 9 2033
FID C 9 2034
FID C 9 2035
SNT TRC
FID C 10 2631
FID C 10 2632
FID C 10 2633
FID C 10 2634
FID C 10 2635
FID C 10 2636
FID C 10 2637
FID C 10 2638
FID C 10 2639
FID C 10 2640
FID C 10 2641
FID C 10 2642
FID C 10 2643
FID C 10 2644
FID C 10 2645
FID C 10 2646
FID C 10 2647
FID C 10 2648
FID C 10 2649
FID C 10 2650
FID C 10 2651
SNT TRC
FID C 3 4169
FID C 3 4170
FID C 3 4171
SNT TRC
FID C 3 4172
FID C 3 4173
SNT TRC
FID C 8 2945
FID C 8 2946
FID C 8 2947
FID C 8 2948
FID C 8 2949
FID C 8 2950
FID C 8 2951
FID C 8 2952
FID C 8 2953
FID C 8 2954
SNT TRC
FID C 8 2957
FID C 8 2958
SNT TRC
FID C 8 2959
FID C 8 2960
FID C 8 2961
SNT TRC
FID C 8 2963
FID C 8 2964
# NET 286
NET UNNAMED_515_NCP45560IMNTWGHDFN1 
SNT TOP T 119 5
FID C 4 1192
FID C 5 716
FID C 3 3102
SNT TOP T 381 1
FID C 4 1193
FID C 5 717
FID C 3 3105
SNT TOP B 175 1
FID C 6 709
FID C 7 189
FID C 8 2149
SNT VIA
FID H 0 2181
FID C 4 1194
FID C 6 710
FID C 3 3108
FID C 8 2151
FID L 11 703
FID L 12 703
FID L 13 687
FID L 14 652
FID L 15 703
FID L 16 703
SNT TRC
FID C 8 2150
SNT TRC
FID C 3 3103
FID C 3 3104
SNT TRC
FID C 3 3106
FID C 3 3107
# NET 287
NET PCA9546_I2C_SDA 
SNT TOP T 4 3
FID C 4 3814
FID C 5 1806
FID C 3 8183
SNT TOP B 183 0
FID C 6 2962
FID C 7 854
FID C 8 6174
SNT VIA
FID H 0 327
FID C 4 3811
FID C 6 2959
FID C 3 8167
FID C 9 2596
FID C 8 6143
FID L 11 1461
FID L 12 1461
FID L 13 2238
FID L 14 2237
FID L 15 1461
FID L 16 1461
SNT VIA
FID H 0 328
FID C 4 3815
FID C 6 2963
FID C 3 8184
FID C 8 6175
FID L 11 1464
FID L 12 1464
FID L 13 2241
FID L 14 2240
FID L 15 1464
FID L 16 1464
SNT VIA
FID H 0 329
FID C 4 3812
FID C 6 2960
FID C 3 8181
FID C 9 2597
FID C 8 6172
FID L 11 1462
FID L 12 1462
FID L 13 2239
FID L 14 2238
FID L 15 1462
FID L 16 1462
SNT VIA
FID H 0 1196
FID C 4 3813
FID C 6 2961
FID C 3 8182
FID C 8 6173
FID L 11 1463
FID L 12 1463
FID L 13 2240
FID L 14 2239
FID L 15 1463
FID L 16 1463
SNT TRC
FID C 9 2589
FID C 9 2590
FID C 9 2591
FID C 9 2592
FID C 9 2593
FID C 9 2594
FID C 9 2595
SNT TRC
FID C 8 6144
FID C 8 6145
FID C 8 6146
FID C 8 6147
FID C 8 6148
FID C 8 6149
FID C 8 6150
FID C 8 6151
FID C 8 6152
FID C 8 6153
FID C 8 6154
FID C 8 6155
FID C 8 6156
FID C 8 6157
FID C 8 6158
FID C 8 6159
FID C 8 6160
FID C 8 6161
FID C 8 6162
FID C 8 6163
FID C 8 6164
FID C 8 6165
SNT TRC
FID C 3 8168
FID C 3 8169
SNT TRC
FID C 3 8170
FID C 3 8171
FID C 3 8172
FID C 3 8173
FID C 3 8174
FID C 3 8175
FID C 3 8176
FID C 3 8177
FID C 3 8178
FID C 3 8179
FID C 3 8180
SNT TRC
FID C 8 6166
FID C 8 6167
FID C 8 6168
FID C 8 6169
FID C 8 6170
FID C 8 6171
# NET 288
NET R_PCA9546_I2C_SDA 
SNT TOP T 388 1
FID C 4 1881
FID C 5 1122
FID C 3 4663
SNT TOP T 604 14
FID C 4 1883
FID C 5 1123
FID C 3 4669
SNT TOP B 183 1
FID C 6 1278
FID C 7 441
FID C 8 3356
SNT TOP B 208 1
FID C 6 1280
FID C 7 442
FID C 8 3358
SNT TOP B 209 1
FID C 6 1281
FID C 7 443
FID C 8 3360
SNT TOP B 210 1
FID C 6 1282
FID C 7 444
FID C 8 3362
SNT VIA
FID H 0 1433
FID C 4 1882
FID C 6 1277
FID C 3 4666
FID C 10 2734
FID C 8 3350
FID L 11 1104
FID L 12 1104
FID L 13 957
FID L 14 907
FID L 15 1104
FID L 16 1104
SNT VIA
FID H 0 2257
FID C 4 1884
FID C 6 1279
FID C 3 4670
FID C 10 2735
FID C 8 3357
FID L 11 1105
FID L 12 1105
FID L 13 958
FID L 14 908
FID L 15 1105
FID L 16 1105
SNT TRC
FID C 10 2687
FID C 10 2688
FID C 10 2689
FID C 10 2690
FID C 10 2691
FID C 10 2692
FID C 10 2693
FID C 10 2694
FID C 10 2695
FID C 10 2696
FID C 10 2697
FID C 10 2698
FID C 10 2699
FID C 10 2700
FID C 10 2701
FID C 10 2702
FID C 10 2703
FID C 10 2704
FID C 10 2705
FID C 10 2706
FID C 10 2707
FID C 10 2708
FID C 10 2709
FID C 10 2710
FID C 10 2711
FID C 10 2712
FID C 10 2713
FID C 10 2714
FID C 10 2715
FID C 10 2716
FID C 10 2717
FID C 10 2718
FID C 10 2719
FID C 10 2720
FID C 10 2721
FID C 10 2722
FID C 10 2723
FID C 10 2724
FID C 10 2725
FID C 10 2726
FID C 10 2727
FID C 10 2728
FID C 10 2729
FID C 10 2730
FID C 10 2731
FID C 10 2732
FID C 10 2733
SNT TRC
FID C 3 4664
FID C 3 4665
SNT TRC
FID C 3 4667
FID C 3 4668
SNT TRC
FID C 8 3351
SNT TRC
FID C 8 3352
SNT TRC
FID C 8 3353
FID C 8 3354
FID C 8 3355
SNT TRC
FID C 8 3359
SNT TRC
FID C 8 3361
# NET 289
NET PCA9546_I2C_SCL 
SNT TOP T 4 6
FID C 4 3820
FID C 5 1807
FID C 3 8200
SNT TOP B 211 0
FID C 6 2967
FID C 7 855
FID C 8 6191
SNT VIA
FID H 0 324
FID C 4 3816
FID C 6 2964
FID C 3 8185
FID C 9 2604
FID C 8 6176
FID L 11 1465
FID L 12 1465
FID L 13 2242
FID L 14 2241
FID L 15 1465
FID L 16 1465
SNT VIA
FID H 0 325
FID C 4 3819
FID C 6 2968
FID C 3 8199
FID C 8 6192
FID L 11 1468
FID L 12 1468
FID L 13 2245
FID L 14 2244
FID L 15 1468
FID L 16 1468
SNT VIA
FID H 0 326
FID C 4 3817
FID C 6 2965
FID C 3 8195
FID C 9 2605
FID C 8 6189
FID L 11 1466
FID L 12 1466
FID L 13 2243
FID L 14 2242
FID L 15 1466
FID L 16 1466
SNT VIA
FID H 0 1195
FID C 4 3818
FID C 6 2966
FID C 3 8196
FID C 8 6190
FID L 11 1467
FID L 12 1467
FID L 13 2244
FID L 14 2243
FID L 15 1467
FID L 16 1467
SNT TRC
FID C 9 2598
FID C 9 2599
FID C 9 2600
FID C 9 2601
FID C 9 2602
FID C 9 2603
SNT TRC
FID C 8 6177
FID C 8 6178
FID C 8 6179
FID C 8 6180
FID C 8 6181
SNT TRC
FID C 3 8186
FID C 3 8187
FID C 3 8188
FID C 3 8189
FID C 3 8190
FID C 3 8191
FID C 3 8192
FID C 3 8193
FID C 3 8194
SNT TRC
FID C 8 6182
FID C 8 6183
FID C 8 6184
FID C 8 6185
FID C 8 6186
FID C 8 6187
FID C 8 6188
SNT TRC
FID C 3 8197
FID C 3 8198
# NET 290
NET R_PCA9546_I2C_SCL 
SNT TOP T 387 1
FID C 4 1887
FID C 5 1125
FID C 3 4679
SNT TOP T 604 13
FID C 4 1886
FID C 5 1124
FID C 3 4678
SNT TOP B 184 1
FID C 6 1286
FID C 7 446
FID C 8 3372
SNT TOP B 185 1
FID C 6 1287
FID C 7 447
FID C 8 3373
SNT TOP B 186 1
FID C 6 1285
FID C 7 445
FID C 8 3369
SNT TOP B 211 1
FID C 6 1288
FID C 7 448
FID C 8 3376
SNT VIA
FID H 0 1432
FID C 4 1885
FID C 6 1283
FID C 3 4675
FID C 10 2760
FID C 8 3363
FID L 11 1106
FID L 12 1106
FID L 13 959
FID L 14 909
FID L 15 1106
FID L 16 1106
SNT VIA
FID H 0 2256
FID C 4 1888
FID C 6 1284
FID C 3 4680
FID C 10 2761
FID C 8 3368
FID L 11 1107
FID L 12 1107
FID L 13 960
FID L 14 910
FID L 15 1107
FID L 16 1107
SNT TRC
FID C 10 2736
FID C 10 2737
FID C 10 2738
FID C 10 2739
FID C 10 2740
FID C 10 2741
FID C 10 2742
FID C 10 2743
FID C 10 2744
FID C 10 2745
FID C 10 2746
FID C 10 2747
FID C 10 2748
FID C 10 2749
FID C 10 2750
FID C 10 2751
FID C 10 2752
FID C 10 2753
FID C 10 2754
FID C 10 2755
FID C 10 2756
FID C 10 2757
FID C 10 2758
FID C 10 2759
SNT TRC
FID C 3 4671
FID C 3 4672
FID C 3 4673
FID C 3 4674
SNT TRC
FID C 3 4676
FID C 3 4677
SNT TRC
FID C 8 3364
SNT TRC
FID C 8 3365
FID C 8 3366
FID C 8 3367
SNT TRC
FID C 8 3370
FID C 8 3371
SNT TRC
FID C 8 3374
FID C 8 3375
# NET 291
NET PCA9546_RST_N 
SNT TOP T 43 0
FID H 0 144
FID C 6 20
FID C 3 121
FID C 8 36
FID L 11 19
FID L 12 19
FID L 13 19
FID L 14 19
FID L 15 19
FID L 16 19
SNT TOP T 604 2
FID C 4 39
FID C 5 26
FID C 3 120
SNT TOP B 266 1
FID C 6 23
FID C 7 8
FID C 8 41
SNT TOP B 268 1
FID C 6 21
FID C 7 6
FID C 8 38
SNT TOP B 271 1
FID C 6 22
FID C 7 7
FID C 8 39
SNT VIA
FID H 0 2164
FID C 4 38
FID C 6 19
FID C 3 119
FID C 8 33
FID L 11 18
FID L 12 18
FID L 13 18
FID L 14 18
FID L 15 18
FID L 16 18
SNT TRC
FID C 8 31
FID C 8 32
SNT TRC
FID C 3 116
FID C 3 117
FID C 3 118
SNT TRC
FID C 8 34
FID C 8 35
SNT TRC
FID C 8 37
SNT TRC
FID C 8 40
# NET 292
NET UNNAMED_5_PCA9546APWTSSOP16_I33 
SNT TOP T 604 0
FID C 4 2374
FID C 5 1382
FID C 3 5802
SNT TOP B 265 1
FID C 6 1693
FID C 7 609
FID C 8 4207
SNT TOP B 267 1
FID C 6 1692
FID C 7 608
FID C 8 4205
SNT VIA
FID H 0 2182
FID C 4 2373
FID C 6 1691
FID C 3 5799
FID C 8 4203
FID L 11 1369
FID L 12 1369
FID L 13 1137
FID L 14 1136
FID L 15 1369
FID L 16 1369
SNT TRC
FID C 3 5800
FID C 3 5801
SNT TRC
FID C 8 4204
SNT TRC
FID C 8 4206
# NET 293
NET XP12R0V_A_FLTB 
SNT TOP T 27 0
FID H 0 161
FID C 6 1454
FID C 3 5347
FID C 8 3783
FID L 11 1229
FID L 12 1229
FID L 13 1071
FID L 14 1021
FID L 15 1229
FID L 16 1229
SNT TOP T 189 8
FID C 4 2119
FID C 5 1271
FID C 3 5344
SNT TOP T 332 1
FID C 4 2120
FID C 5 1272
FID C 3 5353
SNT TOP B 350 0
FID C 6 1455
FID C 7 522
FID C 8 3784
SNT TRC
FID C 8 3781
FID C 8 3782
SNT TRC
FID C 3 5345
FID C 3 5346
SNT TRC
FID C 3 5348
FID C 3 5349
FID C 3 5350
FID C 3 5351
FID C 3 5352
# NET 294
NET UNNAMED_5_PCA9546APWTSSOP16_I_1 
SNT TOP T 604 1
FID C 4 2372
FID C 5 1381
FID C 3 5798
SNT TOP B 269 1
FID C 6 1688
FID C 7 606
FID C 8 4197
SNT TOP B 270 1
FID C 6 1689
FID C 7 607
FID C 8 4201
SNT VIA
FID H 0 2183
FID C 4 2371
FID C 6 1690
FID C 3 5795
FID C 8 4202
FID L 11 1368
FID L 12 1368
FID L 13 1136
FID L 14 1135
FID L 15 1368
FID L 16 1368
SNT TRC
FID C 8 4198
SNT TRC
FID C 8 4199
FID C 8 4200
SNT TRC
FID C 3 5796
FID C 3 5797
# NET 295
NET UNNAMED_5_PCA9546APWTSSOP16_I_2 
SNT TOP T 604 12
FID C 4 2370
FID C 5 1380
FID C 3 5794
SNT TOP B 272 1
FID C 6 1686
FID C 7 604
FID C 8 4194
SNT TOP B 273 1
FID C 6 1687
FID C 7 605
FID C 8 4196
SNT VIA
FID H 0 2184
FID C 4 2369
FID C 6 1685
FID C 3 5793
FID C 8 4193
FID L 11 1367
FID L 12 1367
FID L 13 1135
FID L 14 1134
FID L 15 1367
FID L 16 1367
SNT TRC
FID C 3 5790
FID C 3 5791
FID C 3 5792
SNT TRC
FID C 8 4191
FID C 8 4192
SNT TRC
FID C 8 4195
# NET 296
NET ANT3_OUT 
SNT TOP T 170 450
FID C 4 1017
FID C 5 616
FID C 3 2700
SNT TOP T 277 0
FID C 4 1015
FID C 5 615
FID C 3 2696
SNT VIA
FID H 0 199
FID C 4 1018
FID C 6 620
FID C 3 2701
FID C 9 1307
FID C 10 1559
FID C 8 1827
FID L 11 610
FID L 12 610
FID L 13 594
FID L 14 559
FID L 15 610
FID L 16 610
SNT VIA
FID H 0 1088
FID C 4 1016
FID C 6 619
FID C 3 2697
FID C 10 1558
FID C 8 1825
FID L 11 608
FID L 12 608
FID L 13 592
FID L 14 557
FID L 15 608
FID L 16 608
SNT VIA
FID H 0 2343
FID C 3 2698
FID C 9 1306
FID C 8 1826
FID L 11 609
FID L 12 609
FID L 13 593
FID L 14 558
FID L 15 609
FID L 16 609
SNT TRC
FID C 9 1257
FID C 9 1258
FID C 9 1259
FID C 9 1260
FID C 9 1261
FID C 9 1262
FID C 9 1263
FID C 9 1264
FID C 9 1265
FID C 9 1266
FID C 9 1267
FID C 9 1268
FID C 9 1269
FID C 9 1270
FID C 9 1271
FID C 9 1272
FID C 9 1273
FID C 9 1274
FID C 9 1275
FID C 9 1276
FID C 9 1277
FID C 9 1278
FID C 9 1279
FID C 9 1280
FID C 9 1281
FID C 9 1282
FID C 9 1283
FID C 9 1284
FID C 9 1285
FID C 9 1286
FID C 9 1287
FID C 9 1288
FID C 9 1289
FID C 9 1290
FID C 9 1291
FID C 9 1292
FID C 9 1293
FID C 9 1294
FID C 9 1295
FID C 9 1296
FID C 9 1297
FID C 9 1298
FID C 9 1299
FID C 9 1300
FID C 9 1301
FID C 9 1302
FID C 9 1303
FID C 9 1304
FID C 9 1305
SNT TRC
FID C 10 1547
FID C 10 1548
FID C 10 1549
FID C 10 1550
FID C 10 1551
FID C 10 1552
FID C 10 1553
FID C 10 1554
FID C 10 1555
FID C 10 1556
FID C 10 1557
SNT TRC
FID C 3 2694
FID C 3 2695
SNT TRC
FID C 3 2699
# NET 297
NET UNNAMED_12_74HCT2G125DPTSSOP8_I 
SNT TOP T 127 1
FID C 4 2232
FID C 5 1329
FID C 3 5524
SNT TOP T 277 1
FID C 4 2230
FID C 5 1328
FID C 3 5522
SNT TOP B 124 1
FID C 6 1537
FID C 7 545
FID C 8 3913
SNT VIA
FID H 0 1267
FID C 4 2231
FID C 6 1538
FID C 3 5523
FID C 8 3914
FID L 11 1286
FID L 12 1286
FID L 13 1097
FID L 14 1067
FID L 15 1286
FID L 16 1286
SNT TRC
FID C 8 3911
FID C 8 3912
SNT TRC
FID C 3 5517
FID C 3 5518
SNT TRC
FID C 3 5519
FID C 3 5520
FID C 3 5521
# NET 298
NET ANT4_OUT 
SNT TOP T 170 451
FID C 4 1006
FID C 5 611
FID C 3 2674
SNT TOP T 278 0
FID C 4 1010
FID C 5 612
FID C 3 2682
SNT VIA
FID H 0 201
FID C 4 1008
FID C 6 614
FID C 3 2678
FID C 9 1213
FID C 8 1817
FID L 11 603
FID L 12 603
FID L 13 587
FID L 14 552
FID L 15 603
FID L 16 603
SNT VIA
FID H 0 202
FID C 4 1005
FID C 6 612
FID C 3 2673
FID C 9 1210
FID C 8 1814
FID L 11 600
FID L 12 600
FID L 13 584
FID L 14 549
FID L 15 600
FID L 16 600
SNT VIA
FID H 0 203
FID C 4 1007
FID C 6 613
FID C 3 2677
FID C 9 1212
FID C 8 1816
FID L 11 602
FID L 12 602
FID L 13 586
FID L 14 551
FID L 15 602
FID L 16 602
SNT VIA
FID H 0 2150
FID C 4 1009
FID C 6 615
FID C 3 2679
FID C 8 1818
FID L 11 604
FID L 12 604
FID L 13 588
FID L 14 553
FID L 15 604
FID L 16 604
SNT VIA
FID H 0 2345
FID C 3 2676
FID C 9 1211
FID C 8 1815
FID L 11 601
FID L 12 601
FID L 13 585
FID L 14 550
FID L 15 601
FID L 16 601
SNT TRC
FID C 9 1173
FID C 9 1174
FID C 9 1175
FID C 9 1176
FID C 9 1177
FID C 9 1178
FID C 9 1179
FID C 9 1180
FID C 9 1181
FID C 9 1182
FID C 9 1183
FID C 9 1184
FID C 9 1185
FID C 9 1186
FID C 9 1187
FID C 9 1188
FID C 9 1189
FID C 9 1190
FID C 9 1191
FID C 9 1192
SNT TRC
FID C 9 1193
FID C 9 1194
FID C 9 1195
FID C 9 1196
FID C 9 1197
FID C 9 1198
FID C 9 1199
FID C 9 1200
FID C 9 1201
FID C 9 1202
FID C 9 1203
FID C 9 1204
FID C 9 1205
FID C 9 1206
FID C 9 1207
FID C 9 1208
FID C 9 1209
SNT TRC
FID C 8 1806
FID C 8 1807
FID C 8 1808
FID C 8 1809
FID C 8 1810
FID C 8 1811
FID C 8 1812
FID C 8 1813
SNT TRC
FID C 3 2669
FID C 3 2670
FID C 3 2671
FID C 3 2672
SNT TRC
FID C 3 2675
SNT TRC
FID C 3 2680
FID C 3 2681
# NET 299
NET UNNAMED_12_74HCT2G125DPTSSOP8_3 
SNT TOP T 128 1
FID C 4 2234
FID C 5 1331
FID C 3 5530
SNT TOP T 278 1
FID C 4 2233
FID C 5 1330
FID C 3 5529
SNT TOP B 125 1
FID C 6 1539
FID C 7 546
FID C 8 3917
SNT VIA
FID H 0 1264
FID C 4 2235
FID C 6 1540
FID C 3 5531
FID C 8 3918
FID L 11 1287
FID L 12 1287
FID L 13 1098
FID L 14 1068
FID L 15 1287
FID L 16 1287
SNT TRC
FID C 3 5525
FID C 3 5526
SNT TRC
FID C 3 5527
FID C 3 5528
SNT TRC
FID C 8 3915
FID C 8 3916
# NET 300
NET UNNAMED_5_24LC16BTISTTSSOP8_I15 
SNT TOP T 7 0
FID C 4 333
FID C 5 231
FID C 3 791
SNT TOP B 311 0
FID C 6 171
FID C 7 54
FID C 8 427
SNT TOP B 315 1
FID C 6 172
FID C 7 55
FID C 8 428
SNT VIA
FID H 0 1325
FID C 4 334
FID C 6 170
FID C 3 792
FID C 8 426
FID L 11 257
FID L 12 257
FID L 13 241
FID L 14 206
FID L 15 257
FID L 16 257
SNT TRC
FID C 8 414
FID C 8 415
FID C 8 416
FID C 8 417
FID C 8 418
FID C 8 419
FID C 8 420
FID C 8 421
FID C 8 422
SNT TRC
FID C 3 788
FID C 3 789
FID C 3 790
SNT TRC
FID C 8 423
FID C 8 424
FID C 8 425
# NET 301
NET UNNAMED_5_24LC16BTISTTSSOP8_I_1 
SNT TOP T 7 1
FID C 4 332
FID C 5 230
FID C 3 787
SNT TOP B 178 0
FID C 6 168
FID C 7 52
FID C 8 411
SNT TOP B 325 1
FID C 6 169
FID C 7 53
FID C 8 413
SNT VIA
FID H 0 1326
FID C 4 331
FID C 6 167
FID C 3 786
FID C 8 410
FID L 11 256
FID L 12 256
FID L 13 240
FID L 14 205
FID L 15 256
FID L 16 256
SNT TRC
FID C 8 408
FID C 8 409
SNT TRC
FID C 3 782
FID C 3 783
FID C 3 784
FID C 3 785
SNT TRC
FID C 8 412
# NET 302
NET UNNAMED_5_24LC16BTISTTSSOP8_I_2 
SNT TOP T 7 2
FID C 4 330
FID C 5 229
FID C 3 781
SNT TOP B 179 0
FID C 6 164
FID C 7 50
FID C 8 405
SNT TOP B 329 1
FID C 6 165
FID C 7 51
FID C 8 406
SNT VIA
FID H 0 1327
FID C 4 329
FID C 6 166
FID C 3 780
FID C 8 407
FID L 11 255
FID L 12 255
FID L 13 239
FID L 14 204
FID L 15 255
FID L 16 255
SNT TRC
FID C 8 402
FID C 8 403
SNT TRC
FID C 3 777
FID C 3 778
FID C 3 779
SNT TRC
FID C 8 404
# NET 303
NET FPGA_IN_RST_DLY_N 
SNT TOP T 170 239
FID C 4 31
FID C 5 20
FID C 3 99
SNT TOP T 218 1
FID C 4 34
FID C 5 22
FID C 3 104
SNT TOP T 598 0
FID C 4 33
FID C 5 21
FID C 3 101
SNT VIA
FID H 0 1130
FID C 4 32
FID C 6 15
FID C 3 100
FID C 10 29
FID C 8 22
FID L 11 15
FID L 12 15
FID L 13 15
FID L 14 15
FID L 15 15
FID L 16 15
SNT VIA
FID H 0 2112
FID C 3 97
FID C 10 28
FID C 8 21
FID L 11 14
FID L 12 14
FID L 13 14
FID L 14 14
FID L 15 14
FID L 16 14
SNT TRC
FID C 10 20
FID C 10 21
FID C 10 22
FID C 10 23
FID C 10 24
FID C 10 25
FID C 10 26
FID C 10 27
SNT TRC
FID C 3 95
FID C 3 96
SNT TRC
FID C 3 98
SNT TRC
FID C 3 102
FID C 3 103
# NET 304
NET FPGA_IO_0 
SNT TOP T 170 241
FID C 4 643
FID C 5 397
FID C 3 1720
SNT TOP T 405 1
FID C 4 644
FID C 5 398
FID C 3 1721
SNT TOP B 142 1
FID C 6 400
FID C 7 131
FID C 8 1126
SNT TOP B 307 1
FID C 6 404
FID C 7 132
FID C 8 1133
SNT VIA
FID H 0 233
FID C 4 645
FID C 6 403
FID C 3 1723
FID C 8 1132
FID L 11 423
FID L 12 423
FID L 13 407
FID L 14 372
FID L 15 423
FID L 16 423
SNT VIA
FID H 0 234
FID C 4 642
FID C 6 402
FID C 3 1713
FID C 10 529
FID C 8 1130
FID L 11 422
FID L 12 422
FID L 13 406
FID L 14 371
FID L 15 422
FID L 16 422
SNT VIA
FID H 0 1132
FID C 4 641
FID C 6 401
FID C 3 1712
FID C 10 528
FID C 8 1129
FID L 11 421
FID L 12 421
FID L 13 405
FID L 14 370
FID L 15 421
FID L 16 421
SNT TRC
FID C 10 516
FID C 10 517
FID C 10 518
FID C 10 519
FID C 10 520
FID C 10 521
FID C 10 522
FID C 10 523
FID C 10 524
FID C 10 525
FID C 10 526
FID C 10 527
SNT TRC
FID C 8 1103
FID C 8 1104
FID C 8 1105
FID C 8 1106
FID C 8 1107
FID C 8 1108
FID C 8 1109
FID C 8 1110
FID C 8 1111
FID C 8 1112
FID C 8 1113
FID C 8 1114
FID C 8 1115
FID C 8 1116
FID C 8 1117
FID C 8 1118
FID C 8 1119
FID C 8 1120
FID C 8 1121
FID C 8 1122
FID C 8 1123
FID C 8 1124
FID C 8 1125
SNT TRC
FID C 8 1127
FID C 8 1128
SNT TRC
FID C 3 1714
FID C 3 1715
FID C 3 1716
FID C 3 1717
FID C 3 1718
FID C 3 1719
SNT TRC
FID C 3 1722
SNT TRC
FID C 8 1131
# NET 305
NET FPGA_IO_1 
SNT TOP T 170 219
FID C 4 640
FID C 5 396
FID C 3 1711
SNT TOP T 406 1
FID C 4 638
FID C 5 395
FID C 3 1708
SNT TOP B 143 1
FID C 6 396
FID C 7 129
FID C 8 1096
SNT TOP B 180 1
FID C 6 399
FID C 7 130
FID C 8 1102
SNT VIA
FID H 0 235
FID C 4 639
FID C 6 398
FID C 3 1710
FID C 8 1101
FID L 11 420
FID L 12 420
FID L 13 404
FID L 14 369
FID L 15 420
FID L 16 420
SNT VIA
FID H 0 236
FID C 4 637
FID C 6 397
FID C 3 1701
FID C 10 515
FID C 8 1099
FID L 11 419
FID L 12 419
FID L 13 403
FID L 14 368
FID L 15 419
FID L 16 419
SNT VIA
FID H 0 1133
FID C 4 636
FID C 6 395
FID C 3 1700
FID C 10 514
FID C 8 1095
FID L 11 418
FID L 12 418
FID L 13 402
FID L 14 367
FID L 15 418
FID L 16 418
SNT TRC
FID C 10 505
FID C 10 506
FID C 10 507
FID C 10 508
FID C 10 509
FID C 10 510
FID C 10 511
FID C 10 512
FID C 10 513
SNT TRC
FID C 8 1078
FID C 8 1079
FID C 8 1080
FID C 8 1081
FID C 8 1082
FID C 8 1083
FID C 8 1084
FID C 8 1085
FID C 8 1086
FID C 8 1087
FID C 8 1088
FID C 8 1089
FID C 8 1090
FID C 8 1091
FID C 8 1092
FID C 8 1093
FID C 8 1094
SNT TRC
FID C 8 1097
FID C 8 1098
SNT TRC
FID C 3 1702
FID C 3 1703
FID C 3 1704
FID C 3 1705
FID C 3 1706
FID C 3 1707
SNT TRC
FID C 3 1709
SNT TRC
FID C 8 1100
# NET 306
NET PCIE_SMDAT 
SNT TOP T 183 6
FID C 4 1894
FID C 5 1128
FID C 3 4703
SNT TOP B 198 0
FID C 6 1295
FID C 7 452
FID C 8 3403
SNT TOP B 208 0
FID C 6 1297
FID C 7 453
FID C 8 3405
SNT VIA
FID H 0 339
FID C 4 1893
FID C 6 1296
FID C 3 4702
FID C 10 2780
FID C 8 3404
FID L 11 1112
FID L 12 1112
FID L 13 965
FID L 14 915
FID L 15 1112
FID L 16 1112
SNT VIA
FID H 0 1199
FID C 4 1892
FID C 6 1294
FID C 3 4701
FID C 10 2779
FID C 8 3402
FID L 11 1111
FID L 12 1111
FID L 13 964
FID L 14 914
FID L 15 1111
FID L 16 1111
SNT TRC
FID C 3 4688
FID C 3 4689
FID C 3 4690
FID C 3 4691
FID C 3 4692
FID C 3 4693
FID C 3 4694
FID C 3 4695
FID C 3 4696
FID C 3 4697
FID C 3 4698
FID C 3 4699
FID C 3 4700
SNT TRC
FID C 8 3392
FID C 8 3393
FID C 8 3394
FID C 8 3395
FID C 8 3396
FID C 8 3397
SNT TRC
FID C 8 3398
FID C 8 3399
FID C 8 3400
FID C 8 3401
SNT TRC
FID C 10 2772
FID C 10 2773
FID C 10 2774
FID C 10 2775
FID C 10 2776
FID C 10 2777
FID C 10 2778
# NET 307
NET PCIE_SMCLK 
SNT TOP T 183 1
FID C 4 1896
FID C 5 1129
FID C 3 4712
SNT TOP B 186 0
FID C 6 1302
FID C 7 455
FID C 8 3430
SNT TOP B 197 0
FID C 6 1300
FID C 7 454
FID C 8 3428
SNT VIA
FID H 0 338
FID C 4 1898
FID C 6 1301
FID C 3 4714
FID C 10 2790
FID C 8 3429
FID L 11 1115
FID L 12 1115
FID L 13 968
FID L 14 918
FID L 15 1115
FID L 16 1115
SNT VIA
FID H 0 1420
FID C 4 1897
FID C 6 1299
FID C 3 4713
FID C 10 2789
FID C 8 3427
FID L 11 1114
FID L 12 1114
FID L 13 967
FID L 14 917
FID L 15 1114
FID L 16 1114
SNT VIA
FID H 0 2250
FID C 4 1895
FID C 6 1298
FID C 3 4704
FID C 8 3406
FID L 11 1113
FID L 12 1113
FID L 13 966
FID L 14 916
FID L 15 1113
FID L 16 1113
SNT TRC
FID C 3 4705
FID C 3 4706
SNT TRC
FID C 3 4707
FID C 3 4708
FID C 3 4709
FID C 3 4710
FID C 3 4711
SNT TRC
FID C 8 3407
FID C 8 3408
FID C 8 3409
FID C 8 3410
FID C 8 3411
FID C 8 3412
FID C 8 3413
FID C 8 3414
FID C 8 3415
FID C 8 3416
FID C 8 3417
FID C 8 3418
FID C 8 3419
FID C 8 3420
FID C 8 3421
FID C 8 3422
SNT TRC
FID C 8 3423
FID C 8 3424
FID C 8 3425
FID C 8 3426
SNT TRC
FID C 10 2781
FID C 10 2782
FID C 10 2783
FID C 10 2784
FID C 10 2785
FID C 10 2786
FID C 10 2787
FID C 10 2788
# NET 308
NET EEPROM_I2C_SDA 
SNT TOP T 4 8
FID C 4 3908
FID C 5 1864
FID C 3 8501
SNT TOP T 329 0
FID C 4 3911
FID C 5 1865
FID C 3 8504
SNT VIA
FID H 0 208
FID C 4 3907
FID C 6 3044
FID C 3 8488
FID C 9 2927
FID C 10 3757
FID C 8 6419
FID L 11 1528
FID L 12 1528
FID L 13 2305
FID L 14 2304
FID L 15 1528
FID L 16 1528
SNT VIA
FID H 0 209
FID C 4 3910
FID C 6 3046
FID C 3 8503
FID C 10 3764
FID C 8 6421
FID L 11 1530
FID L 12 1530
FID L 13 2307
FID L 14 2306
FID L 15 1530
FID L 16 1530
SNT VIA
FID H 0 2226
FID C 4 3909
FID C 6 3045
FID C 3 8502
FID C 9 2947
FID C 8 6420
FID L 11 1529
FID L 12 1529
FID L 13 2306
FID L 14 2305
FID L 15 1529
FID L 16 1529
SNT TRC
FID C 10 3758
FID C 10 3759
FID C 10 3760
FID C 10 3761
FID C 10 3762
FID C 10 3763
SNT TRC
FID C 3 8489
FID C 3 8490
FID C 3 8491
FID C 3 8492
FID C 3 8493
FID C 3 8494
FID C 3 8495
FID C 3 8496
SNT TRC
FID C 9 2928
FID C 9 2929
FID C 9 2930
FID C 9 2931
FID C 9 2932
FID C 9 2933
FID C 9 2934
FID C 9 2935
FID C 9 2936
FID C 9 2937
FID C 9 2938
FID C 9 2939
FID C 9 2940
FID C 9 2941
FID C 9 2942
FID C 9 2943
FID C 9 2944
FID C 9 2945
FID C 9 2946
SNT TRC
FID C 3 8497
FID C 3 8498
FID C 3 8499
FID C 3 8500
# NET 309
NET EEPROM_I2C_SCL 
SNT TOP T 4 11
FID C 4 3913
FID C 5 1866
FID C 3 8515
SNT TOP T 328 0
FID C 4 3916
FID C 5 1867
FID C 3 8518
SNT VIA
FID H 0 206
FID C 4 3912
FID C 6 3047
FID C 3 8505
FID C 9 2948
FID C 10 3765
FID C 8 6422
FID L 11 1531
FID L 12 1531
FID L 13 2308
FID L 14 2307
FID L 15 1531
FID L 16 1531
SNT VIA
FID H 0 207
FID C 4 3914
FID C 6 3048
FID C 3 8516
FID C 10 3771
FID C 8 6423
FID L 11 1532
FID L 12 1532
FID L 13 2309
FID L 14 2308
FID L 15 1532
FID L 16 1532
SNT VIA
FID H 0 2225
FID C 4 3915
FID C 6 3049
FID C 3 8517
FID C 9 2966
FID C 8 6424
FID L 11 1533
FID L 12 1533
FID L 13 2310
FID L 14 2309
FID L 15 1533
FID L 16 1533
SNT TRC
FID C 10 3766
FID C 10 3767
FID C 10 3768
FID C 10 3769
FID C 10 3770
SNT TRC
FID C 9 2949
FID C 9 2950
FID C 9 2951
FID C 9 2952
FID C 9 2953
FID C 9 2954
FID C 9 2955
FID C 9 2956
FID C 9 2957
FID C 9 2958
FID C 9 2959
FID C 9 2960
FID C 9 2961
FID C 9 2962
FID C 9 2963
FID C 9 2964
FID C 9 2965
SNT TRC
FID C 3 8506
FID C 3 8507
FID C 3 8508
FID C 3 8509
FID C 3 8510
FID C 3 8511
SNT TRC
FID C 3 8512
FID C 3 8513
FID C 3 8514
# NET 310
NET XP1R2V_FB 
SNT TOP T 118 2
FID C 4 1699
FID C 5 1002
FID C 3 4294
SNT TOP T 190 1
FID C 4 1701
FID C 5 1004
FID C 3 4296
SNT TOP T 259 1
FID C 4 1697
FID C 5 1001
FID C 3 4287
SNT TOP T 430 1
FID C 4 1700
FID C 5 1003
FID C 3 4295
SNT VIA
FID H 0 1370
FID C 4 1698
FID C 6 1125
FID C 3 4293
FID C 8 3010
FID L 11 1014
FID L 12 1014
FID L 13 907
FID L 14 817
FID L 15 1014
FID L 16 1014
SNT TRC
FID C 3 4288
SNT TRC
FID C 3 4289
SNT TRC
FID C 3 4290
SNT TRC
FID C 3 4291
FID C 3 4292
# NET 311
NET XP1R8V_FB 
SNT TOP T 116 2
FID C 4 1659
FID C 5 976
FID C 3 4206
SNT TOP T 191 1
FID C 4 1661
FID C 5 978
FID C 3 4211
SNT TOP T 432 1
FID C 4 1660
FID C 5 977
FID C 3 4209
SNT TOP B 111 1
FID C 6 1105
FID C 7 353
FID C 8 2985
SNT VIA
FID H 0 2295
FID C 4 1662
FID C 6 1104
FID C 3 4212
FID C 8 2984
FID L 11 999
FID L 12 999
FID L 13 901
FID L 14 802
FID L 15 999
FID L 16 999
SNT TRC
FID C 3 4207
SNT TRC
FID C 3 4208
SNT TRC
FID C 3 4210
SNT TRC
FID C 8 2986
# NET 312
NET FLASH_CS_N 
SNT TOP T 5 11
FID C 4 692
FID C 5 425
FID C 3 1875
SNT TOP T 168 0
FID C 4 694
FID C 5 426
FID C 3 1878
SNT TOP B 282 1
FID C 6 430
FID C 7 138
FID C 8 1215
SNT VIA
FID H 0 215
FID C 4 691
FID C 6 429
FID C 3 1874
FID C 8 1214
FID L 11 443
FID L 12 443
FID L 13 427
FID L 14 392
FID L 15 443
FID L 16 443
SNT VIA
FID H 0 1106
FID C 4 693
FID C 6 431
FID C 3 1876
FID C 8 1217
FID L 11 444
FID L 12 444
FID L 13 428
FID L 14 393
FID L 15 444
FID L 16 444
SNT TRC
FID C 8 1184
FID C 8 1185
FID C 8 1186
FID C 8 1187
FID C 8 1188
FID C 8 1189
FID C 8 1190
FID C 8 1191
FID C 8 1192
FID C 8 1193
FID C 8 1194
FID C 8 1195
FID C 8 1196
FID C 8 1197
FID C 8 1198
FID C 8 1199
FID C 8 1200
FID C 8 1201
FID C 8 1202
FID C 8 1203
FID C 8 1204
FID C 8 1205
FID C 8 1206
FID C 8 1207
FID C 8 1208
FID C 8 1209
FID C 8 1210
FID C 8 1211
FID C 8 1212
FID C 8 1213
SNT TRC
FID C 3 1873
SNT TRC
FID C 8 1216
SNT TRC
FID C 3 1877
# NET 313
NET FLASH_CLK 
SNT TOP T 5 3
FID C 4 696
FID C 5 427
FID C 3 1883
SNT TOP T 168 5
FID C 4 698
FID C 5 428
FID C 3 1886
SNT TOP B 286 0
FID C 6 433
FID C 7 139
FID C 8 1221
SNT VIA
FID H 0 214
FID C 4 695
FID C 6 432
FID C 3 1882
FID C 9 981
FID C 8 1218
FID L 11 445
FID L 12 445
FID L 13 429
FID L 14 394
FID L 15 445
FID L 16 445
SNT VIA
FID H 0 2154
FID C 4 697
FID C 6 434
FID C 3 1884
FID C 9 982
FID C 8 1222
FID L 11 446
FID L 12 446
FID L 13 430
FID L 14 395
FID L 15 446
FID L 16 446
SNT TRC
FID C 9 967
FID C 9 968
FID C 9 969
FID C 9 970
FID C 9 971
FID C 9 972
FID C 9 973
FID C 9 974
FID C 9 975
FID C 9 976
FID C 9 977
FID C 9 978
FID C 9 979
FID C 9 980
SNT TRC
FID C 3 1879
FID C 3 1880
FID C 3 1881
SNT TRC
FID C 8 1219
FID C 8 1220
SNT TRC
FID C 3 1885
# NET 314
NET FPGA_PROGRAM_N 
SNT TOP T 19 0
FID H 0 170
FID C 6 1319
FID C 3 4835
FID C 10 2953
FID C 8 3490
FID L 11 1128
FID L 12 1128
FID L 13 981
FID L 14 931
FID L 15 1128
FID L 16 1128
SNT TOP T 170 319
FID C 4 1931
FID C 5 1156
FID C 3 4840
SNT TOP T 266 1
FID C 4 1930
FID C 5 1155
FID C 3 4837
SNT TOP T 360 1
FID C 4 1929
FID C 5 1154
FID C 3 4836
SNT VIA
FID H 0 2138
FID C 3 4838
FID C 10 2954
FID C 8 3491
FID L 11 1129
FID L 12 1129
FID L 13 982
FID L 14 932
FID L 15 1129
FID L 16 1129
SNT TRC
FID C 10 2931
FID C 10 2932
FID C 10 2933
FID C 10 2934
FID C 10 2935
FID C 10 2936
FID C 10 2937
FID C 10 2938
FID C 10 2939
FID C 10 2940
FID C 10 2941
FID C 10 2942
FID C 10 2943
FID C 10 2944
FID C 10 2945
FID C 10 2946
FID C 10 2947
FID C 10 2948
FID C 10 2949
FID C 10 2950
FID C 10 2951
FID C 10 2952
SNT TRC
FID C 3 4832
FID C 3 4833
SNT TRC
FID C 3 4834
SNT TRC
FID C 3 4839
# NET 315
NET CFGBVS 
SNT TOP T 170 403
FID C 4 1992
FID C 5 1197
FID C 3 5082
SNT TOP T 371 1
FID C 4 1994
FID C 5 1198
FID C 3 5085
SNT VIA
FID H 0 2223
FID C 4 1993
FID C 6 1368
FID C 3 5084
FID C 9 2220
FID C 8 3615
FID L 11 1172
FID L 12 1172
FID L 13 1025
FID L 14 964
FID L 15 1172
FID L 16 1172
SNT VIA
FID H 0 2346
FID C 3 5081
FID C 9 2219
FID C 8 3614
FID L 11 1171
FID L 12 1171
FID L 13 1024
FID L 14 963
FID L 15 1171
FID L 16 1171
SNT TRC
FID C 3 5080
SNT TRC
FID C 9 2208
FID C 9 2209
FID C 9 2210
FID C 9 2211
FID C 9 2212
FID C 9 2213
FID C 9 2214
FID C 9 2215
FID C 9 2216
FID C 9 2217
FID C 9 2218
SNT TRC
FID C 3 5083
# NET 316
NET R_FPGA_TDO 
SNT TOP T 170 408
FID C 4 1890
FID C 5 1126
FID C 3 4683
SNT TOP B 227 1
FID C 6 1290
FID C 7 449
FID C 8 3381
SNT VIA
FID H 0 1204
FID C 4 1889
FID C 6 1289
FID C 3 4682
FID C 10 2771
FID C 8 3378
FID L 11 1109
FID L 12 1109
FID L 13 962
FID L 14 912
FID L 15 1109
FID L 16 1109
SNT VIA
FID H 0 2387
FID C 3 4681
FID C 10 2770
FID C 8 3377
FID L 11 1108
FID L 12 1108
FID L 13 961
FID L 14 911
FID L 15 1108
FID L 16 1108
SNT TRC
FID C 10 2762
FID C 10 2763
FID C 10 2764
FID C 10 2765
FID C 10 2766
FID C 10 2767
FID C 10 2768
FID C 10 2769
SNT TRC
FID C 8 3379
FID C 8 3380
SNT TRC
FID C 3 4684
# NET 317
NET FPGA_MGTRREF 
SNT TOP T 170 161
FID C 4 51
FID C 5 38
FID C 3 166
SNT TOP B 9 0
FID H 0 172
FID C 6 34
FID C 3 164
FID C 9 18
FID C 8 62
FID L 11 23
FID L 12 23
FID L 13 23
FID L 14 23
FID L 15 23
FID L 16 23
SNT TOP B 123 1
FID C 6 33
FID C 7 15
FID C 8 60
SNT VIA
FID H 0 2362
FID C 3 167
FID C 9 19
FID C 8 63
FID L 11 24
FID L 12 24
FID L 13 24
FID L 14 24
FID L 15 24
FID L 16 24
SNT TRC
FID C 9 8
FID C 9 9
FID C 9 10
FID C 9 11
FID C 9 12
FID C 9 13
FID C 9 14
FID C 9 15
FID C 9 16
FID C 9 17
SNT TRC
FID C 8 61
SNT TRC
FID C 3 165
# NET 318
NET UNNAMED_127_MT25QL128ABA1ESESOP 
SNT TOP T 168 4
FID C 4 1867
FID C 5 1113
FID C 3 4625
SNT TOP B 285 0
FID C 6 1263
FID C 7 433
FID C 8 3315
SNT TOP B 287 0
FID C 6 1264
FID C 7 434
FID C 8 3319
SNT VIA
FID H 0 2174
FID C 4 1866
FID C 6 1262
FID C 3 4623
FID C 8 3314
FID L 11 1096
FID L 12 1096
FID L 13 949
FID L 14 899
FID L 15 1096
FID L 16 1096
SNT TRC
FID C 8 3316
SNT TRC
FID C 8 3317
FID C 8 3318
SNT TRC
FID C 3 4624
# NET 319
NET FPGA_OUT_SEC_EEPROM_WP 
SNT TOP T 170 56
FID C 4 588
FID C 5 374
FID C 3 1573
SNT TOP B 196 0
FID C 6 354
FID C 7 116
FID C 8 913
SNT VIA
FID H 0 1152
FID C 4 587
FID C 6 353
FID C 3 1570
FID C 9 763
FID C 8 912
FID L 11 382
FID L 12 382
FID L 13 366
FID L 14 331
FID L 15 382
FID L 16 382
SNT VIA
FID H 0 2124
FID C 3 1572
FID C 9 764
FID C 8 914
FID L 11 383
FID L 12 383
FID L 13 367
FID L 14 332
FID L 15 383
FID L 16 383
SNT TRC
FID C 9 719
FID C 9 720
FID C 9 721
FID C 9 722
FID C 9 723
FID C 9 724
FID C 9 725
FID C 9 726
FID C 9 727
FID C 9 728
FID C 9 729
FID C 9 730
FID C 9 731
FID C 9 732
FID C 9 733
FID C 9 734
FID C 9 735
FID C 9 736
FID C 9 737
FID C 9 738
FID C 9 739
FID C 9 740
FID C 9 741
FID C 9 742
FID C 9 743
FID C 9 744
FID C 9 745
FID C 9 746
FID C 9 747
FID C 9 748
FID C 9 749
FID C 9 750
FID C 9 751
FID C 9 752
FID C 9 753
FID C 9 754
FID C 9 755
FID C 9 756
FID C 9 757
FID C 9 758
FID C 9 759
FID C 9 760
FID C 9 761
FID C 9 762
SNT TRC
FID C 8 910
FID C 8 911
SNT TRC
FID C 3 1571
# NET 320
NET LM75B_I2C_SDA 
SNT TOP T 303 1
FID C 4 3837
FID C 5 1816
FID C 3 8254
SNT TOP T 346 0
FID C 4 3831
FID C 5 1814
FID C 3 8248
SNT TOP T 422 0
FID C 4 3838
FID C 5 1817
FID C 3 8256
SNT TOP T 604 3
FID C 4 3832
FID C 5 1815
FID C 3 8249
SNT TOP B 188 0
FID C 6 2981
FID C 7 860
FID C 8 6247
SNT VIA
FID H 0 319
FID C 4 3830
FID C 6 2977
FID C 3 8247
FID C 8 6224
FID L 11 1475
FID L 12 1475
FID L 13 2252
FID L 14 2251
FID L 15 1475
FID L 16 1475
SNT VIA
FID H 0 320
FID C 4 3834
FID C 6 2979
FID C 3 8251
FID C 9 2679
FID C 8 6228
FID L 11 1477
FID L 12 1477
FID L 13 2254
FID L 14 2253
FID L 15 1477
FID L 16 1477
SNT VIA
FID H 0 321
FID C 4 3833
FID C 6 2978
FID C 3 8250
FID C 9 2678
FID C 8 6227
FID L 11 1476
FID L 12 1476
FID L 13 2253
FID L 14 2252
FID L 15 1476
FID L 16 1476
SNT VIA
FID H 0 322
FID C 4 3835
FID C 6 2980
FID C 3 8252
FID C 9 2680
FID C 8 6246
FID L 11 1478
FID L 12 1478
FID L 13 2255
FID L 14 2254
FID L 15 1478
FID L 16 1478
SNT VIA
FID H 0 1194
FID C 4 3836
FID C 6 2982
FID C 3 8253
FID C 9 2681
FID C 8 6248
FID L 11 1479
FID L 12 1479
FID L 13 2256
FID L 14 2255
FID L 15 1479
FID L 16 1479
SNT TRC
FID C 9 2606
FID C 9 2607
FID C 9 2608
FID C 9 2609
FID C 9 2610
FID C 9 2611
FID C 9 2612
FID C 9 2613
FID C 9 2614
FID C 9 2615
FID C 9 2616
FID C 9 2617
FID C 9 2618
FID C 9 2619
FID C 9 2620
FID C 9 2621
FID C 9 2622
FID C 9 2623
FID C 9 2624
FID C 9 2625
FID C 9 2626
FID C 9 2627
FID C 9 2628
FID C 9 2629
FID C 9 2630
FID C 9 2631
FID C 9 2632
FID C 9 2633
FID C 9 2634
FID C 9 2635
FID C 9 2636
FID C 9 2637
FID C 9 2638
FID C 9 2639
FID C 9 2640
FID C 9 2641
FID C 9 2642
FID C 9 2643
FID C 9 2644
FID C 9 2645
SNT TRC
FID C 3 8227
SNT TRC
FID C 3 8228
FID C 3 8229
FID C 3 8230
FID C 3 8231
FID C 3 8232
FID C 3 8233
FID C 3 8234
FID C 3 8235
FID C 3 8236
SNT TRC
FID C 3 8237
FID C 3 8238
FID C 3 8239
FID C 3 8240
FID C 3 8241
FID C 3 8242
FID C 3 8243
FID C 3 8244
FID C 3 8245
SNT TRC
FID C 9 2646
FID C 9 2647
FID C 9 2648
FID C 9 2649
FID C 9 2650
FID C 9 2651
FID C 9 2652
FID C 9 2653
FID C 9 2654
FID C 9 2655
FID C 9 2656
FID C 9 2657
FID C 9 2658
FID C 9 2659
FID C 9 2660
FID C 9 2661
FID C 9 2662
FID C 9 2663
FID C 9 2664
FID C 9 2665
FID C 9 2666
FID C 9 2667
FID C 9 2668
FID C 9 2669
FID C 9 2670
FID C 9 2671
FID C 9 2672
FID C 9 2673
FID C 9 2674
FID C 9 2675
FID C 9 2676
FID C 9 2677
SNT TRC
FID C 3 8246
SNT TRC
FID C 8 6225
FID C 8 6226
SNT TRC
FID C 8 6229
FID C 8 6230
FID C 8 6231
FID C 8 6232
FID C 8 6233
FID C 8 6234
FID C 8 6235
FID C 8 6236
FID C 8 6237
FID C 8 6238
FID C 8 6239
FID C 8 6240
FID C 8 6241
FID C 8 6242
FID C 8 6243
FID C 8 6244
FID C 8 6245
SNT TRC
FID C 3 8255
# NET 321
NET UNNAMED_127_MT25QL128ABA1ESES_1 
SNT TOP T 168 1
FID C 4 1865
FID C 5 1112
FID C 3 4622
SNT TOP B 280 0
FID C 6 1260
FID C 7 432
FID C 8 3312
SNT TOP B 281 0
FID C 6 1259
FID C 7 431
FID C 8 3310
SNT VIA
FID H 0 2175
FID C 4 1864
FID C 6 1261
FID C 3 4620
FID C 8 3313
FID L 11 1095
FID L 12 1095
FID L 13 948
FID L 14 898
FID L 15 1095
FID L 16 1095
SNT TRC
FID C 8 3308
FID C 8 3309
SNT TRC
FID C 8 3311
SNT TRC
FID C 3 4621
# NET 322
NET UNNAMED_127_MT25QL128ABA1ESES_3 
SNT TOP T 168 2
FID C 4 1861
FID C 5 1110
FID C 3 4616
SNT TOP B 278 0
FID C 6 1253
FID C 7 427
FID C 8 3298
SNT TOP B 279 0
FID C 6 1254
FID C 7 428
FID C 8 3300
SNT VIA
FID H 0 2177
FID C 4 1860
FID C 6 1255
FID C 3 4614
FID C 8 3301
FID L 11 1093
FID L 12 1093
FID L 13 946
FID L 14 896
FID L 15 1093
FID L 16 1093
SNT TRC
FID C 8 3295
FID C 8 3296
FID C 8 3297
SNT TRC
FID C 8 3299
SNT TRC
FID C 3 4615
# NET 323
NET UNNAMED_127_MT25QL128ABA1ESES_2 
SNT TOP T 168 6
FID C 4 1863
FID C 5 1111
FID C 3 4619
SNT TOP B 283 0
FID C 6 1257
FID C 7 429
FID C 8 3305
SNT TOP B 284 0
FID C 6 1258
FID C 7 430
FID C 8 3307
SNT VIA
FID H 0 2176
FID C 4 1862
FID C 6 1256
FID C 3 4617
FID C 8 3302
FID L 11 1094
FID L 12 1094
FID L 13 947
FID L 14 897
FID L 15 1094
FID L 16 1094
SNT TRC
FID C 8 3303
FID C 8 3304
SNT TRC
FID C 8 3306
SNT TRC
FID C 3 4618
# NET 324
NET FLASH_DQ0_MOSI 
SNT TOP T 5 6
FID C 4 689
FID C 5 424
FID C 3 1871
SNT TOP B 285 1
FID C 6 428
FID C 7 137
FID C 8 1183
SNT VIA
FID H 0 2155
FID C 4 690
FID C 6 427
FID C 3 1872
FID C 8 1182
FID L 11 442
FID L 12 442
FID L 13 426
FID L 14 391
FID L 15 442
FID L 16 442
SNT TRC
FID C 3 1864
FID C 3 1865
FID C 3 1866
FID C 3 1867
FID C 3 1868
FID C 3 1869
FID C 3 1870
SNT TRC
FID C 8 1180
FID C 8 1181
# NET 325
NET FLASH_DQ1_MISO 
SNT TOP T 5 8
FID C 4 687
FID C 5 423
FID C 3 1862
SNT TOP B 280 1
FID C 6 426
FID C 7 136
FID C 8 1179
SNT VIA
FID H 0 216
FID C 4 686
FID C 6 424
FID C 3 1860
FID C 8 1176
FID L 11 440
FID L 12 440
FID L 13 424
FID L 14 389
FID L 15 440
FID L 16 440
SNT VIA
FID H 0 1107
FID C 4 688
FID C 6 425
FID C 3 1863
FID C 8 1178
FID L 11 441
FID L 12 441
FID L 13 425
FID L 14 390
FID L 15 441
FID L 16 441
SNT TRC
FID C 8 1166
FID C 8 1167
FID C 8 1168
FID C 8 1169
FID C 8 1170
FID C 8 1171
FID C 8 1172
FID C 8 1173
FID C 8 1174
FID C 8 1175
SNT TRC
FID C 3 1861
SNT TRC
FID C 8 1177
# NET 326
NET FLASH_DQ2 
SNT TOP T 2 2
FID C 4 685
FID C 5 422
FID C 3 1859
SNT TOP T 240 1
FID C 4 684
FID C 5 421
FID C 3 1858
SNT TOP B 279 1
FID C 6 422
FID C 7 135
FID C 8 1164
SNT VIA
FID H 0 2229
FID C 4 683
FID C 6 423
FID C 3 1855
FID C 8 1165
FID L 11 439
FID L 12 439
FID L 13 423
FID L 14 388
FID L 15 439
FID L 16 439
SNT TRC
FID C 8 1160
FID C 8 1161
FID C 8 1162
FID C 8 1163
SNT TRC
FID C 3 1854
SNT TRC
FID C 3 1856
FID C 3 1857
# NET 327
NET FLASH_DQ3 
SNT TOP T 3 2
FID C 4 682
FID C 5 420
FID C 3 1853
SNT TOP T 239 1
FID C 4 681
FID C 5 419
FID C 3 1852
SNT TOP B 283 1
FID C 6 421
FID C 7 134
FID C 8 1159
SNT VIA
FID H 0 1108
FID C 4 680
FID C 6 420
FID C 3 1849
FID C 8 1158
FID L 11 438
FID L 12 438
FID L 13 422
FID L 14 387
FID L 15 438
FID L 16 438
SNT TRC
FID C 8 1150
FID C 8 1151
FID C 8 1152
FID C 8 1153
FID C 8 1154
FID C 8 1155
FID C 8 1156
FID C 8 1157
SNT TRC
FID C 3 1847
FID C 3 1848
SNT TRC
FID C 3 1850
FID C 3 1851
# NET 328
NET CCLK_0 
SNT TOP T 170 275
FID C 4 1996
FID C 5 1199
FID C 3 5089
SNT TOP B 262 0
FID C 6 1370
FID C 7 490
FID C 8 3620
SNT VIA
FID H 0 1101
FID C 4 1995
FID C 6 1369
FID C 3 5087
FID C 9 2225
FID C 8 3619
FID L 11 1174
FID L 12 1174
FID L 13 1027
FID L 14 966
FID L 15 1174
FID L 16 1174
SNT VIA
FID H 0 2106
FID C 3 5086
FID C 9 2224
FID C 8 3616
FID L 11 1173
FID L 12 1173
FID L 13 1026
FID L 14 965
FID L 15 1173
FID L 16 1173
SNT TRC
FID C 9 2221
FID C 9 2222
FID C 9 2223
SNT TRC
FID C 8 3617
FID C 8 3618
SNT TRC
FID C 3 5088
# NET 329
NET FPGA_FLASH_CLK 
SNT TOP T 5 1
FID C 4 670
FID C 5 412
FID C 3 1776
SNT TOP B 262 1
FID C 6 416
FID C 7 133
FID C 8 1146
SNT VIA
FID H 0 221
FID C 4 671
FID C 6 417
FID C 3 1777
FID C 10 728
FID C 8 1147
FID L 11 435
FID L 12 435
FID L 13 419
FID L 14 384
FID L 15 435
FID L 16 435
SNT VIA
FID H 0 1118
FID C 4 669
FID C 6 415
FID C 3 1775
FID C 10 727
FID C 8 1145
FID L 11 434
FID L 12 434
FID L 13 418
FID L 14 383
FID L 15 434
FID L 16 434
SNT TRC
FID C 10 723
FID C 10 724
FID C 10 725
FID C 10 726
SNT TRC
FID C 8 1144
SNT TRC
FID C 3 1774
# NET 330
NET FPGA_DONE 
SNT TOP T 20 0
FID H 0 169
FID C 6 1357
FID C 3 5061
FID C 9 2197
FID C 8 3589
FID L 11 1164
FID L 12 1164
FID L 13 1017
FID L 14 956
FID L 15 1164
FID L 16 1164
SNT TOP T 170 186
FID C 4 1984
FID C 5 1191
FID C 3 5063
SNT TOP B 312 1
FID C 6 1358
FID C 7 484
FID C 8 3590
SNT TOP B 313 0
FID C 6 1359
FID C 7 485
FID C 8 3592
SNT VIA
FID H 0 2350
FID C 3 5062
FID C 9 2198
FID C 8 3593
FID L 11 1165
FID L 12 1165
FID L 13 1018
FID L 14 957
FID L 15 1165
FID L 16 1165
SNT TRC
FID C 3 5060
SNT TRC
FID C 9 2151
FID C 9 2152
FID C 9 2153
FID C 9 2154
FID C 9 2155
FID C 9 2156
FID C 9 2157
FID C 9 2158
FID C 9 2159
FID C 9 2160
FID C 9 2161
FID C 9 2162
FID C 9 2163
FID C 9 2164
FID C 9 2165
FID C 9 2166
FID C 9 2167
FID C 9 2168
FID C 9 2169
FID C 9 2170
FID C 9 2171
FID C 9 2172
FID C 9 2173
FID C 9 2174
FID C 9 2175
FID C 9 2176
FID C 9 2177
FID C 9 2178
FID C 9 2179
FID C 9 2180
FID C 9 2181
FID C 9 2182
FID C 9 2183
FID C 9 2184
FID C 9 2185
FID C 9 2186
FID C 9 2187
FID C 9 2188
FID C 9 2189
FID C 9 2190
FID C 9 2191
FID C 9 2192
FID C 9 2193
FID C 9 2194
FID C 9 2195
FID C 9 2196
SNT TRC
FID C 8 3587
FID C 8 3588
SNT TRC
FID C 8 3591
# NET 331
NET LM75B_I2C_SCL 
SNT TOP T 186 1
FID C 4 3841
FID C 5 1819
FID C 3 8284
SNT TOP T 188 1
FID C 4 3839
FID C 5 1818
FID C 3 8271
SNT TOP T 302 1
FID C 4 3847
FID C 5 1821
FID C 3 8290
SNT TOP T 604 4
FID C 4 3843
FID C 5 1820
FID C 3 8286
SNT TOP B 108 1
FID C 6 2988
FID C 7 861
FID C 8 6277
SNT VIA
FID H 0 315
FID C 4 3842
FID C 6 2984
FID C 3 8285
FID C 8 6273
FID L 11 1481
FID L 12 1481
FID L 13 2258
FID L 14 2257
FID L 15 1481
FID L 16 1481
SNT VIA
FID H 0 316
FID C 4 3845
FID C 6 2986
FID C 3 8288
FID C 9 2740
FID C 8 6275
FID L 11 1483
FID L 12 1483
FID L 13 2260
FID L 14 2259
FID L 15 1483
FID L 16 1483
SNT VIA
FID H 0 317
FID C 4 3844
FID C 6 2985
FID C 3 8287
FID C 9 2739
FID C 8 6274
FID L 11 1482
FID L 12 1482
FID L 13 2259
FID L 14 2258
FID L 15 1482
FID L 16 1482
SNT VIA
FID H 0 318
FID C 4 3846
FID C 6 2987
FID C 3 8289
FID C 9 2741
FID C 8 6276
FID L 11 1484
FID L 12 1484
FID L 13 2261
FID L 14 2260
FID L 15 1484
FID L 16 1484
SNT VIA
FID H 0 1193
FID C 4 3840
FID C 6 2983
FID C 3 8272
FID C 9 2706
FID C 8 6269
FID L 11 1480
FID L 12 1480
FID L 13 2257
FID L 14 2256
FID L 15 1480
FID L 16 1480
SNT TRC
FID C 9 2682
FID C 9 2683
FID C 9 2684
FID C 9 2685
FID C 9 2686
FID C 9 2687
FID C 9 2688
FID C 9 2689
FID C 9 2690
FID C 9 2691
FID C 9 2692
FID C 9 2693
FID C 9 2694
FID C 9 2695
FID C 9 2696
FID C 9 2697
FID C 9 2698
FID C 9 2699
FID C 9 2700
FID C 9 2701
FID C 9 2702
FID C 9 2703
FID C 9 2704
FID C 9 2705
SNT TRC
FID C 3 8257
FID C 3 8258
FID C 3 8259
FID C 3 8260
SNT TRC
FID C 3 8261
FID C 3 8262
FID C 3 8263
SNT TRC
FID C 8 6249
FID C 8 6250
FID C 8 6251
FID C 8 6252
FID C 8 6253
FID C 8 6254
FID C 8 6255
FID C 8 6256
FID C 8 6257
FID C 8 6258
FID C 8 6259
FID C 8 6260
FID C 8 6261
FID C 8 6262
FID C 8 6263
FID C 8 6264
FID C 8 6265
FID C 8 6266
FID C 8 6267
FID C 8 6268
SNT TRC
FID C 3 8264
FID C 3 8265
FID C 3 8266
FID C 3 8267
FID C 3 8268
FID C 3 8269
FID C 3 8270
SNT TRC
FID C 3 8273
FID C 3 8274
FID C 3 8275
SNT TRC
FID C 8 6270
FID C 8 6271
FID C 8 6272
SNT TRC
FID C 3 8276
FID C 3 8277
FID C 3 8278
FID C 3 8279
FID C 3 8280
FID C 3 8281
FID C 3 8282
FID C 3 8283
SNT TRC
FID C 9 2707
FID C 9 2708
FID C 9 2709
FID C 9 2710
FID C 9 2711
FID C 9 2712
FID C 9 2713
FID C 9 2714
FID C 9 2715
FID C 9 2716
FID C 9 2717
FID C 9 2718
FID C 9 2719
FID C 9 2720
FID C 9 2721
FID C 9 2722
FID C 9 2723
FID C 9 2724
FID C 9 2725
FID C 9 2726
FID C 9 2727
FID C 9 2728
FID C 9 2729
FID C 9 2730
FID C 9 2731
FID C 9 2732
FID C 9 2733
FID C 9 2734
FID C 9 2735
FID C 9 2736
FID C 9 2737
FID C 9 2738
# NET 332
NET FPGA_M0 
SNT TOP T 170 406
FID C 4 1971
FID C 5 1182
FID C 3 5005
SNT TOP T 377 0
FID C 4 1972
FID C 5 1183
FID C 3 5006
SNT TOP T 378 1
FID C 4 1973
FID C 5 1184
FID C 3 5008
SNT VIA
FID H 0 1142
FID C 4 1970
FID C 6 1348
FID C 3 5004
FID C 8 3563
FID L 11 1157
FID L 12 1157
FID L 13 1010
FID L 14 949
FID L 15 1157
FID L 16 1157
SNT TRC
FID C 3 4999
FID C 3 5000
SNT TRC
FID C 3 5001
FID C 3 5002
FID C 3 5003
SNT TRC
FID C 3 5007
# NET 333
NET FPGA_BRD_REV2 
SNT TOP T 170 325
FID C 4 1988
FID C 5 1194
FID C 3 5072
SNT TOP T 359 0
FID C 4 1985
FID C 5 1192
FID C 3 5066
SNT TOP T 361 1
FID C 4 1987
FID C 5 1193
FID C 3 5069
SNT VIA
FID H 0 217
FID C 4 1986
FID C 6 1360
FID C 3 5068
FID C 10 3213
FID C 8 3594
FID L 11 1166
FID L 12 1166
FID L 13 1019
FID L 14 958
FID L 15 1166
FID L 16 1166
SNT VIA
FID H 0 2574
FID C 6 1361
FID C 3 5070
FID C 10 3214
FID C 8 3595
FID L 11 1167
FID L 12 1167
FID L 13 1020
FID L 14 959
FID L 15 1167
FID L 16 1167
SNT TRC
FID C 10 3207
FID C 10 3208
FID C 10 3209
FID C 10 3210
FID C 10 3211
FID C 10 3212
SNT TRC
FID C 3 5064
FID C 3 5065
SNT TRC
FID C 3 5067
SNT TRC
FID C 3 5071
# NET 334
NET FPGA_BRD_REV1 
SNT TOP T 170 326
FID C 4 1989
FID C 5 1195
FID C 3 5074
SNT TOP B 232 1
FID C 6 1364
FID C 7 487
FID C 8 3601
SNT TOP B 233 0
FID C 6 1363
FID C 7 486
FID C 8 3599
SNT VIA
FID H 0 1109
FID C 4 1990
FID C 6 1362
FID C 3 5076
FID C 9 2207
FID C 8 3598
FID L 11 1169
FID L 12 1169
FID L 13 1022
FID L 14 961
FID L 15 1169
FID L 16 1169
SNT VIA
FID H 0 2348
FID C 3 5073
FID C 9 2206
FID C 8 3596
FID L 11 1168
FID L 12 1168
FID L 13 1021
FID L 14 960
FID L 15 1168
FID L 16 1168
SNT TRC
FID C 9 2199
FID C 9 2200
FID C 9 2201
FID C 9 2202
FID C 9 2203
FID C 9 2204
FID C 9 2205
SNT TRC
FID C 3 5075
SNT TRC
FID C 8 3597
SNT TRC
FID C 8 3600
# NET 335
NET FPGA_M1 
SNT TOP T 170 405
FID C 4 1968
FID C 5 1181
FID C 3 4997
SNT TOP B 252 0
FID C 6 1346
FID C 7 479
FID C 8 3561
SNT TOP B 253 1
FID C 6 1345
FID C 7 478
FID C 8 3559
SNT VIA
FID H 0 1143
FID C 4 1969
FID C 6 1347
FID C 3 4998
FID C 10 3121
FID C 8 3562
FID L 11 1156
FID L 12 1156
FID L 13 1009
FID L 14 948
FID L 15 1156
FID L 16 1156
SNT VIA
FID H 0 2354
FID C 3 4994
FID C 10 3120
FID C 8 3556
FID L 11 1155
FID L 12 1155
FID L 13 1008
FID L 14 947
FID L 15 1155
FID L 16 1155
SNT TRC
FID C 10 3115
FID C 10 3116
FID C 10 3117
FID C 10 3118
FID C 10 3119
SNT TRC
FID C 8 3557
FID C 8 3558
SNT TRC
FID C 3 4995
FID C 3 4996
SNT TRC
FID C 8 3560
# NET 336
NET FPGA_BRD_REV0 
SNT TOP T 170 327
FID C 4 1991
FID C 5 1196
FID C 3 5078
SNT TOP B 260 1
FID C 6 1367
FID C 7 489
FID C 8 3613
SNT TOP B 261 0
FID C 6 1366
FID C 7 488
FID C 8 3611
SNT VIA
FID C 6 1365
FID C 8 3610
SNT VIA
FID H 0 2347
FID C 3 5077
FID C 8 3609
FID L 11 1170
FID L 12 1170
FID L 13 1023
FID L 14 962
FID L 15 1170
FID L 16 1170
SNT TRC
FID C 8 3602
FID C 8 3603
FID C 8 3604
FID C 8 3605
SNT TRC
FID C 8 3606
FID C 8 3607
FID C 8 3608
SNT TRC
FID C 8 3612
SNT TRC
FID C 3 5079
# NET 337
NET FPGA_M2 
SNT TOP T 170 404
FID C 4 1964
FID C 5 1178
FID C 3 4990
SNT TOP T 372 0
FID C 4 1965
FID C 5 1179
FID C 3 4991
SNT TOP T 373 1
FID C 4 1967
FID C 5 1180
FID C 3 4993
SNT VIA
FID H 0 2231
FID C 4 1966
FID C 6 1344
FID C 3 4992
FID C 9 2150
FID C 8 3555
FID L 11 1154
FID L 12 1154
FID L 13 1007
FID L 14 946
FID L 15 1154
FID L 16 1154
SNT VIA
FID H 0 2355
FID C 3 4987
FID C 9 2149
FID C 8 3554
FID L 11 1153
FID L 12 1153
FID L 13 1006
FID L 14 945
FID L 15 1153
FID L 16 1153
SNT TRC
FID C 9 2136
FID C 9 2137
FID C 9 2138
FID C 9 2139
FID C 9 2140
FID C 9 2141
FID C 9 2142
FID C 9 2143
FID C 9 2144
FID C 9 2145
FID C 9 2146
FID C 9 2147
FID C 9 2148
SNT TRC
FID C 3 4986
SNT TRC
FID C 3 4988
SNT TRC
FID C 3 4989
# NET 338
NET PUDC 
SNT TOP T 170 417
FID C 4 1891
FID C 5 1127
FID C 3 4687
SNT TOP B 258 0
FID C 6 1292
FID C 7 451
FID C 8 3390
SNT TOP B 259 1
FID C 6 1291
FID C 7 450
FID C 8 3388
SNT VIA
FID H 0 2221
FID C 6 1293
FID C 3 4685
FID C 8 3391
FID L 11 1110
FID L 12 1110
FID L 13 963
FID L 14 913
FID L 15 1110
FID L 16 1110
SNT TRC
FID C 8 3382
FID C 8 3383
FID C 8 3384
FID C 8 3385
FID C 8 3386
FID C 8 3387
SNT TRC
FID C 8 3389
SNT TRC
FID C 3 4686
# NET 339
NET UNNAMED_515_ISL80101IRAJZDFN10_ 
SNT TOP T 117 2
FID C 4 1831
FID C 5 1091
FID C 3 4561
SNT TOP T 428 1
FID C 4 1830
FID C 5 1090
FID C 3 4560
SNT TOP B 351 1
FID C 6 1225
FID C 7 411
FID C 8 3233
SNT TOP B 352 1
FID C 6 1226
FID C 7 412
FID C 8 3234
SNT VIA
FID H 0 2279
FID C 4 1832
FID C 6 1227
FID C 3 4562
FID C 8 3237
FID L 11 1083
FID L 12 1083
FID L 13 936
FID L 14 886
FID L 15 1083
FID L 16 1083
SNT TRC
FID C 8 3231
FID C 8 3232
SNT TRC
FID C 8 3235
FID C 8 3236
SNT TRC
FID C 3 4556
FID C 3 4557
SNT TRC
FID C 3 4558
FID C 3 4559
# NET 340
NET FPGA_D00_MOSI 
SNT TOP T 170 351
FID C 4 20
FID C 5 13
FID C 3 68
SNT TOP T 217 0
FID C 4 19
FID C 5 12
FID C 3 67
SNT VIA
FID H 0 1111
FID C 4 18
FID C 6 10
FID C 3 66
FID C 8 16
FID L 11 9
FID L 12 9
FID L 13 9
FID L 14 9
FID L 15 9
FID L 16 9
SNT TRC
FID C 3 58
FID C 3 59
FID C 3 60
FID C 3 61
SNT TRC
FID C 3 62
FID C 3 63
FID C 3 64
FID C 3 65
# NET 341
NET FPGA_FLASH_DQ0_MOSI 
SNT TOP T 5 4
FID C 4 664
FID C 5 409
FID C 3 1765
SNT TOP T 217 1
FID C 4 661
FID C 5 408
FID C 3 1761
SNT VIA
FID H 0 223
FID C 4 662
FID C 6 411
FID C 3 1763
FID C 10 676
FID C 8 1140
FID L 11 430
FID L 12 430
FID L 13 414
FID L 14 379
FID L 15 430
FID L 16 430
SNT VIA
FID H 0 1120
FID C 4 663
FID C 6 412
FID C 3 1764
FID C 10 677
FID C 8 1141
FID L 11 431
FID L 12 431
FID L 13 415
FID L 14 380
FID L 15 431
FID L 16 431
SNT TRC
FID C 10 626
FID C 10 627
FID C 10 628
FID C 10 629
FID C 10 630
FID C 10 631
FID C 10 632
FID C 10 633
FID C 10 634
FID C 10 635
FID C 10 636
FID C 10 637
FID C 10 638
FID C 10 639
FID C 10 640
FID C 10 641
FID C 10 642
FID C 10 643
FID C 10 644
FID C 10 645
FID C 10 646
FID C 10 647
FID C 10 648
FID C 10 649
FID C 10 650
FID C 10 651
FID C 10 652
FID C 10 653
FID C 10 654
FID C 10 655
FID C 10 656
FID C 10 657
FID C 10 658
FID C 10 659
FID C 10 660
FID C 10 661
FID C 10 662
FID C 10 663
FID C 10 664
FID C 10 665
FID C 10 666
FID C 10 667
FID C 10 668
FID C 10 669
FID C 10 670
FID C 10 671
FID C 10 672
FID C 10 673
FID C 10 674
FID C 10 675
SNT TRC
FID C 3 1758
FID C 3 1759
FID C 3 1760
SNT TRC
FID C 3 1762
# NET 342
NET CLK_200M_OE 
SNT TOP T 17 0
FID H 0 174
FID C 6 35
FID C 3 172
FID C 8 64
FID L 11 25
FID L 12 25
FID L 13 25
FID L 14 25
FID L 15 25
FID L 16 25
SNT TOP T 166 0
FID C 4 53
FID C 5 40
FID C 3 174
SNT TOP T 376 1
FID C 4 52
FID C 5 39
FID C 3 173
SNT TRC
FID C 3 168
FID C 3 169
FID C 3 170
SNT TRC
FID C 3 171
# NET 343
NET CLK_125M_OE 
SNT TOP T 165 0
FID C 4 55
FID C 5 41
FID C 3 183
SNT TOP T 195 1
FID C 4 56
FID C 5 42
FID C 3 184
SNT TOP B 6 0
FID H 0 176
FID C 6 37
FID C 3 180
FID C 8 66
FID L 11 27
FID L 12 27
FID L 13 27
FID L 14 27
FID L 15 27
FID L 16 27
SNT VIA
FID H 0 1102
FID C 4 54
FID C 6 36
FID C 3 175
FID C 8 65
FID L 11 26
FID L 12 26
FID L 13 26
FID L 14 26
FID L 15 26
FID L 16 26
SNT TRC
FID C 3 176
FID C 3 177
SNT TRC
FID C 3 178
FID C 3 179
SNT TRC
FID C 3 181
FID C 3 182
# NET 344
NET FPGA_D01 
SNT TOP T 170 373
FID C 4 17
FID C 5 11
FID C 3 57
SNT TOP T 216 0
FID C 4 16
FID C 5 10
FID C 3 56
SNT VIA
FID H 0 1112
FID C 4 15
FID C 6 9
FID C 3 55
FID C 8 15
FID L 11 8
FID L 12 8
FID L 13 8
FID L 14 8
FID L 15 8
FID L 16 8
SNT TRC
FID C 3 49
FID C 3 50
FID C 3 51
FID C 3 52
SNT TRC
FID C 3 53
FID C 3 54
# NET 345
NET FPGA_FLASH_DQ1_MISO 
SNT TOP T 5 10
FID C 4 657
FID C 5 406
FID C 3 1751
SNT TOP T 216 1
FID C 4 659
FID C 5 407
FID C 3 1753
SNT TOP T 247 0
FID C 4 656
FID C 5 405
FID C 3 1750
SNT VIA
FID H 0 224
FID C 4 660
FID C 6 410
FID C 3 1756
FID C 10 625
FID C 8 1139
FID L 11 429
FID L 12 429
FID L 13 413
FID L 14 378
FID L 15 429
FID L 16 429
SNT VIA
FID H 0 1121
FID C 4 658
FID C 6 409
FID C 3 1752
FID C 10 624
FID C 8 1138
FID L 11 428
FID L 12 428
FID L 13 412
FID L 14 377
FID L 15 428
FID L 16 428
SNT TRC
FID C 10 569
FID C 10 570
FID C 10 571
FID C 10 572
FID C 10 573
FID C 10 574
FID C 10 575
FID C 10 576
FID C 10 577
FID C 10 578
FID C 10 579
FID C 10 580
FID C 10 581
FID C 10 582
FID C 10 583
FID C 10 584
FID C 10 585
FID C 10 586
FID C 10 587
FID C 10 588
FID C 10 589
FID C 10 590
FID C 10 591
FID C 10 592
FID C 10 593
FID C 10 594
FID C 10 595
FID C 10 596
FID C 10 597
FID C 10 598
FID C 10 599
FID C 10 600
FID C 10 601
FID C 10 602
FID C 10 603
FID C 10 604
FID C 10 605
FID C 10 606
FID C 10 607
FID C 10 608
FID C 10 609
FID C 10 610
FID C 10 611
FID C 10 612
FID C 10 613
FID C 10 614
FID C 10 615
FID C 10 616
FID C 10 617
FID C 10 618
FID C 10 619
FID C 10 620
FID C 10 621
FID C 10 622
FID C 10 623
SNT TRC
FID C 3 1748
FID C 3 1749
SNT TRC
FID C 3 1754
FID C 3 1755
SNT TRC
FID C 3 1757
# NET 346
NET XP3R3V_PG 
SNT TOP T 26 0
FID H 0 162
FID C 6 1431
FID C 3 5240
FID C 10 3273
FID C 8 3740
FID L 11 1215
FID L 12 1215
FID L 13 1057
FID L 14 1007
FID L 15 1215
FID L 16 1215
SNT TOP B 275 1
FID C 6 1432
FID C 7 512
FID C 8 3741
SNT TOP B 332 0
FID C 6 1430
FID C 7 511
FID C 8 3739
SNT VIA
FID H 0 1038
FID C 4 2079
FID C 6 1429
FID C 3 5239
FID C 10 3272
FID C 8 3738
FID L 11 1214
FID L 12 1214
FID L 13 1056
FID L 14 1006
FID L 15 1214
FID L 16 1214
SNT TRC
FID C 8 3725
FID C 8 3726
FID C 8 3727
FID C 8 3728
FID C 8 3729
SNT TRC
FID C 10 3253
FID C 10 3254
FID C 10 3255
FID C 10 3256
FID C 10 3257
FID C 10 3258
FID C 10 3259
FID C 10 3260
FID C 10 3261
FID C 10 3262
FID C 10 3263
FID C 10 3264
FID C 10 3265
FID C 10 3266
FID C 10 3267
FID C 10 3268
FID C 10 3269
FID C 10 3270
FID C 10 3271
SNT TRC
FID C 8 3730
FID C 8 3731
FID C 8 3732
FID C 8 3733
FID C 8 3734
FID C 8 3735
FID C 8 3736
FID C 8 3737
# NET 347
NET XP1R0V_RT 
SNT TOP T 182 12
FID C 4 1714
FID C 5 1013
FID C 3 4323
SNT TOP T 408 0
FID C 4 1715
FID C 5 1014
FID C 3 4324
SNT VIA
FID H 0 1368
FID C 4 1713
FID C 6 1133
FID C 3 4322
FID C 8 3023
FID L 11 1018
FID L 12 1018
FID L 13 911
FID L 14 821
FID L 15 1018
FID L 16 1018
SNT TRC
FID C 3 4318
FID C 3 4319
SNT TRC
FID C 3 4320
FID C 3 4321
# NET 348
NET UNNAMED_3_G2201019801_I100_EN 
SNT TOP T 183 0
FID C 4 2219
FID C 5 1320
FID C 3 5492
SNT TOP T 204 1
FID C 4 2220
FID C 5 1321
FID C 3 5497
SNT TOP T 205 1
FID C 4 2221
FID C 5 1322
FID C 3 5498
SNT VIA
FID H 0 2275
FID C 4 2218
FID C 6 1532
FID C 3 5488
FID C 8 3904
FID L 11 1282
FID L 12 1282
FID L 13 1093
FID L 14 1063
FID L 15 1282
FID L 16 1282
SNT TRC
FID C 3 5489
FID C 3 5490
FID C 3 5491
SNT TRC
FID C 3 5493
FID C 3 5494
FID C 3 5495
SNT TRC
FID C 3 5496
# NET 349
NET XP1R0V_BT 
SNT TOP T 182 0
FID C 4 1791
FID C 5 1064
FID C 3 4478
SNT TOP B 168 0
FID C 6 1190
FID C 7 392
FID C 8 3158
SNT VIA
FID H 0 1366
FID C 4 1790
FID C 6 1191
FID C 3 4477
FID C 8 3161
FID L 11 1068
FID L 12 1068
FID L 13 921
FID L 14 871
FID L 15 1068
FID L 16 1068
SNT TRC
FID C 8 3159
FID C 8 3160
SNT TRC
FID C 3 4474
FID C 3 4475
FID C 3 4476
# NET 350
NET UNNAMED_14_RESISTOR_I65_2 
SNT TOP B 321 0
FID C 6 1239
FID C 7 419
FID C 8 3266
SNT TOP B 322 1
FID C 6 1238
FID C 7 418
FID C 8 3265
SNT VIA
FID C 6 1237
FID C 8 3261
SNT TRC
FID C 8 3258
FID C 8 3259
FID C 8 3260
SNT TRC
FID C 8 3262
FID C 8 3263
FID C 8 3264
# NET 351
NET UART_MAC_TX_FPGA_RX 
SNT TOP T 170 61
FID C 4 1869
FID C 5 1114
FID C 3 4635
SNT TOP T 357 1
FID C 4 1870
FID C 5 1115
FID C 3 4636
SNT TOP B 231 1
FID C 6 1266
FID C 7 435
FID C 8 3323
SNT VIA
FID H 0 1263
FID C 4 1868
FID C 6 1265
FID C 3 4634
FID C 8 3322
FID L 11 1097
FID L 12 1097
FID L 13 950
FID L 14 900
FID L 15 1097
FID L 16 1097
SNT TRC
FID C 3 4626
FID C 3 4627
FID C 3 4628
FID C 3 4629
FID C 3 4630
SNT TRC
FID C 3 4631
FID C 3 4632
FID C 3 4633
SNT TRC
FID C 8 3320
FID C 8 3321
# NET 352
NET RSVD_DBG_USB_MUX_SEL 
SNT TOP T 170 301
FID C 4 1213
FID C 5 728
FID C 3 3152
SNT TOP T 207 0
FID C 4 1215
FID C 5 729
FID C 3 3156
SNT VIA
FID H 0 1425
FID C 4 1214
FID C 6 728
FID C 3 3153
FID C 9 1597
FID C 8 2187
FID L 11 715
FID L 12 715
FID L 13 699
FID L 14 664
FID L 15 715
FID L 16 715
SNT VIA
FID H 0 2166
FID C 4 1212
FID C 6 727
FID C 3 3150
FID C 9 1596
FID C 10 2152
FID C 8 2186
FID L 11 714
FID L 12 714
FID L 13 698
FID L 14 663
FID L 15 714
FID L 16 714
SNT VIA
FID H 0 2386
FID C 3 3149
FID C 10 2151
FID C 8 2185
FID L 11 713
FID L 12 713
FID L 13 697
FID L 14 662
FID L 15 713
FID L 16 713
SNT TRC
FID C 9 1582
FID C 9 1583
FID C 9 1584
FID C 9 1585
FID C 9 1586
FID C 9 1587
FID C 9 1588
FID C 9 1589
FID C 9 1590
FID C 9 1591
FID C 9 1592
FID C 9 1593
FID C 9 1594
FID C 9 1595
SNT TRC
FID C 10 2129
FID C 10 2130
FID C 10 2131
FID C 10 2132
FID C 10 2133
FID C 10 2134
FID C 10 2135
FID C 10 2136
FID C 10 2137
FID C 10 2138
FID C 10 2139
FID C 10 2140
FID C 10 2141
FID C 10 2142
FID C 10 2143
FID C 10 2144
FID C 10 2145
FID C 10 2146
FID C 10 2147
FID C 10 2148
FID C 10 2149
FID C 10 2150
SNT TRC
FID C 3 3151
SNT TRC
FID C 3 3154
FID C 3 3155
# NET 353
NET UNNAMED_527_RESISTOR_I206_1 
SNT TOP B 106 2
FID C 6 714
FID C 7 191
FID C 8 2165
SNT TOP B 241 0
FID C 6 715
FID C 7 192
FID C 8 2166
SNT VIA
FID C 6 713
FID C 8 2159
SNT TRC
FID C 8 2156
FID C 8 2157
FID C 8 2158
SNT TRC
FID C 8 2160
FID C 8 2161
FID C 8 2162
FID C 8 2163
FID C 8 2164
# NET 354
NET FPGA_OUT_SMA1_LED_RED_N 
SNT TOP T 170 169
FID C 4 869
FID C 5 528
FID C 3 2283
SNT TOP T 298 0
FID C 4 871
FID C 5 529
FID C 3 2287
SNT VIA
FID H 0 269
FID C 4 870
FID C 6 530
FID C 3 2286
FID C 8 1556
FID L 11 533
FID L 12 533
FID L 13 517
FID L 14 482
FID L 15 533
FID L 16 533
SNT VIA
FID H 0 1155
FID C 4 868
FID C 6 529
FID C 3 2282
FID C 10 1254
FID C 8 1555
FID L 11 532
FID L 12 532
FID L 13 516
FID L 14 481
FID L 15 532
FID L 16 532
SNT VIA
FID H 0 2128
FID C 3 2281
FID C 10 1253
FID C 8 1554
FID L 11 531
FID L 12 531
FID L 13 515
FID L 14 480
FID L 15 531
FID L 16 531
SNT TRC
FID C 10 1225
FID C 10 1226
FID C 10 1227
FID C 10 1228
FID C 10 1229
FID C 10 1230
FID C 10 1231
FID C 10 1232
FID C 10 1233
FID C 10 1234
FID C 10 1235
FID C 10 1236
FID C 10 1237
FID C 10 1238
FID C 10 1239
FID C 10 1240
FID C 10 1241
FID C 10 1242
FID C 10 1243
FID C 10 1244
FID C 10 1245
FID C 10 1246
FID C 10 1247
FID C 10 1248
FID C 10 1249
FID C 10 1250
FID C 10 1251
FID C 10 1252
SNT TRC
FID C 8 1527
FID C 8 1528
FID C 8 1529
FID C 8 1530
FID C 8 1531
FID C 8 1532
FID C 8 1533
FID C 8 1534
FID C 8 1535
FID C 8 1536
FID C 8 1537
FID C 8 1538
FID C 8 1539
FID C 8 1540
FID C 8 1541
FID C 8 1542
FID C 8 1543
FID C 8 1544
FID C 8 1545
FID C 8 1546
FID C 8 1547
FID C 8 1548
FID C 8 1549
FID C 8 1550
FID C 8 1551
FID C 8 1552
FID C 8 1553
SNT TRC
FID C 3 2284
SNT TRC
FID C 3 2285
# NET 355
NET FPGA_OUT_SMA2_LED_BLUE_N 
SNT TOP T 170 101
FID C 4 867
FID C 5 527
FID C 3 2280
SNT TOP T 300 0
FID C 4 866
FID C 5 526
FID C 3 2279
SNT VIA
FID H 0 1156
FID C 4 865
FID C 6 528
FID C 3 2278
FID C 10 1224
FID C 8 1526
FID L 11 530
FID L 12 530
FID L 13 514
FID L 14 479
FID L 15 530
FID L 16 530
SNT VIA
FID H 0 2129
FID C 3 2273
FID C 10 1223
FID C 8 1525
FID L 11 529
FID L 12 529
FID L 13 513
FID L 14 478
FID L 15 529
FID L 16 529
SNT TRC
FID C 10 1198
FID C 10 1199
FID C 10 1200
FID C 10 1201
FID C 10 1202
FID C 10 1203
FID C 10 1204
FID C 10 1205
FID C 10 1206
FID C 10 1207
FID C 10 1208
FID C 10 1209
FID C 10 1210
FID C 10 1211
FID C 10 1212
FID C 10 1213
FID C 10 1214
FID C 10 1215
FID C 10 1216
FID C 10 1217
FID C 10 1218
FID C 10 1219
FID C 10 1220
FID C 10 1221
FID C 10 1222
SNT TRC
FID C 3 2274
SNT TRC
FID C 3 2275
FID C 3 2276
FID C 3 2277
# NET 356
NET FPGA_OUT_SMA2_LED_GREEN_N 
SNT TOP T 170 102
FID C 4 864
FID C 5 525
FID C 3 2272
SNT TOP T 322 0
FID C 4 863
FID C 5 524
FID C 3 2271
SNT VIA
FID H 0 1157
FID C 4 862
FID C 6 527
FID C 3 2270
FID C 10 1197
FID C 8 1524
FID L 11 528
FID L 12 528
FID L 13 512
FID L 14 477
FID L 15 528
FID L 16 528
SNT VIA
FID H 0 2130
FID C 3 2266
FID C 10 1196
FID C 8 1523
FID L 11 527
FID L 12 527
FID L 13 511
FID L 14 476
FID L 15 527
FID L 16 527
SNT TRC
FID C 10 1177
FID C 10 1178
FID C 10 1179
FID C 10 1180
FID C 10 1181
FID C 10 1182
FID C 10 1183
FID C 10 1184
FID C 10 1185
FID C 10 1186
FID C 10 1187
FID C 10 1188
FID C 10 1189
FID C 10 1190
FID C 10 1191
FID C 10 1192
FID C 10 1193
FID C 10 1194
FID C 10 1195
SNT TRC
FID C 3 2267
SNT TRC
FID C 3 2268
FID C 3 2269
# NET 357
NET FPGA_IN_MAC_PPS_OUTP ;1=7,3=0
SNT TOP T 170 440
FID C 4 1977
FID C 5 1186
FID C 3 5018
SNT TOP T 210 0
FID C 4 1978
FID C 5 1187
FID C 3 5034
SNT TOP T 249 0
FID C 4 1976
FID C 5 1185
FID C 3 5016
SNT TOP B 19 0
FID C 6 1352
FID C 7 481
FID C 8 3574
SNT TOP B 162 0
FID C 6 1350
FID C 7 480
FID C 8 3570
SNT VIA
FID H 0 1409
FID C 4 1975
FID C 6 1351
FID C 3 5015
FID C 10 3170
FID C 8 3571
FID L 11 1159
FID L 12 1159
FID L 13 1012
FID L 14 951
FID L 15 1159
FID L 16 1159
SNT VIA
FID H 0 2306
FID H 1 1
FID C 4 1974
FID C 6 1349
FID C 3 5009
FID C 10 3122
FID C 8 3564
FID L 11 1158
FID L 12 1158
FID L 13 1011
FID L 14 950
FID L 15 1158
FID L 16 1158
SNT VIA
FID H 0 2563
FID C 3 5017
FID C 10 3171
FID C 8 3572
FID L 11 1160
FID L 12 1160
FID L 13 1013
FID L 14 952
FID L 15 1160
FID L 16 1160
SNT TRC
FID C 10 3123
FID C 10 3124
FID C 10 3125
FID C 10 3126
FID C 10 3127
FID C 10 3128
FID C 10 3129
FID C 10 3130
FID C 10 3131
FID C 10 3132
FID C 10 3133
FID C 10 3134
FID C 10 3135
FID C 10 3136
FID C 10 3137
FID C 10 3138
FID C 10 3139
FID C 10 3140
FID C 10 3141
FID C 10 3142
FID C 10 3143
FID C 10 3144
FID C 10 3145
FID C 10 3146
FID C 10 3147
FID C 10 3148
FID C 10 3149
FID C 10 3150
FID C 10 3151
FID C 10 3152
FID C 10 3153
FID C 10 3154
FID C 10 3155
FID C 10 3156
FID C 10 3157
FID C 10 3158
FID C 10 3159
FID C 10 3160
SNT TRC
FID C 8 3565
FID C 8 3566
FID C 8 3567
FID C 8 3568
FID C 8 3569
SNT TRC
FID C 10 3161
FID C 10 3162
FID C 10 3163
FID C 10 3164
FID C 10 3165
FID C 10 3166
FID C 10 3167
FID C 10 3168
FID C 10 3169
SNT TRC
FID C 3 5010
FID C 3 5011
FID C 3 5012
FID C 3 5013
FID C 3 5014
SNT TRC
FID C 3 5019
SNT TRC
FID C 8 3573
SNT TRC
FID C 3 5020
FID C 3 5021
FID C 3 5022
FID C 3 5023
FID C 3 5024
FID C 3 5025
FID C 3 5026
FID C 3 5027
FID C 3 5028
FID C 3 5029
FID C 3 5030
FID C 3 5031
FID C 3 5032
FID C 3 5033
# NET 358
NET FPGA_IN_MAC_PPS_OUTN ;1=7,3=0
SNT TOP T 170 462
FID C 4 1982
FID C 5 1189
FID C 3 5044
SNT TOP T 196 0
FID C 4 1983
FID C 5 1190
FID C 3 5059
SNT TOP T 250 0
FID C 4 1981
FID C 5 1188
FID C 3 5042
SNT TOP B 19 1
FID C 6 1356
FID C 7 483
FID C 8 3586
SNT TOP B 161 0
FID C 6 1354
FID C 7 482
FID C 8 3581
SNT VIA
FID H 0 1408
FID C 4 1980
FID C 6 1355
FID C 3 5041
FID C 10 3205
FID C 8 3582
FID L 11 1162
FID L 12 1162
FID L 13 1015
FID L 14 954
FID L 15 1162
FID L 16 1162
SNT VIA
FID H 0 2305
FID H 1 0
FID C 4 1979
FID C 6 1353
FID C 3 5035
FID C 10 3172
FID C 8 3575
FID L 11 1161
FID L 12 1161
FID L 13 1014
FID L 14 953
FID L 15 1161
FID L 16 1161
SNT VIA
FID H 0 2562
FID C 3 5043
FID C 10 3206
FID C 8 3583
FID L 11 1163
FID L 12 1163
FID L 13 1016
FID L 14 955
FID L 15 1163
FID L 16 1163
SNT TRC
FID C 10 3173
FID C 10 3174
FID C 10 3175
FID C 10 3176
FID C 10 3177
FID C 10 3178
FID C 10 3179
FID C 10 3180
FID C 10 3181
FID C 10 3182
FID C 10 3183
FID C 10 3184
FID C 10 3185
FID C 10 3186
FID C 10 3187
FID C 10 3188
FID C 10 3189
FID C 10 3190
FID C 10 3191
FID C 10 3192
FID C 10 3193
FID C 10 3194
FID C 10 3195
SNT TRC
FID C 8 3576
FID C 8 3577
FID C 8 3578
FID C 8 3579
FID C 8 3580
SNT TRC
FID C 10 3196
FID C 10 3197
FID C 10 3198
FID C 10 3199
FID C 10 3200
FID C 10 3201
FID C 10 3202
FID C 10 3203
FID C 10 3204
SNT TRC
FID C 3 5036
FID C 3 5037
FID C 3 5038
FID C 3 5039
FID C 3 5040
SNT TRC
FID C 3 5045
SNT TRC
FID C 8 3584
FID C 8 3585
SNT TRC
FID C 3 5046
FID C 3 5047
FID C 3 5048
FID C 3 5049
FID C 3 5050
FID C 3 5051
FID C 3 5052
FID C 3 5053
FID C 3 5054
FID C 3 5055
FID C 3 5056
FID C 3 5057
FID C 3 5058
# NET 359
NET FPGA_OUT_MAC_PPS_IN0P ;1=6,3=0
SNT TOP T 170 46
FID C 4 1941
FID C 5 1163
FID C 3 4901
SNT TOP T 367 0
FID C 4 1943
FID C 5 1165
FID C 3 4903
SNT TOP T 368 0
FID C 4 1942
FID C 5 1164
FID C 3 4902
SNT VIA
FID H 0 2308
FID H 1 3
FID C 4 1940
FID C 6 1322
FID C 3 4886
FID C 10 3029
FID C 8 3496
FID L 11 1134
FID L 12 1134
FID L 13 987
FID L 14 937
FID L 15 1134
FID L 16 1134
SNT VIA
FID H 0 2586
FID H 1 23
FID C 3 4899
FID C 10 3054
FID C 8 3497
FID L 11 1135
FID L 12 1135
FID L 13 988
FID L 14 938
FID L 15 1135
FID L 16 1135
SNT TRC
FID C 3 4887
FID C 3 4888
FID C 3 4889
FID C 3 4890
FID C 3 4891
FID C 3 4892
FID C 3 4893
FID C 3 4894
FID C 3 4895
FID C 3 4896
FID C 3 4897
FID C 3 4898
SNT TRC
FID C 10 3030
FID C 10 3031
FID C 10 3032
FID C 10 3033
FID C 10 3034
FID C 10 3035
FID C 10 3036
FID C 10 3037
FID C 10 3038
FID C 10 3039
FID C 10 3040
FID C 10 3041
FID C 10 3042
FID C 10 3043
FID C 10 3044
FID C 10 3045
FID C 10 3046
FID C 10 3047
FID C 10 3048
FID C 10 3049
FID C 10 3050
FID C 10 3051
FID C 10 3052
FID C 10 3053
SNT TRC
FID C 3 4900
SNT TRC
FID C 3 4904
FID C 3 4905
FID C 3 4906
FID C 3 4907
FID C 3 4908
# NET 360
NET FPGA_OUT_MAC_PPS_IN0N ;1=6,3=0
SNT TOP T 170 45
FID C 4 1945
FID C 5 1166
FID C 3 4945
SNT TOP T 368 1
FID C 4 1946
FID C 5 1167
FID C 3 4946
SNT TOP T 369 0
FID C 4 1947
FID C 5 1168
FID C 3 4947
SNT VIA
FID H 0 2307
FID H 1 2
FID C 4 1944
FID C 6 1323
FID C 3 4909
FID C 10 3055
FID C 8 3498
FID L 11 1136
FID L 12 1136
FID L 13 989
FID L 14 939
FID L 15 1136
FID L 16 1136
SNT VIA
FID H 0 2585
FID H 1 22
FID C 3 4943
FID C 10 3097
FID C 8 3499
FID L 11 1137
FID L 12 1137
FID L 13 990
FID L 14 940
FID L 15 1137
FID L 16 1137
SNT TRC
FID C 3 4910
FID C 3 4911
FID C 3 4912
FID C 3 4913
FID C 3 4914
FID C 3 4915
FID C 3 4916
FID C 3 4917
FID C 3 4918
FID C 3 4919
FID C 3 4920
FID C 3 4921
FID C 3 4922
FID C 3 4923
FID C 3 4924
FID C 3 4925
FID C 3 4926
FID C 3 4927
FID C 3 4928
FID C 3 4929
FID C 3 4930
FID C 3 4931
FID C 3 4932
FID C 3 4933
FID C 3 4934
FID C 3 4935
FID C 3 4936
FID C 3 4937
FID C 3 4938
FID C 3 4939
FID C 3 4940
FID C 3 4941
FID C 3 4942
SNT TRC
FID C 10 3056
FID C 10 3057
FID C 10 3058
FID C 10 3059
FID C 10 3060
FID C 10 3061
FID C 10 3062
FID C 10 3063
FID C 10 3064
FID C 10 3065
FID C 10 3066
FID C 10 3067
FID C 10 3068
FID C 10 3069
FID C 10 3070
FID C 10 3071
FID C 10 3072
FID C 10 3073
FID C 10 3074
FID C 10 3075
FID C 10 3076
FID C 10 3077
FID C 10 3078
FID C 10 3079
FID C 10 3080
FID C 10 3081
FID C 10 3082
FID C 10 3083
FID C 10 3084
FID C 10 3085
FID C 10 3086
FID C 10 3087
FID C 10 3088
FID C 10 3089
FID C 10 3090
FID C 10 3091
FID C 10 3092
FID C 10 3093
FID C 10 3094
FID C 10 3095
FID C 10 3096
SNT TRC
FID C 3 4944
SNT TRC
FID C 3 4948
FID C 3 4949
FID C 3 4950
FID C 3 4951
FID C 3 4952
# NET 361
NET FPGA_OUT_MAC_PPS_IN1P ;1=5,3=0
SNT TOP T 170 26
FID C 4 1933
FID C 5 1157
FID C 3 4856
SNT TOP T 364 0
FID C 4 1935
FID C 5 1159
FID C 3 4858
SNT TOP T 365 0
FID C 4 1934
FID C 5 1158
FID C 3 4857
SNT VIA
FID H 0 2310
FID H 1 5
FID C 4 1932
FID C 6 1320
FID C 3 4841
FID C 10 2955
FID C 8 3492
FID L 11 1130
FID L 12 1130
FID L 13 983
FID L 14 933
FID L 15 1130
FID L 16 1130
SNT VIA
FID H 0 2588
FID H 1 25
FID C 3 4854
FID C 10 3003
FID C 8 3493
FID L 11 1131
FID L 12 1131
FID L 13 984
FID L 14 934
FID L 15 1131
FID L 16 1131
SNT TRC
FID C 10 2956
FID C 10 2957
FID C 10 2958
FID C 10 2959
FID C 10 2960
FID C 10 2961
FID C 10 2962
FID C 10 2963
FID C 10 2964
FID C 10 2965
FID C 10 2966
FID C 10 2967
FID C 10 2968
FID C 10 2969
FID C 10 2970
FID C 10 2971
FID C 10 2972
FID C 10 2973
FID C 10 2974
FID C 10 2975
FID C 10 2976
FID C 10 2977
FID C 10 2978
FID C 10 2979
FID C 10 2980
FID C 10 2981
FID C 10 2982
FID C 10 2983
FID C 10 2984
FID C 10 2985
FID C 10 2986
FID C 10 2987
FID C 10 2988
FID C 10 2989
FID C 10 2990
FID C 10 2991
FID C 10 2992
FID C 10 2993
FID C 10 2994
FID C 10 2995
FID C 10 2996
FID C 10 2997
FID C 10 2998
FID C 10 2999
FID C 10 3000
FID C 10 3001
FID C 10 3002
SNT TRC
FID C 3 4842
FID C 3 4843
FID C 3 4844
FID C 3 4845
FID C 3 4846
FID C 3 4847
FID C 3 4848
FID C 3 4849
FID C 3 4850
FID C 3 4851
FID C 3 4852
FID C 3 4853
SNT TRC
FID C 3 4855
SNT TRC
FID C 3 4859
FID C 3 4860
FID C 3 4861
FID C 3 4862
FID C 3 4863
# NET 362
NET FPGA_OUT_MAC_PPS_IN1N ;1=5,3=0
SNT TOP T 170 48
FID C 4 1937
FID C 5 1160
FID C 3 4878
SNT TOP T 365 1
FID C 4 1938
FID C 5 1161
FID C 3 4879
SNT TOP T 366 0
FID C 4 1939
FID C 5 1162
FID C 3 4880
SNT VIA
FID H 0 2309
FID H 1 4
FID C 4 1936
FID C 6 1321
FID C 3 4864
FID C 10 3004
FID C 8 3494
FID L 11 1132
FID L 12 1132
FID L 13 985
FID L 14 935
FID L 15 1132
FID L 16 1132
SNT VIA
FID H 0 2587
FID H 1 24
FID C 3 4876
FID C 10 3028
FID C 8 3495
FID L 11 1133
FID L 12 1133
FID L 13 986
FID L 14 936
FID L 15 1133
FID L 16 1133
SNT TRC
FID C 10 3005
FID C 10 3006
FID C 10 3007
FID C 10 3008
FID C 10 3009
FID C 10 3010
FID C 10 3011
FID C 10 3012
FID C 10 3013
FID C 10 3014
FID C 10 3015
FID C 10 3016
FID C 10 3017
FID C 10 3018
FID C 10 3019
FID C 10 3020
FID C 10 3021
FID C 10 3022
FID C 10 3023
FID C 10 3024
FID C 10 3025
FID C 10 3026
FID C 10 3027
SNT TRC
FID C 3 4865
FID C 3 4866
FID C 3 4867
FID C 3 4868
FID C 3 4869
FID C 3 4870
FID C 3 4871
FID C 3 4872
FID C 3 4873
FID C 3 4874
FID C 3 4875
SNT TRC
FID C 3 4877
SNT TRC
FID C 3 4881
FID C 3 4882
FID C 3 4883
FID C 3 4884
FID C 3 4885
# NET 363
NET ICP10100_I2C_SDA 
SNT TOP T 187 5
FID C 4 3876
FID C 5 1846
FID C 3 8400
SNT TOP T 604 8
FID C 4 3879
FID C 5 1847
FID C 3 8403
SNT TOP B 201 1
FID C 6 3012
FID C 7 863
FID C 8 6333
SNT TOP B 206 0
FID C 6 3010
FID C 7 862
FID C 8 6330
SNT VIA
FID H 0 314
FID C 4 3878
FID C 6 3011
FID C 3 8402
FID C 8 6332
FID L 11 1512
FID L 12 1512
FID L 13 2289
FID L 14 2288
FID L 15 1512
FID L 16 1512
SNT VIA
FID H 0 2163
FID C 4 3877
FID C 6 3009
FID C 3 8401
FID C 8 6327
FID L 11 1511
FID L 12 1511
FID L 13 2288
FID L 14 2287
FID L 15 1511
FID L 16 1511
SNT TRC
FID C 8 6304
FID C 8 6305
FID C 8 6306
FID C 8 6307
FID C 8 6308
FID C 8 6309
FID C 8 6310
FID C 8 6311
FID C 8 6312
FID C 8 6313
FID C 8 6314
FID C 8 6315
FID C 8 6316
FID C 8 6317
FID C 8 6318
FID C 8 6319
FID C 8 6320
FID C 8 6321
FID C 8 6322
FID C 8 6323
FID C 8 6324
FID C 8 6325
FID C 8 6326
SNT TRC
FID C 3 8390
FID C 3 8391
FID C 3 8392
FID C 3 8393
FID C 3 8394
FID C 3 8395
FID C 3 8396
FID C 3 8397
SNT TRC
FID C 3 8398
FID C 3 8399
SNT TRC
FID C 8 6328
FID C 8 6329
SNT TRC
FID C 8 6331
# NET 364
NET ICP10100_I2C_SCL 
SNT TOP T 187 6
FID C 4 3880
FID C 5 1848
FID C 3 8414
SNT TOP T 604 9
FID C 4 3883
FID C 5 1849
FID C 3 8417
SNT TOP B 205 1
FID C 6 3016
FID C 7 865
FID C 8 6356
SNT TOP B 207 0
FID C 6 3015
FID C 7 864
FID C 8 6354
SNT VIA
FID H 0 313
FID C 4 3882
FID C 6 3014
FID C 3 8416
FID C 8 6353
FID L 11 1514
FID L 12 1514
FID L 13 2291
FID L 14 2290
FID L 15 1514
FID L 16 1514
SNT VIA
FID H 0 2162
FID C 4 3881
FID C 6 3013
FID C 3 8415
FID C 8 6349
FID L 11 1513
FID L 12 1513
FID L 13 2290
FID L 14 2289
FID L 15 1513
FID L 16 1513
SNT TRC
FID C 3 8404
FID C 3 8405
FID C 3 8406
FID C 3 8407
FID C 3 8408
FID C 3 8409
FID C 3 8410
FID C 3 8411
SNT TRC
FID C 8 6334
FID C 8 6335
FID C 8 6336
FID C 8 6337
FID C 8 6338
FID C 8 6339
FID C 8 6340
FID C 8 6341
FID C 8 6342
FID C 8 6343
FID C 8 6344
FID C 8 6345
FID C 8 6346
FID C 8 6347
FID C 8 6348
SNT TRC
FID C 3 8412
FID C 3 8413
SNT TRC
FID C 8 6350
FID C 8 6351
FID C 8 6352
SNT TRC
FID C 8 6355
# NET 365
NET FPGA_IO_2 
SNT TOP T 170 217
FID C 4 635
FID C 5 394
FID C 3 1698
SNT TOP T 255 1
FID C 4 634
FID C 5 393
FID C 3 1696
SNT TOP B 136 1
FID C 6 394
FID C 7 128
FID C 8 1076
SNT TOP B 144 1
FID C 6 390
FID C 7 127
FID C 8 1069
SNT VIA
FID H 0 237
FID C 4 633
FID C 6 393
FID C 3 1694
FID C 9 965
FID C 8 1074
FID L 11 416
FID L 12 416
FID L 13 400
FID L 14 365
FID L 15 416
FID L 16 416
SNT VIA
FID H 0 238
FID C 4 632
FID C 6 392
FID C 3 1693
FID C 10 504
FID C 8 1073
FID L 11 415
FID L 12 415
FID L 13 399
FID L 14 364
FID L 15 415
FID L 16 415
SNT VIA
FID H 0 1134
FID C 4 631
FID C 6 391
FID C 3 1692
FID C 10 503
FID C 8 1072
FID L 11 414
FID L 12 414
FID L 13 398
FID L 14 363
FID L 15 414
FID L 16 414
SNT VIA
FID H 0 2114
FID C 3 1697
FID C 9 966
FID C 8 1077
FID L 11 417
FID L 12 417
FID L 13 401
FID L 14 366
FID L 15 417
FID L 16 417
SNT TRC
FID C 10 493
FID C 10 494
FID C 10 495
FID C 10 496
FID C 10 497
FID C 10 498
FID C 10 499
FID C 10 500
FID C 10 501
FID C 10 502
SNT TRC
FID C 8 1046
FID C 8 1047
FID C 8 1048
FID C 8 1049
FID C 8 1050
FID C 8 1051
FID C 8 1052
FID C 8 1053
FID C 8 1054
FID C 8 1055
FID C 8 1056
FID C 8 1057
FID C 8 1058
FID C 8 1059
FID C 8 1060
FID C 8 1061
FID C 8 1062
FID C 8 1063
FID C 8 1064
FID C 8 1065
FID C 8 1066
FID C 8 1067
FID C 8 1068
SNT TRC
FID C 8 1070
FID C 8 1071
SNT TRC
FID C 9 960
FID C 9 961
FID C 9 962
FID C 9 963
FID C 9 964
SNT TRC
FID C 8 1075
SNT TRC
FID C 3 1695
SNT TRC
FID C 3 1699
# NET 366
NET FPGA_IO_3 
SNT TOP T 170 195
FID C 4 630
FID C 5 392
FID C 3 1690
SNT TOP T 254 1
FID C 4 628
FID C 5 391
FID C 3 1686
SNT TOP B 135 1
FID C 6 389
FID C 7 126
FID C 8 1044
SNT TOP B 145 1
FID C 6 386
FID C 7 125
FID C 8 1040
SNT VIA
FID H 0 239
FID C 4 629
FID C 6 388
FID C 3 1688
FID C 9 958
FID C 8 1043
FID L 11 412
FID L 12 412
FID L 13 396
FID L 14 361
FID L 15 412
FID L 16 412
SNT VIA
FID H 0 240
FID C 4 627
FID C 6 387
FID C 3 1685
FID C 10 492
FID C 8 1041
FID L 11 411
FID L 12 411
FID L 13 395
FID L 14 360
FID L 15 411
FID L 16 411
SNT VIA
FID H 0 1135
FID C 4 626
FID C 6 385
FID C 3 1684
FID C 10 491
FID C 8 1037
FID L 11 410
FID L 12 410
FID L 13 394
FID L 14 359
FID L 15 410
FID L 16 410
SNT VIA
FID H 0 2115
FID C 3 1689
FID C 9 959
FID C 8 1045
FID L 11 413
FID L 12 413
FID L 13 397
FID L 14 362
FID L 15 413
FID L 16 413
SNT TRC
FID C 10 478
FID C 10 479
FID C 10 480
FID C 10 481
FID C 10 482
FID C 10 483
FID C 10 484
FID C 10 485
FID C 10 486
FID C 10 487
FID C 10 488
FID C 10 489
FID C 10 490
SNT TRC
FID C 8 1018
FID C 8 1019
FID C 8 1020
FID C 8 1021
FID C 8 1022
FID C 8 1023
FID C 8 1024
FID C 8 1025
FID C 8 1026
FID C 8 1027
FID C 8 1028
FID C 8 1029
FID C 8 1030
FID C 8 1031
FID C 8 1032
FID C 8 1033
FID C 8 1034
FID C 8 1035
FID C 8 1036
SNT TRC
FID C 8 1038
FID C 8 1039
SNT TRC
FID C 9 953
FID C 9 954
FID C 9 955
FID C 9 956
FID C 9 957
SNT TRC
FID C 3 1687
SNT TRC
FID C 8 1042
SNT TRC
FID C 3 1691
# NET 367
NET FPGA_IN_MAC_ALARM_OUT_N 
SNT TOP T 170 53
FID C 4 1264
FID C 5 764
FID C 3 3291
SNT TOP T 197 1
FID C 4 1262
FID C 5 762
FID C 3 3286
SNT TOP T 198 0
FID C 4 1263
FID C 5 763
FID C 3 3288
SNT VIA
FID H 0 231
FID C 4 1265
FID C 6 763
FID C 3 3292
FID C 10 2321
FID C 8 2296
FID L 11 762
FID L 12 762
FID L 13 746
FID L 14 711
FID L 15 762
FID L 16 762
SNT VIA
FID H 0 1128
FID C 4 1261
FID C 6 762
FID C 3 3283
FID C 10 2311
FID C 8 2295
FID L 11 761
FID L 12 761
FID L 13 745
FID L 14 710
FID L 15 761
FID L 16 761
SNT TRC
FID C 3 3284
FID C 3 3285
SNT TRC
FID C 3 3287
SNT TRC
FID C 10 2312
FID C 10 2313
FID C 10 2314
FID C 10 2315
FID C 10 2316
FID C 10 2317
FID C 10 2318
FID C 10 2319
FID C 10 2320
SNT TRC
FID C 3 3289
FID C 3 3290
# NET 368
NET FPGA_IN_MAC_BITEOUT 
SNT TOP T 170 30
FID C 4 1260
FID C 5 761
FID C 3 3282
SNT TOP T 379 1
FID C 4 1259
FID C 5 760
FID C 3 3281
SNT TOP T 380 1
FID C 4 1258
FID C 5 759
FID C 3 3279
SNT VIA
FID H 0 2217
FID C 6 761
FID C 3 3278
FID C 8 2294
FID L 11 760
FID L 12 760
FID L 13 744
FID L 14 709
FID L 15 760
FID L 16 760
SNT TRC
FID C 3 3275
SNT TRC
FID C 3 3276
FID C 3 3277
SNT TRC
FID C 3 3280
# NET 369
NET FPGA_IN_BNO080_INT_N 
SNT TOP T 170 277
FID C 4 1277
FID C 5 771
FID C 3 3314
SNT TOP T 353 0
FID C 4 1276
FID C 5 770
FID C 3 3312
SNT TOP T 362 1
FID C 4 1275
FID C 5 769
FID C 3 3311
SNT VIA
FID H 0 227
FID C 4 1278
FID C 6 775
FID C 3 3317
FID C 9 1780
FID C 10 2410
FID C 8 2322
FID L 11 772
FID L 12 772
FID L 13 756
FID L 14 721
FID L 15 772
FID L 16 772
SNT VIA
FID H 0 228
FID C 4 1274
FID C 6 773
FID C 3 3309
FID C 9 1779
FID C 8 2320
FID L 11 770
FID L 12 770
FID L 13 754
FID L 14 719
FID L 15 770
FID L 16 770
SNT VIA
FID H 0 2575
FID C 6 774
FID C 3 3316
FID C 10 2409
FID C 8 2321
FID L 11 771
FID L 12 771
FID L 13 755
FID L 14 720
FID L 15 771
FID L 16 771
SNT TRC
FID C 10 2377
FID C 10 2378
FID C 10 2379
FID C 10 2380
FID C 10 2381
FID C 10 2382
FID C 10 2383
FID C 10 2384
FID C 10 2385
FID C 10 2386
FID C 10 2387
FID C 10 2388
FID C 10 2389
FID C 10 2390
FID C 10 2391
FID C 10 2392
FID C 10 2393
FID C 10 2394
FID C 10 2395
FID C 10 2396
FID C 10 2397
FID C 10 2398
FID C 10 2399
FID C 10 2400
FID C 10 2401
FID C 10 2402
FID C 10 2403
FID C 10 2404
FID C 10 2405
FID C 10 2406
FID C 10 2407
FID C 10 2408
SNT TRC
FID C 9 1774
FID C 9 1775
FID C 9 1776
FID C 9 1777
FID C 9 1778
SNT TRC
FID C 3 3310
SNT TRC
FID C 3 3313
SNT TRC
FID C 3 3315
# NET 370
NET XP5R0V_RT 
SNT TOP T 180 12
FID C 4 2021
FID C 5 1214
FID C 3 5137
SNT TOP T 345 0
FID C 4 2020
FID C 5 1213
FID C 3 5136
SNT VIA
FID H 0 1399
FID C 4 2019
FID C 6 1386
FID C 3 5135
FID C 8 3655
FID L 11 1184
FID L 12 1184
FID L 13 1037
FID L 14 976
FID L 15 1184
FID L 16 1184
SNT TRC
FID C 3 5129
FID C 3 5130
SNT TRC
FID C 3 5131
FID C 3 5132
FID C 3 5133
FID C 3 5134
# NET 371
NET BNO080_SA0 
SNT TOP T 149 16
FID C 4 1302
FID C 5 784
FID C 3 3494
SNT TOP T 363 0
FID C 4 1300
FID C 5 782
FID C 3 3492
SNT TOP T 370 1
FID C 4 1301
FID C 5 783
FID C 3 3493
SNT VIA
FID H 0 1100
FID C 4 1299
FID C 6 789
FID C 3 3487
FID C 8 2356
FID L 11 785
FID L 12 785
FID L 13 769
FID L 14 734
FID L 15 785
FID L 16 785
SNT TRC
FID C 3 3483
SNT TRC
FID C 3 3484
FID C 3 3485
FID C 3 3486
SNT TRC
FID C 3 3488
FID C 3 3489
FID C 3 3490
FID C 3 3491
# NET 372
NET R_BNO080_RST_N 
SNT TOP T 48 0
FID H 0 119
FID C 6 2928
FID C 3 8117
FID C 9 2431
FID C 8 5976
FID L 11 1444
FID L 12 1444
FID L 13 2221
FID L 14 2220
FID L 15 1444
FID L 16 1444
SNT TOP T 149 10
FID C 4 3791
FID C 5 1798
FID C 3 8124
SNT TOP T 352 1
FID C 4 3788
FID C 5 1795
FID C 3 8119
SNT TOP T 354 0
FID C 4 3789
FID C 5 1796
FID C 3 8121
SNT TOP T 355 0
FID C 4 3790
FID C 5 1797
FID C 3 8123
SNT VIA
FID H 0 2170
FID C 4 3787
FID C 6 2929
FID C 3 8118
FID C 9 2432
FID C 8 5977
FID L 11 1445
FID L 12 1445
FID L 13 2222
FID L 14 2221
FID L 15 1445
FID L 16 1445
SNT TRC
FID C 9 2424
FID C 9 2425
FID C 9 2426
FID C 9 2427
FID C 9 2428
FID C 9 2429
FID C 9 2430
SNT TRC
FID C 3 8112
FID C 3 8113
FID C 3 8114
SNT TRC
FID C 3 8115
FID C 3 8116
SNT TRC
FID C 3 8120
SNT TRC
FID C 3 8122
# NET 373
NET FPGA_IO_4 
SNT TOP T 170 262
FID C 4 624
FID C 5 390
FID C 3 1682
SNT TOP T 423 1
FID C 4 622
FID C 5 389
FID C 3 1679
SNT TOP B 146 0
FID C 6 383
FID C 7 124
FID C 8 1014
SNT TOP B 343 1
FID C 6 382
FID C 7 123
FID C 8 1013
SNT VIA
FID H 0 241
FID C 4 623
FID C 6 381
FID C 3 1681
FID C 8 1012
FID L 11 408
FID L 12 408
FID L 13 392
FID L 14 357
FID L 15 408
FID L 16 408
SNT VIA
FID H 0 1136
FID C 4 621
FID C 6 380
FID C 3 1671
FID C 9 951
FID C 8 1010
FID L 11 407
FID L 12 407
FID L 13 391
FID L 14 356
FID L 15 407
FID L 16 407
SNT VIA
FID H 0 1137
FID C 4 625
FID C 6 384
FID C 3 1683
FID C 9 952
FID C 8 1017
FID L 11 409
FID L 12 409
FID L 13 393
FID L 14 358
FID L 15 409
FID L 16 409
SNT TRC
FID C 8 987
FID C 8 988
FID C 8 989
FID C 8 990
FID C 8 991
FID C 8 992
FID C 8 993
FID C 8 994
FID C 8 995
FID C 8 996
FID C 8 997
FID C 8 998
FID C 8 999
FID C 8 1000
FID C 8 1001
FID C 8 1002
FID C 8 1003
FID C 8 1004
FID C 8 1005
FID C 8 1006
FID C 8 1007
FID C 8 1008
FID C 8 1009
SNT TRC
FID C 9 938
FID C 9 939
FID C 9 940
FID C 9 941
FID C 9 942
FID C 9 943
FID C 9 944
FID C 9 945
FID C 9 946
FID C 9 947
FID C 9 948
FID C 9 949
FID C 9 950
SNT TRC
FID C 3 1672
FID C 3 1673
FID C 3 1674
FID C 3 1675
FID C 3 1676
FID C 3 1677
FID C 3 1678
SNT TRC
FID C 3 1680
SNT TRC
FID C 8 1011
SNT TRC
FID C 8 1015
FID C 8 1016
# NET 374
NET R_SHT3X_RST_N 
SNT TOP T 38 0
FID H 0 149
FID C 6 719
FID C 3 3123
FID C 8 2171
FID L 11 707
FID L 12 707
FID L 13 691
FID L 14 656
FID L 15 707
FID L 16 707
SNT TOP T 142 5
FID C 4 1200
FID C 5 720
FID C 3 3117
SNT TOP T 415 0
FID C 4 1202
FID C 5 721
FID C 3 3127
SNT TOP T 416 0
FID C 4 1203
FID C 5 722
FID C 3 3129
SNT TOP T 417 1
FID C 4 1204
FID C 5 723
FID C 3 3130
SNT VIA
FID H 0 2261
FID C 4 1201
FID C 6 720
FID C 3 3125
FID C 8 2172
FID L 11 708
FID L 12 708
FID L 13 692
FID L 14 657
FID L 15 708
FID L 16 708
SNT TRC
FID C 3 3118
FID C 3 3119
FID C 3 3120
SNT TRC
FID C 3 3121
FID C 3 3122
SNT TRC
FID C 3 3124
SNT TRC
FID C 3 3126
SNT TRC
FID C 3 3128
# NET 375
NET FPGA_OUT_SHT3X_RST_N 
SNT TOP T 170 216
FID C 4 1237
FID C 5 748
FID C 3 3234
SNT TOP T 415 1
FID C 4 1240
FID C 5 749
FID C 3 3239
SNT VIA
FID H 0 266
FID C 4 1238
FID C 6 746
FID C 3 3236
FID C 9 1767
FID C 10 2179
FID C 8 2216
FID L 11 744
FID L 12 744
FID L 13 728
FID L 14 693
FID L 15 744
FID L 16 744
SNT VIA
FID H 0 2125
FID C 3 3233
FID C 9 1766
FID C 8 2215
FID L 11 743
FID L 12 743
FID L 13 727
FID L 14 692
FID L 15 743
FID L 16 743
SNT VIA
FID H 0 2233
FID C 4 1239
FID C 6 747
FID C 3 3237
FID C 10 2180
FID C 8 2217
FID L 11 745
FID L 12 745
FID L 13 729
FID L 14 694
FID L 15 745
FID L 16 745
SNT TRC
FID C 9 1737
FID C 9 1738
FID C 9 1739
FID C 9 1740
FID C 9 1741
FID C 9 1742
FID C 9 1743
FID C 9 1744
FID C 9 1745
FID C 9 1746
FID C 9 1747
FID C 9 1748
FID C 9 1749
FID C 9 1750
FID C 9 1751
FID C 9 1752
FID C 9 1753
FID C 9 1754
FID C 9 1755
FID C 9 1756
FID C 9 1757
FID C 9 1758
FID C 9 1759
FID C 9 1760
FID C 9 1761
FID C 9 1762
FID C 9 1763
FID C 9 1764
FID C 9 1765
SNT TRC
FID C 10 2173
FID C 10 2174
FID C 10 2175
FID C 10 2176
FID C 10 2177
FID C 10 2178
SNT TRC
FID C 3 3235
SNT TRC
FID C 3 3238
# NET 376
NET R_SHT3X_ALERT_N 
SNT TOP T 37 0
FID H 0 150
FID C 6 722
FID C 3 3138
FID C 9 1581
FID C 8 2174
FID L 11 710
FID L 12 710
FID L 13 694
FID L 14 659
FID L 15 710
FID L 16 710
SNT TOP T 142 2
FID C 4 1205
FID C 5 724
FID C 3 3131
SNT TOP T 418 0
FID C 4 1207
FID C 5 725
FID C 3 3137
SNT VIA
FID H 0 2258
FID C 4 1206
FID C 6 721
FID C 3 3136
FID C 9 1580
FID C 8 2173
FID L 11 709
FID L 12 709
FID L 13 693
FID L 14 658
FID L 15 709
FID L 16 709
SNT TRC
FID C 3 3132
FID C 3 3133
FID C 3 3134
SNT TRC
FID C 9 1578
FID C 9 1579
SNT TRC
FID C 3 3135
# NET 377
NET FPGA_IN_SHT3X_ALERT_N 
SNT TOP T 170 238
FID C 4 1255
FID C 5 757
FID C 3 3269
SNT TOP T 418 1
FID C 4 1254
FID C 5 756
FID C 3 3267
SNT TOP B 339 1
FID C 6 757
FID C 7 198
FID C 8 2282
SNT VIA
FID H 0 232
FID C 4 1252
FID C 6 755
FID C 3 3262
FID C 10 2278
FID C 8 2277
FID L 11 755
FID L 12 755
FID L 13 739
FID L 14 704
FID L 15 755
FID L 16 755
SNT VIA
FID H 0 1131
FID C 4 1253
FID C 6 756
FID C 3 3266
FID C 10 2279
FID C 8 2281
FID L 11 756
FID L 12 756
FID L 13 740
FID L 14 705
FID L 15 756
FID L 16 756
SNT VIA
FID H 0 2113
FID C 3 3268
FID C 8 2283
FID L 11 757
FID L 12 757
FID L 13 741
FID L 14 706
FID L 15 757
FID L 16 757
SNT TRC
FID C 8 2259
FID C 8 2260
FID C 8 2261
FID C 8 2262
FID C 8 2263
FID C 8 2264
FID C 8 2265
FID C 8 2266
FID C 8 2267
FID C 8 2268
FID C 8 2269
FID C 8 2270
FID C 8 2271
FID C 8 2272
FID C 8 2273
FID C 8 2274
FID C 8 2275
FID C 8 2276
SNT TRC
FID C 10 2266
FID C 10 2267
FID C 10 2268
FID C 10 2269
FID C 10 2270
FID C 10 2271
FID C 10 2272
FID C 10 2273
FID C 10 2274
FID C 10 2275
FID C 10 2276
FID C 10 2277
SNT TRC
FID C 3 3263
FID C 3 3264
FID C 3 3265
SNT TRC
FID C 8 2278
FID C 8 2279
FID C 8 2280
SNT TRC
FID C 3 3270
# NET 378
NET UNNAMED_9_BNO080LGA28_I29_PS1 
SNT TOP T 149 4
FID C 4 1161
FID C 5 694
FID C 3 3017
SNT TOP T 424 0
FID C 4 1160
FID C 5 693
FID C 3 3016
SNT VIA
FID H 0 2192
FID C 4 1159
FID C 6 697
FID C 3 3008
FID C 8 2134
FID L 11 692
FID L 12 692
FID L 13 676
FID L 14 641
FID L 15 692
FID L 16 692
SNT TRC
FID C 3 3009
FID C 3 3010
FID C 3 3011
FID C 3 3012
SNT TRC
FID C 3 3013
FID C 3 3014
FID C 3 3015
# NET 379
NET R_BNO080_BOOT_N 
SNT TOP T 46 0
FID H 0 121
FID C 6 2932
FID C 3 8134
FID C 9 2448
FID C 8 5980
FID L 11 1448
FID L 12 1448
FID L 13 2225
FID L 14 2224
FID L 15 1448
FID L 16 1448
SNT TOP T 149 3
FID C 4 3797
FID C 5 1802
FID C 3 8143
SNT TOP T 425 1
FID C 4 3796
FID C 5 1801
FID C 3 8142
SNT TOP B 347 1
FID C 6 2934
FID C 7 849
FID C 8 5985
SNT VIA
FID H 0 2167
FID C 4 3795
FID C 6 2933
FID C 3 8135
FID C 9 2449
FID C 8 5981
FID L 11 1449
FID L 12 1449
FID L 13 2226
FID L 14 2225
FID L 15 1449
FID L 16 1449
SNT TRC
FID C 9 2444
FID C 9 2445
FID C 9 2446
FID C 9 2447
SNT TRC
FID C 3 8136
FID C 3 8137
FID C 3 8138
SNT TRC
FID C 3 8139
FID C 3 8140
FID C 3 8141
SNT TRC
FID C 8 5982
FID C 8 5983
FID C 8 5984
# NET 380
NET UNNAMED_9_BNO080LGA28_I29_PS0 
SNT TOP T 149 5
FID C 4 1164
FID C 5 696
FID C 3 3026
SNT TOP T 384 0
FID C 4 1163
FID C 5 695
FID C 3 3025
SNT VIA
FID H 0 2191
FID C 4 1162
FID C 6 698
FID C 3 3018
FID C 8 2135
FID L 11 693
FID L 12 693
FID L 13 677
FID L 14 642
FID L 15 693
FID L 16 693
SNT TRC
FID C 3 3019
FID C 3 3020
FID C 3 3021
FID C 3 3022
SNT TRC
FID C 3 3023
FID C 3 3024
# NET 381
NET UNNAMED_9_BNO080LGA28_I29_CLKSE 
SNT TOP T 149 9
FID C 4 1167
FID C 5 698
FID C 3 3038
SNT TOP T 351 1
FID C 4 1169
FID C 5 700
FID C 3 3041
SNT TOP T 356 0
FID C 4 1168
FID C 5 699
FID C 3 3039
SNT VIA
FID H 0 2190
FID C 4 1166
FID C 6 700
FID C 3 3037
FID C 8 2137
FID L 11 695
FID L 12 695
FID L 13 679
FID L 14 644
FID L 15 695
FID L 16 695
SNT TRC
FID C 3 3032
FID C 3 3033
FID C 3 3034
SNT TRC
FID C 3 3035
FID C 3 3036
SNT TRC
FID C 3 3040
# NET 382
NET FPGA_IO_5 
SNT TOP T 170 263
FID C 4 619
FID C 5 388
FID C 3 1669
SNT TOP T 253 1
FID C 4 617
FID C 5 387
FID C 3 1666
SNT TOP B 134 1
FID C 6 377
FID C 7 121
FID C 8 982
SNT TOP B 147 0
FID C 6 378
FID C 7 122
FID C 8 983
SNT VIA
FID H 0 242
FID C 4 618
FID C 6 376
FID C 3 1668
FID C 8 981
FID L 11 405
FID L 12 405
FID L 13 389
FID L 14 354
FID L 15 405
FID L 16 405
SNT VIA
FID H 0 243
FID C 4 616
FID C 6 375
FID C 3 1659
FID C 9 936
FID C 8 979
FID L 11 404
FID L 12 404
FID L 13 388
FID L 14 353
FID L 15 404
FID L 16 404
SNT VIA
FID H 0 1138
FID C 4 620
FID C 6 379
FID C 3 1670
FID C 9 937
FID C 8 986
FID L 11 406
FID L 12 406
FID L 13 390
FID L 14 355
FID L 15 406
FID L 16 406
SNT TRC
FID C 8 957
FID C 8 958
FID C 8 959
FID C 8 960
FID C 8 961
FID C 8 962
FID C 8 963
FID C 8 964
FID C 8 965
FID C 8 966
FID C 8 967
FID C 8 968
FID C 8 969
FID C 8 970
FID C 8 971
FID C 8 972
FID C 8 973
FID C 8 974
FID C 8 975
FID C 8 976
FID C 8 977
FID C 8 978
SNT TRC
FID C 9 924
FID C 9 925
FID C 9 926
FID C 9 927
FID C 9 928
FID C 9 929
FID C 9 930
FID C 9 931
FID C 9 932
FID C 9 933
FID C 9 934
FID C 9 935
SNT TRC
FID C 3 1660
FID C 3 1661
FID C 3 1662
FID C 3 1663
FID C 3 1664
FID C 3 1665
SNT TRC
FID C 3 1667
SNT TRC
FID C 8 980
SNT TRC
FID C 8 984
FID C 8 985
# NET 383
NET XP5R0V_BT 
SNT TOP T 180 0
FID C 4 2034
FID C 5 1223
FID C 3 5174
SNT TOP B 163 0
FID C 6 1394
FID C 7 501
FID C 8 3671
SNT VIA
FID H 0 1396
FID C 4 2033
FID C 6 1395
FID C 3 5173
FID C 8 3674
FID L 11 1188
FID L 12 1188
FID L 13 1041
FID L 14 980
FID L 15 1188
FID L 16 1188
SNT TRC
FID C 8 3672
FID C 8 3673
SNT TRC
FID C 3 5170
FID C 3 5171
FID C 3 5172
# NET 384
NET RGB_LED_I2C_SDA 
SNT TOP T 212 0
FID C 4 798
FID C 5 493
FID C 3 2139
SNT TOP T 330 0
FID C 4 804
FID C 5 495
FID C 3 2150
SNT TOP T 388 0
FID C 4 801
FID C 5 494
FID C 3 2147
SNT VIA
FID H 0 341
FID C 4 802
FID C 6 488
FID C 3 2148
FID C 9 991
FID C 10 802
FID C 8 1390
FID L 11 486
FID L 12 486
FID L 13 470
FID L 14 435
FID L 15 486
FID L 16 486
SNT VIA
FID H 0 1201
FID C 4 797
FID C 6 485
FID C 3 2138
FID C 8 1387
FID L 11 483
FID L 12 483
FID L 13 467
FID L 14 432
FID L 15 483
FID L 16 483
SNT VIA
FID H 0 1423
FID C 4 799
FID C 6 486
FID C 3 2142
FID C 9 990
FID C 8 1388
FID L 11 484
FID L 12 484
FID L 13 468
FID L 14 433
FID L 15 484
FID L 16 484
SNT VIA
FID H 0 1424
FID C 4 800
FID C 6 487
FID C 3 2146
FID C 8 1389
FID L 11 485
FID L 12 485
FID L 13 469
FID L 14 434
FID L 15 485
FID L 16 485
SNT VIA
FID H 0 2252
FID C 4 803
FID C 6 489
FID C 3 2149
FID C 10 803
FID C 8 1391
FID L 11 487
FID L 12 487
FID L 13 471
FID L 14 436
FID L 15 487
FID L 16 487
SNT TRC
FID C 10 794
FID C 10 795
FID C 10 796
FID C 10 797
FID C 10 798
FID C 10 799
FID C 10 800
FID C 10 801
SNT TRC
FID C 8 1358
FID C 8 1359
FID C 8 1360
FID C 8 1361
FID C 8 1362
FID C 8 1363
FID C 8 1364
FID C 8 1365
FID C 8 1366
FID C 8 1367
FID C 8 1368
FID C 8 1369
FID C 8 1370
FID C 8 1371
FID C 8 1372
SNT TRC
FID C 9 983
FID C 9 984
FID C 9 985
FID C 9 986
FID C 9 987
FID C 9 988
FID C 9 989
SNT TRC
FID C 8 1373
FID C 8 1374
FID C 8 1375
FID C 8 1376
FID C 8 1377
FID C 8 1378
FID C 8 1379
FID C 8 1380
FID C 8 1381
FID C 8 1382
FID C 8 1383
FID C 8 1384
FID C 8 1385
FID C 8 1386
SNT TRC
FID C 3 2133
FID C 3 2134
FID C 3 2135
FID C 3 2136
FID C 3 2137
SNT TRC
FID C 3 2140
FID C 3 2141
SNT TRC
FID C 3 2143
FID C 3 2144
FID C 3 2145
# NET 385
NET RGB_LED_I2C_SCL 
SNT TOP T 211 0
FID C 4 806
FID C 5 496
FID C 3 2155
SNT TOP T 327 0
FID C 4 811
FID C 5 498
FID C 3 2163
SNT TOP T 387 0
FID C 4 809
FID C 5 497
FID C 3 2161
SNT VIA
FID H 0 340
FID C 4 810
FID C 6 493
FID C 3 2162
FID C 9 1001
FID C 10 850
FID C 8 1437
FID L 11 491
FID L 12 491
FID L 13 475
FID L 14 440
FID L 15 491
FID L 16 491
SNT VIA
FID H 0 1200
FID C 4 805
FID C 6 490
FID C 3 2154
FID C 8 1434
FID L 11 488
FID L 12 488
FID L 13 472
FID L 14 437
FID L 15 488
FID L 16 488
SNT VIA
FID H 0 1421
FID C 4 807
FID C 6 491
FID C 3 2158
FID C 9 1000
FID C 8 1435
FID L 11 489
FID L 12 489
FID L 13 473
FID L 14 438
FID L 15 489
FID L 16 489
SNT VIA
FID H 0 1422
FID C 4 808
FID C 6 492
FID C 3 2160
FID C 8 1436
FID L 11 490
FID L 12 490
FID L 13 474
FID L 14 439
FID L 15 490
FID L 16 490
SNT VIA
FID H 0 2251
FID C 4 812
FID C 6 494
FID C 3 2164
FID C 10 851
FID C 8 1438
FID L 11 492
FID L 12 492
FID L 13 476
FID L 14 441
FID L 15 492
FID L 16 492
SNT TRC
FID C 8 1392
FID C 8 1393
FID C 8 1394
FID C 8 1395
FID C 8 1396
FID C 8 1397
FID C 8 1398
FID C 8 1399
FID C 8 1400
FID C 8 1401
FID C 8 1402
FID C 8 1403
FID C 8 1404
FID C 8 1405
FID C 8 1406
FID C 8 1407
FID C 8 1408
FID C 8 1409
FID C 8 1410
FID C 8 1411
FID C 8 1412
FID C 8 1413
FID C 8 1414
FID C 8 1415
FID C 8 1416
FID C 8 1417
FID C 8 1418
FID C 8 1419
FID C 8 1420
SNT TRC
FID C 10 804
FID C 10 805
FID C 10 806
FID C 10 807
FID C 10 808
FID C 10 809
FID C 10 810
FID C 10 811
FID C 10 812
FID C 10 813
FID C 10 814
FID C 10 815
FID C 10 816
FID C 10 817
FID C 10 818
FID C 10 819
FID C 10 820
FID C 10 821
FID C 10 822
FID C 10 823
FID C 10 824
FID C 10 825
FID C 10 826
FID C 10 827
FID C 10 828
FID C 10 829
FID C 10 830
FID C 10 831
FID C 10 832
FID C 10 833
FID C 10 834
FID C 10 835
FID C 10 836
FID C 10 837
FID C 10 838
FID C 10 839
FID C 10 840
FID C 10 841
FID C 10 842
FID C 10 843
FID C 10 844
FID C 10 845
FID C 10 846
FID C 10 847
FID C 10 848
FID C 10 849
SNT TRC
FID C 8 1421
FID C 8 1422
FID C 8 1423
FID C 8 1424
FID C 8 1425
FID C 8 1426
FID C 8 1427
FID C 8 1428
FID C 8 1429
FID C 8 1430
FID C 8 1431
FID C 8 1432
FID C 8 1433
SNT TRC
FID C 9 992
FID C 9 993
FID C 9 994
FID C 9 995
FID C 9 996
FID C 9 997
FID C 9 998
FID C 9 999
SNT TRC
FID C 3 2151
FID C 3 2152
FID C 3 2153
SNT TRC
FID C 3 2156
FID C 3 2157
SNT TRC
FID C 3 2159
# NET 386
NET UNNAMED_8_PCA9508DPTSSOP8_I51_E 
SNT TOP T 187 4
FID C 4 790
FID C 5 488
FID C 3 2119
SNT TOP B 202 1
FID C 6 482
FID C 7 153
FID C 8 1355
SNT VIA
FID H 0 2188
FID C 4 789
FID C 6 481
FID C 3 2116
FID C 8 1353
FID L 11 480
FID L 12 480
FID L 13 464
FID L 14 429
FID L 15 480
FID L 16 480
SNT TRC
FID C 3 2117
FID C 3 2118
SNT TRC
FID C 8 1354
# NET 387
NET BF_ICP10100_I2C_SCL 
SNT TOP T 187 1
FID C 4 830
FID C 5 507
FID C 3 2200
SNT TOP T 339 1
FID C 4 826
FID C 5 505
FID C 3 2193
SNT TOP T 340 0
FID C 4 827
FID C 5 506
FID C 3 2194
SNT TOP B 207 1
FID C 6 508
FID C 7 158
FID C 8 1481
SNT VIA
FID H 0 1404
FID C 4 828
FID C 6 507
FID C 3 2195
FID C 10 944
FID C 8 1477
FID L 11 503
FID L 12 503
FID L 13 487
FID L 14 452
FID L 15 503
FID L 16 503
SNT VIA
FID H 0 2151
FID C 4 829
FID C 6 509
FID C 3 2196
FID C 10 945
FID C 8 1482
FID L 11 504
FID L 12 504
FID L 13 488
FID L 14 453
FID L 15 504
FID L 16 504
SNT TRC
FID C 10 931
FID C 10 932
FID C 10 933
FID C 10 934
FID C 10 935
FID C 10 936
FID C 10 937
FID C 10 938
FID C 10 939
FID C 10 940
FID C 10 941
FID C 10 942
FID C 10 943
SNT TRC
FID C 3 2189
FID C 3 2190
SNT TRC
FID C 3 2191
FID C 3 2192
SNT TRC
FID C 8 1478
FID C 8 1479
FID C 8 1480
SNT TRC
FID C 3 2197
FID C 3 2198
FID C 3 2199
# NET 388
NET BF_ICP10100_I2C_SDA 
SNT TOP T 187 2
FID C 4 822
FID C 5 502
FID C 3 2184
SNT TOP T 304 1
FID C 4 825
FID C 5 504
FID C 3 2188
SNT TOP T 305 0
FID C 4 824
FID C 5 503
FID C 3 2186
SNT TOP B 206 1
FID C 6 505
FID C 7 157
FID C 8 1475
SNT VIA
FID H 0 1405
FID C 4 821
FID C 6 504
FID C 3 2181
FID C 10 929
FID C 8 1470
FID L 11 501
FID L 12 501
FID L 13 485
FID L 14 450
FID L 15 501
FID L 16 501
SNT VIA
FID H 0 2152
FID C 4 823
FID C 6 506
FID C 3 2185
FID C 10 930
FID C 8 1476
FID L 11 502
FID L 12 502
FID L 13 486
FID L 14 451
FID L 15 502
FID L 16 502
SNT TRC
FID C 10 923
FID C 10 924
FID C 10 925
FID C 10 926
FID C 10 927
FID C 10 928
SNT TRC
FID C 3 2179
FID C 3 2180
SNT TRC
FID C 3 2182
FID C 3 2183
SNT TRC
FID C 8 1471
FID C 8 1472
FID C 8 1473
FID C 8 1474
SNT TRC
FID C 3 2187
# NET 389
NET R_RGB_LED_I2C_SDA 
SNT TOP T 120 5
FID C 4 0
FID C 5 0
FID C 3 4
SNT TOP T 212 1
FID C 4 2
FID C 5 1
FID C 3 7
SNT TOP B 296 1
FID C 6 0
FID C 7 0
FID C 8 1
SNT TOP B 297 1
FID C 6 1
FID C 7 1
FID C 8 3
SNT VIA
FID H 0 1222
FID C 4 1
FID C 6 2
FID C 3 6
FID C 8 5
FID L 11 2
FID L 12 2
FID L 13 2
FID L 14 2
FID L 15 2
FID L 16 2
SNT TRC
FID C 3 1
FID C 3 2
FID C 3 3
SNT TRC
FID C 8 2
SNT TRC
FID C 8 4
SNT TRC
FID C 3 5
# NET 390
NET R_RGB_LED_I2C_SCL 
SNT TOP T 120 6
FID C 4 3
FID C 5 2
FID C 3 8
SNT TOP T 211 1
FID C 4 5
FID C 5 3
FID C 3 15
SNT TOP B 295 1
FID C 6 3
FID C 7 2
FID C 8 6
SNT TOP B 298 1
FID C 6 4
FID C 7 3
FID C 8 8
SNT VIA
FID H 0 1221
FID C 4 4
FID C 6 5
FID C 3 14
FID C 8 10
FID L 11 3
FID L 12 3
FID L 13 3
FID L 14 3
FID L 15 3
FID L 16 3
SNT TRC
FID C 8 7
SNT TRC
FID C 8 9
SNT TRC
FID C 3 9
FID C 3 10
FID C 3 11
FID C 3 12
SNT TRC
FID C 3 13
# NET 391
NET FPGA_OUT_RGB_LED_SHUTDOWN_N 
SNT TOP T 170 479
FID C 4 813
FID C 5 499
FID C 3 2165
SNT TOP B 264 0
FID C 6 497
FID C 7 154
FID C 8 1447
SNT VIA
FID H 0 265
FID C 4 814
FID C 6 496
FID C 3 2168
FID C 10 874
FID C 8 1446
FID L 11 494
FID L 12 494
FID L 13 478
FID L 14 443
FID L 15 494
FID L 16 494
SNT VIA
FID H 0 2220
FID C 6 495
FID C 3 2167
FID C 10 873
FID C 8 1445
FID L 11 493
FID L 12 493
FID L 13 477
FID L 14 442
FID L 15 493
FID L 16 493
SNT TRC
FID C 10 852
FID C 10 853
FID C 10 854
FID C 10 855
FID C 10 856
FID C 10 857
FID C 10 858
FID C 10 859
FID C 10 860
FID C 10 861
FID C 10 862
FID C 10 863
FID C 10 864
FID C 10 865
FID C 10 866
FID C 10 867
FID C 10 868
FID C 10 869
FID C 10 870
FID C 10 871
FID C 10 872
SNT TRC
FID C 8 1439
FID C 8 1440
FID C 8 1441
FID C 8 1442
FID C 8 1443
FID C 8 1444
SNT TRC
FID C 3 2166
# NET 392
NET FPGA_M_RGB_LED_I2C_SDA 
SNT TOP T 170 458
FID C 4 817
FID C 5 500
FID C 3 2173
SNT TOP B 297 0
FID C 6 498
FID C 7 155
FID C 8 1455
SNT VIA
FID H 0 1411
FID C 4 816
FID C 6 500
FID C 3 2171
FID C 10 896
FID C 8 1459
FID L 11 497
FID L 12 497
FID L 13 481
FID L 14 446
FID L 15 497
FID L 16 497
SNT VIA
FID H 0 2119
FID C 3 2170
FID C 10 895
FID C 8 1458
FID L 11 496
FID L 12 496
FID L 13 480
FID L 14 445
FID L 15 496
FID L 16 496
SNT VIA
FID H 0 2157
FID C 4 815
FID C 6 499
FID C 3 2169
FID C 8 1457
FID L 11 495
FID L 12 495
FID L 13 479
FID L 14 444
FID L 15 495
FID L 16 495
SNT TRC
FID C 10 875
FID C 10 876
FID C 10 877
FID C 10 878
FID C 10 879
FID C 10 880
FID C 10 881
FID C 10 882
FID C 10 883
FID C 10 884
FID C 10 885
FID C 10 886
FID C 10 887
FID C 10 888
FID C 10 889
FID C 10 890
FID C 10 891
FID C 10 892
FID C 10 893
FID C 10 894
SNT TRC
FID C 8 1448
FID C 8 1449
FID C 8 1450
FID C 8 1451
FID C 8 1452
FID C 8 1453
FID C 8 1454
SNT TRC
FID C 8 1456
SNT TRC
FID C 3 2172
# NET 393
NET FPGA_M_RGB_LED_I2C_SCL 
SNT TOP T 170 459
FID C 4 820
FID C 5 501
FID C 3 2178
SNT TOP B 298 0
FID C 6 501
FID C 7 156
FID C 8 1465
SNT VIA
FID H 0 1410
FID C 4 819
FID C 6 503
FID C 3 2176
FID C 10 922
FID C 8 1469
FID L 11 500
FID L 12 500
FID L 13 484
FID L 14 449
FID L 15 500
FID L 16 500
SNT VIA
FID H 0 2118
FID C 3 2175
FID C 10 921
FID C 8 1468
FID L 11 499
FID L 12 499
FID L 13 483
FID L 14 448
FID L 15 499
FID L 16 499
SNT VIA
FID H 0 2156
FID C 4 818
FID C 6 502
FID C 3 2174
FID C 8 1467
FID L 11 498
FID L 12 498
FID L 13 482
FID L 14 447
FID L 15 498
FID L 16 498
SNT TRC
FID C 10 897
FID C 10 898
FID C 10 899
FID C 10 900
FID C 10 901
FID C 10 902
FID C 10 903
FID C 10 904
FID C 10 905
FID C 10 906
FID C 10 907
FID C 10 908
FID C 10 909
FID C 10 910
FID C 10 911
FID C 10 912
FID C 10 913
FID C 10 914
FID C 10 915
FID C 10 916
FID C 10 917
FID C 10 918
FID C 10 919
FID C 10 920
SNT TRC
FID C 8 1460
FID C 8 1461
FID C 8 1462
FID C 8 1463
FID C 8 1464
SNT TRC
FID C 8 1466
SNT TRC
FID C 3 2177
# NET 394
NET UNNAMED_14_IS32FL3207QWLA3TRQ_1 
SNT TOP T 120 4
FID C 4 791
FID C 5 489
FID C 3 2120
SNT TOP T 402 0
FID C 4 793
FID C 5 490
FID C 3 2125
SNT VIA
FID H 0 2179
FID C 4 792
FID C 6 483
FID C 3 2121
FID C 8 1356
FID L 11 481
FID L 12 481
FID L 13 465
FID L 14 430
FID L 15 481
FID L 16 481
SNT TRC
FID C 3 2122
SNT TRC
FID C 3 2123
FID C 3 2124
# NET 395
NET UNNAMED_14_IS32FL3207QWLA3TRQFN 
SNT TOP T 120 1
FID C 4 794
FID C 5 491
FID C 3 2126
SNT TOP T 401 1
FID C 4 796
FID C 5 492
FID C 3 2132
SNT VIA
FID H 0 2178
FID C 4 795
FID C 6 484
FID C 3 2127
FID C 8 1357
FID L 11 482
FID L 12 482
FID L 13 466
FID L 14 431
FID L 15 482
FID L 16 482
SNT TRC
FID C 3 2128
FID C 3 2129
SNT TRC
FID C 3 2130
FID C 3 2131
# NET 396
NET FPGA_IO_6 
SNT TOP T 170 306
FID C 4 614
FID C 5 386
FID C 3 1657
SNT TOP T 252 1
FID C 4 612
FID C 5 385
FID C 3 1653
SNT TOP B 133 1
FID C 6 372
FID C 7 119
FID C 8 951
SNT TOP B 148 0
FID C 6 374
FID C 7 120
FID C 8 956
SNT VIA
FID H 0 244
FID C 4 613
FID C 6 371
FID C 3 1654
FID C 9 921
FID C 8 950
FID L 11 401
FID L 12 401
FID L 13 385
FID L 14 350
FID L 15 401
FID L 16 401
SNT VIA
FID H 0 245
FID C 4 611
FID C 6 370
FID C 3 1651
FID C 9 920
FID C 8 948
FID L 11 400
FID L 12 400
FID L 13 384
FID L 14 349
FID L 15 400
FID L 16 400
SNT VIA
FID H 0 1139
FID C 4 615
FID C 6 373
FID C 3 1658
FID C 9 923
FID C 8 953
FID L 11 403
FID L 12 403
FID L 13 387
FID L 14 352
FID L 15 403
FID L 16 403
SNT VIA
FID H 0 2116
FID C 3 1655
FID C 9 922
FID C 8 952
FID L 11 402
FID L 12 402
FID L 13 386
FID L 14 351
FID L 15 402
FID L 16 402
SNT TRC
FID C 9 891
FID C 9 892
FID C 9 893
FID C 9 894
FID C 9 895
FID C 9 896
FID C 9 897
FID C 9 898
FID C 9 899
FID C 9 900
FID C 9 901
FID C 9 902
FID C 9 903
FID C 9 904
FID C 9 905
FID C 9 906
FID C 9 907
FID C 9 908
FID C 9 909
FID C 9 910
FID C 9 911
FID C 9 912
SNT TRC
FID C 3 1643
FID C 3 1644
FID C 3 1645
FID C 3 1646
FID C 3 1647
FID C 3 1648
FID C 3 1649
FID C 3 1650
SNT TRC
FID C 9 913
FID C 9 914
FID C 9 915
FID C 9 916
FID C 9 917
FID C 9 918
FID C 9 919
SNT TRC
FID C 8 949
SNT TRC
FID C 3 1652
SNT TRC
FID C 3 1656
SNT TRC
FID C 8 954
FID C 8 955
# NET 397
NET FPGA_IO_7 
SNT TOP T 170 284
FID C 4 607
FID C 5 383
FID C 3 1638
SNT TOP T 251 1
FID C 4 609
FID C 5 384
FID C 3 1641
SNT TOP B 132 1
FID C 6 366
FID C 7 117
FID C 8 941
SNT TOP B 149 0
FID C 6 368
FID C 7 118
FID C 8 946
SNT VIA
FID H 0 246
FID C 4 608
FID C 6 367
FID C 3 1640
FID C 8 943
FID L 11 398
FID L 12 398
FID L 13 382
FID L 14 347
FID L 15 398
FID L 16 398
SNT VIA
FID H 0 247
FID C 4 606
FID C 6 365
FID C 3 1630
FID C 9 889
FID C 8 940
FID L 11 397
FID L 12 397
FID L 13 381
FID L 14 346
FID L 15 397
FID L 16 397
SNT VIA
FID H 0 1140
FID C 4 610
FID C 6 369
FID C 3 1642
FID C 9 890
FID C 8 947
FID L 11 399
FID L 12 399
FID L 13 383
FID L 14 348
FID L 15 399
FID L 16 399
SNT TRC
FID C 8 931
FID C 8 932
FID C 8 933
FID C 8 934
FID C 8 935
FID C 8 936
FID C 8 937
FID C 8 938
FID C 8 939
SNT TRC
FID C 9 869
FID C 9 870
FID C 9 871
FID C 9 872
FID C 9 873
FID C 9 874
FID C 9 875
FID C 9 876
FID C 9 877
FID C 9 878
FID C 9 879
FID C 9 880
FID C 9 881
FID C 9 882
FID C 9 883
FID C 9 884
FID C 9 885
FID C 9 886
FID C 9 887
FID C 9 888
SNT TRC
FID C 3 1631
FID C 3 1632
FID C 3 1633
FID C 3 1634
FID C 3 1635
FID C 3 1636
FID C 3 1637
SNT TRC
FID C 8 942
SNT TRC
FID C 3 1639
SNT TRC
FID C 8 944
FID C 8 945
# NET 398
NET R_BNO080_EVN_SDA 
SNT TOP T 149 15
FID C 4 1303
FID C 5 785
FID C 3 3497
SNT TOP B 289 0
FID C 6 792
FID C 7 208
FID C 8 2360
SNT VIA
FID H 0 343
FID C 4 1304
FID C 6 790
FID C 3 3498
FID C 9 1845
FID C 8 2358
FID L 11 786
FID L 12 786
FID L 13 770
FID L 14 735
FID L 15 786
FID L 16 786
SNT VIA
FID H 0 2169
FID C 4 1305
FID C 6 791
FID C 3 3499
FID C 9 1846
FID C 8 2359
FID L 11 787
FID L 12 787
FID L 13 771
FID L 14 736
FID L 15 787
FID L 16 787
SNT TRC
FID C 9 1835
FID C 9 1836
FID C 9 1837
FID C 9 1838
FID C 9 1839
FID C 9 1840
FID C 9 1841
FID C 9 1842
FID C 9 1843
FID C 9 1844
SNT TRC
FID C 8 2357
SNT TRC
FID C 3 3495
FID C 3 3496
# NET 399
NET BNO080_EVN_SDA 
SNT TOP T 71 0
FID H 0 102
FID C 6 445
FID C 3 1938
FID C 8 1251
FID L 11 453
FID L 12 453
FID L 13 437
FID L 14 402
FID L 15 453
FID L 16 453
SNT TOP B 288 1
FID C 6 446
FID C 7 144
FID C 8 1252
SNT TOP B 289 1
FID C 6 447
FID C 7 145
FID C 8 1254
SNT TRC
FID C 8 1242
FID C 8 1243
FID C 8 1244
FID C 8 1245
FID C 8 1246
FID C 8 1247
FID C 8 1248
FID C 8 1249
FID C 8 1250
SNT TRC
FID C 8 1253
# NET 400
NET SMA2_SIG_OUT_BF_EN_N 
SNT TOP T 31 0
FID H 0 157
FID C 6 650
FID C 3 2832
FID C 10 1894
FID C 8 1920
FID L 11 642
FID L 12 642
FID L 13 626
FID L 14 591
FID L 15 642
FID L 16 642
SNT TOP T 126 0
FID C 4 1069
FID C 5 645
FID C 3 2833
SNT TOP T 170 298
FID C 4 1071
FID C 5 647
FID C 3 2835
SNT TOP T 307 1
FID C 4 1070
FID C 5 646
FID C 3 2834
SNT VIA
FID H 0 708
FID C 4 1072
FID C 6 651
FID C 3 2838
FID C 9 1419
FID C 10 1895
FID C 8 1922
FID L 11 644
FID L 12 644
FID L 13 628
FID L 14 593
FID L 15 644
FID L 16 644
SNT VIA
FID H 0 2147
FID C 3 2836
FID C 9 1418
FID C 8 1921
FID L 11 643
FID L 12 643
FID L 13 627
FID L 14 592
FID L 15 643
FID L 16 643
SNT TRC
FID C 9 1376
FID C 9 1377
FID C 9 1378
FID C 9 1379
FID C 9 1380
FID C 9 1381
FID C 9 1382
FID C 9 1383
FID C 9 1384
FID C 9 1385
FID C 9 1386
FID C 9 1387
FID C 9 1388
FID C 9 1389
FID C 9 1390
FID C 9 1391
FID C 9 1392
FID C 9 1393
FID C 9 1394
FID C 9 1395
FID C 9 1396
FID C 9 1397
FID C 9 1398
FID C 9 1399
FID C 9 1400
FID C 9 1401
FID C 9 1402
FID C 9 1403
FID C 9 1404
FID C 9 1405
FID C 9 1406
FID C 9 1407
FID C 9 1408
FID C 9 1409
FID C 9 1410
FID C 9 1411
FID C 9 1412
FID C 9 1413
FID C 9 1414
FID C 9 1415
FID C 9 1416
FID C 9 1417
SNT TRC
FID C 10 1890
FID C 10 1891
FID C 10 1892
FID C 10 1893
SNT TRC
FID C 3 2827
FID C 3 2828
FID C 3 2829
SNT TRC
FID C 3 2830
FID C 3 2831
SNT TRC
FID C 3 2837
# NET 401
NET R_LM75B_1_I2C_SDA 
SNT TOP B 108 0
FID C 6 1671
FID C 7 593
FID C 8 4158
SNT TOP B 188 1
FID C 6 1672
FID C 7 594
FID C 8 4159
SNT VIA
FID C 6 1670
FID C 8 4157
SNT TRC
FID C 8 4149
FID C 8 4150
FID C 8 4151
FID C 8 4152
FID C 8 4153
FID C 8 4154
SNT TRC
FID C 8 4155
FID C 8 4156
# NET 402
NET UNNAMED_6_LM75BDPTSSOP8_I34_A2 
SNT TOP B 108 4
FID C 6 1674
FID C 7 595
FID C 8 4165
SNT TOP B 192 0
FID C 6 1675
FID C 7 596
FID C 8 4166
SNT TOP B 193 1
FID C 6 1676
FID C 7 597
FID C 8 4168
SNT VIA
FID H 0 1332
FID C 4 2366
FID C 6 1673
FID C 3 5787
FID C 8 4164
FID L 11 1364
FID L 12 1364
FID L 13 1132
FID L 14 1131
FID L 15 1364
FID L 16 1364
SNT TRC
FID C 8 4160
FID C 8 4161
FID C 8 4162
SNT TRC
FID C 8 4163
SNT TRC
FID C 8 4167
# NET 403
NET UNNAMED_6_LM75BDPTSSOP8_I34_A1 
SNT TOP B 108 5
FID C 6 1679
FID C 7 599
FID C 8 4178
SNT TOP B 190 0
FID C 6 1678
FID C 7 598
FID C 8 4177
SNT TOP B 191 1
FID C 6 1680
FID C 7 600
FID C 8 4179
SNT VIA
FID H 0 1331
FID C 4 2367
FID C 6 1677
FID C 3 5788
FID C 8 4175
FID L 11 1365
FID L 12 1365
FID L 13 1133
FID L 14 1132
FID L 15 1365
FID L 16 1365
SNT TRC
FID C 8 4169
FID C 8 4170
FID C 8 4171
SNT TRC
FID C 8 4172
FID C 8 4173
FID C 8 4174
SNT TRC
FID C 8 4176
# NET 404
NET UNNAMED_6_LM75BDPTSSOP8_I34_A0 
SNT TOP B 108 6
FID C 6 1682
FID C 7 601
FID C 8 4187
SNT TOP B 194 0
FID C 6 1684
FID C 7 603
FID C 8 4190
SNT TOP B 195 1
FID C 6 1683
FID C 7 602
FID C 8 4188
SNT VIA
FID H 0 1330
FID C 4 2368
FID C 6 1681
FID C 3 5789
FID C 8 4186
FID L 11 1366
FID L 12 1366
FID L 13 1134
FID L 14 1133
FID L 15 1366
FID L 16 1366
SNT TRC
FID C 8 4180
FID C 8 4181
FID C 8 4182
SNT TRC
FID C 8 4183
FID C 8 4184
FID C 8 4185
SNT TRC
FID C 8 4189
# NET 405
NET FPGA_D02 
SNT TOP T 170 350
FID C 4 14
FID C 5 9
FID C 3 48
SNT TOP T 215 0
FID C 4 13
FID C 5 8
FID C 3 47
SNT VIA
FID H 0 1113
FID C 4 12
FID C 6 8
FID C 3 46
FID C 8 14
FID L 11 7
FID L 12 7
FID L 13 7
FID L 14 7
FID L 15 7
FID L 16 7
SNT TRC
FID C 3 37
FID C 3 38
FID C 3 39
FID C 3 40
SNT TRC
FID C 3 41
FID C 3 42
FID C 3 43
FID C 3 44
FID C 3 45
# NET 406
NET FPGA_FLASH_DQ2 
SNT TOP T 2 3
FID C 4 654
FID C 5 403
FID C 3 1746
SNT TOP T 215 1
FID C 4 651
FID C 5 402
FID C 3 1738
SNT TOP T 240 0
FID C 4 655
FID C 5 404
FID C 3 1747
SNT VIA
FID H 0 225
FID C 4 652
FID C 6 407
FID C 3 1740
FID C 10 567
FID C 8 1136
FID L 11 426
FID L 12 426
FID L 13 410
FID L 14 375
FID L 15 426
FID L 16 426
SNT VIA
FID H 0 1122
FID C 4 653
FID C 6 408
FID C 3 1745
FID C 10 568
FID C 8 1137
FID L 11 427
FID L 12 427
FID L 13 411
FID L 14 376
FID L 15 427
FID L 16 427
SNT TRC
FID C 10 548
FID C 10 549
FID C 10 550
FID C 10 551
FID C 10 552
FID C 10 553
FID C 10 554
FID C 10 555
FID C 10 556
FID C 10 557
FID C 10 558
FID C 10 559
FID C 10 560
FID C 10 561
FID C 10 562
FID C 10 563
FID C 10 564
FID C 10 565
FID C 10 566
SNT TRC
FID C 3 1739
SNT TRC
FID C 3 1741
FID C 3 1742
SNT TRC
FID C 3 1743
FID C 3 1744
# NET 407
NET FPGA_IN_LM75B_INT1_N 
SNT TOP T 40 0
FID H 0 147
FID C 6 591
FID C 3 2561
FID C 8 1719
FID L 11 581
FID L 12 581
FID L 13 565
FID L 14 530
FID L 15 581
FID L 16 581
SNT TOP T 170 329
FID C 4 978
FID C 5 596
FID C 3 2565
SNT TOP B 108 2
FID C 6 592
FID C 7 177
FID C 8 1720
SNT TOP B 187 1
FID C 6 593
FID C 7 178
FID C 8 1721
SNT VIA
FID H 0 1126
FID C 4 977
FID C 6 594
FID C 3 2563
FID C 10 1428
FID C 8 1723
FID L 11 583
FID L 12 583
FID L 13 567
FID L 14 532
FID L 15 583
FID L 16 583
SNT VIA
FID H 0 2108
FID C 3 2562
FID C 10 1427
FID C 8 1722
FID L 11 582
FID L 12 582
FID L 13 566
FID L 14 531
FID L 15 582
FID L 16 582
SNT TRC
FID C 8 1696
FID C 8 1697
FID C 8 1698
SNT TRC
FID C 10 1409
FID C 10 1410
FID C 10 1411
FID C 10 1412
FID C 10 1413
FID C 10 1414
FID C 10 1415
FID C 10 1416
FID C 10 1417
FID C 10 1418
FID C 10 1419
FID C 10 1420
FID C 10 1421
FID C 10 1422
FID C 10 1423
FID C 10 1424
FID C 10 1425
FID C 10 1426
SNT TRC
FID C 8 1699
FID C 8 1700
FID C 8 1701
FID C 8 1702
FID C 8 1703
FID C 8 1704
FID C 8 1705
FID C 8 1706
FID C 8 1707
FID C 8 1708
FID C 8 1709
FID C 8 1710
FID C 8 1711
FID C 8 1712
FID C 8 1713
FID C 8 1714
FID C 8 1715
FID C 8 1716
FID C 8 1717
SNT TRC
FID C 8 1718
SNT TRC
FID C 3 2564
# NET 408
NET BNO080_EVN_SCL 
SNT TOP T 72 0
FID H 0 137
FID C 6 448
FID C 3 1939
FID C 8 1261
FID L 11 454
FID L 12 454
FID L 13 438
FID L 14 403
FID L 15 454
FID L 16 454
SNT TOP B 256 1
FID C 6 449
FID C 7 146
FID C 8 1262
SNT TOP B 257 1
FID C 6 450
FID C 7 147
FID C 8 1264
SNT TRC
FID C 8 1255
FID C 8 1256
FID C 8 1257
FID C 8 1258
FID C 8 1259
FID C 8 1260
SNT TRC
FID C 8 1263
# NET 409
NET UNNAMED_8_ICP10100LGA10_I24_RES 
SNT TOP T 148 0
FID C 4 1186
FID C 5 711
FID C 3 3090
SNT TOP B 169 0
FID C 6 706
FID C 7 188
FID C 8 2143
SNT VIA
FID H 0 2185
FID C 4 1185
FID C 6 707
FID C 3 3089
FID C 8 2147
FID L 11 701
FID L 12 701
FID L 13 685
FID L 14 650
FID L 15 701
FID L 16 701
SNT TRC
FID C 8 2144
FID C 8 2145
FID C 8 2146
SNT TRC
FID C 3 3086
FID C 3 3087
FID C 3 3088
# NET 410
NET PRI_EEPROM_SDA 
SNT TOP T 133 2
FID C 4 1024
FID C 5 619
FID C 3 2723
SNT TOP T 335 1
FID C 4 1025
FID C 5 620
FID C 3 2724
SNT VIA
FID H 0 2165
FID C 4 1023
FID C 6 624
FID C 3 2722
FID C 8 1847
FID L 11 614
FID L 12 614
FID L 13 598
FID L 14 563
FID L 15 614
FID L 16 614
SNT TRC
FID C 3 2715
FID C 3 2716
FID C 3 2717
FID C 3 2718
SNT TRC
FID C 3 2719
FID C 3 2720
FID C 3 2721
# NET 411
NET UNNAMED_8_ICP10100LGA10_I24_R_1 
SNT TOP T 148 2
FID C 4 1184
FID C 5 710
FID C 3 3085
SNT TOP T 262 0
FID C 4 1182
FID C 5 709
FID C 3 3078
SNT VIA
FID H 0 2186
FID C 4 1183
FID C 6 705
FID C 3 3084
FID C 8 2142
FID L 11 700
FID L 12 700
FID L 13 684
FID L 14 649
FID L 15 700
FID L 16 700
SNT TRC
FID C 3 3074
FID C 3 3075
FID C 3 3076
FID C 3 3077
SNT TRC
FID C 3 3079
FID C 3 3080
FID C 3 3081
FID C 3 3082
FID C 3 3083
# NET 412
NET UNNAMED_8_ICP10100LGA10_I24_R_2 
SNT TOP T 148 4
FID C 4 1181
FID C 5 708
FID C 3 3073
SNT TOP T 263 0
FID C 4 1179
FID C 5 707
FID C 3 3066
SNT VIA
FID H 0 1336
FID C 4 1180
FID C 6 704
FID C 3 3069
FID C 8 2141
FID L 11 699
FID L 12 699
FID L 13 683
FID L 14 648
FID L 15 699
FID L 16 699
SNT TRC
FID C 3 3067
FID C 3 3068
SNT TRC
FID C 3 3070
FID C 3 3071
FID C 3 3072
# NET 413
NET FPGA_D03 
SNT TOP T 170 372
FID C 4 11
FID C 5 7
FID C 3 36
SNT TOP T 214 0
FID C 4 10
FID C 5 6
FID C 3 35
SNT VIA
FID H 0 1114
FID C 4 9
FID C 6 7
FID C 3 34
FID C 8 13
FID L 11 6
FID L 12 6
FID L 13 6
FID L 14 6
FID L 15 6
FID L 16 6
SNT TRC
FID C 3 23
FID C 3 24
FID C 3 25
FID C 3 26
SNT TRC
FID C 3 27
FID C 3 28
FID C 3 29
FID C 3 30
FID C 3 31
FID C 3 32
FID C 3 33
# NET 414
NET FPGA_FLASH_DQ3 
SNT TOP T 3 3
FID C 4 649
FID C 5 400
FID C 3 1736
SNT TOP T 214 1
FID C 4 647
FID C 5 399
FID C 3 1730
SNT TOP T 239 0
FID C 4 650
FID C 5 401
FID C 3 1737
SNT VIA
FID H 0 226
FID C 4 646
FID C 6 405
FID C 3 1729
FID C 10 546
FID C 8 1134
FID L 11 424
FID L 12 424
FID L 13 408
FID L 14 373
FID L 15 424
FID L 16 424
SNT VIA
FID H 0 1123
FID C 4 648
FID C 6 406
FID C 3 1735
FID C 10 547
FID C 8 1135
FID L 11 425
FID L 12 425
FID L 13 409
FID L 14 374
FID L 15 425
FID L 16 425
SNT TRC
FID C 10 530
FID C 10 531
FID C 10 532
FID C 10 533
FID C 10 534
FID C 10 535
FID C 10 536
FID C 10 537
FID C 10 538
FID C 10 539
FID C 10 540
FID C 10 541
FID C 10 542
FID C 10 543
FID C 10 544
FID C 10 545
SNT TRC
FID C 3 1724
FID C 3 1725
FID C 3 1726
FID C 3 1727
FID C 3 1728
SNT TRC
FID C 3 1731
FID C 3 1732
SNT TRC
FID C 3 1733
FID C 3 1734
# NET 415
NET XP3R3V_RT 
SNT TOP T 181 12
FID C 4 2078
FID C 5 1243
FID C 3 5238
SNT TOP T 391 0
FID C 4 2077
FID C 5 1242
FID C 3 5237
SNT TRC
FID C 3 5235
FID C 3 5236
# NET 416
NET UNNAMED_8_ICP10100LGA10_I24_R_3 
SNT TOP T 148 5
FID C 4 1178
FID C 5 706
FID C 3 3065
SNT TOP T 264 0
FID C 4 1176
FID C 5 705
FID C 3 3060
SNT VIA
FID H 0 2187
FID C 4 1177
FID C 6 703
FID C 3 3061
FID C 8 2140
FID L 11 698
FID L 12 698
FID L 13 682
FID L 14 647
FID L 15 698
FID L 16 698
SNT TRC
FID C 3 3062
SNT TRC
FID C 3 3063
FID C 3 3064
# NET 417
NET UNNAMED_8_ICP10100LGA10_I24_R_4 
SNT TOP T 148 6
FID C 4 1175
FID C 5 704
FID C 3 3059
SNT TOP T 265 0
FID C 4 1173
FID C 5 703
FID C 3 3052
SNT VIA
FID H 0 1337
FID C 4 1174
FID C 6 702
FID C 3 3058
FID C 8 2139
FID L 11 697
FID L 12 697
FID L 13 681
FID L 14 646
FID L 15 697
FID L 16 697
SNT TRC
FID C 3 3053
FID C 3 3054
SNT TRC
FID C 3 3055
FID C 3 3056
FID C 3 3057
# NET 418
NET R_FT4232_CHC_RX 
SNT TOP T 13 38
FID C 4 462
FID C 5 316
FID C 3 1113
SNT TOP T 241 0
FID C 4 460
FID C 5 314
FID C 3 1110
SNT TOP T 267 0
FID C 4 461
FID C 5 315
FID C 3 1112
SNT VIA
FID H 0 1205
FID C 4 459
FID C 6 251
FID C 3 1109
FID C 8 573
FID L 11 310
FID L 12 310
FID L 13 294
FID L 14 259
FID L 15 310
FID L 16 310
SNT TRC
FID C 3 1105
SNT TRC
FID C 3 1106
FID C 3 1107
FID C 3 1108
SNT TRC
FID C 3 1111
# NET 419
NET UART_FT4232_RX_FPGA_TX 
SNT TOP T 170 344
FID C 4 420
FID C 5 290
FID C 3 985
SNT TOP T 267 1
FID C 4 419
FID C 5 289
FID C 3 984
SNT VIA
FID H 0 718
FID C 4 418
FID C 6 218
FID C 3 983
FID C 9 80
FID C 8 506
FID L 11 291
FID L 12 291
FID L 13 275
FID L 14 240
FID L 15 291
FID L 16 291
SNT VIA
FID H 0 1259
FID C 4 417
FID C 6 217
FID C 3 981
FID C 9 79
FID C 10 129
FID C 8 505
FID L 11 290
FID L 12 290
FID L 13 274
FID L 14 239
FID L 15 290
FID L 16 290
SNT VIA
FID H 0 2486
FID C 3 986
FID C 10 130
FID C 8 507
FID L 11 292
FID L 12 292
FID L 13 276
FID L 14 241
FID L 15 292
FID L 16 292
SNT TRC
FID C 10 82
FID C 10 83
FID C 10 84
FID C 10 85
FID C 10 86
FID C 10 87
FID C 10 88
FID C 10 89
FID C 10 90
FID C 10 91
FID C 10 92
FID C 10 93
FID C 10 94
FID C 10 95
FID C 10 96
FID C 10 97
FID C 10 98
FID C 10 99
FID C 10 100
FID C 10 101
FID C 10 102
FID C 10 103
FID C 10 104
FID C 10 105
FID C 10 106
FID C 10 107
FID C 10 108
FID C 10 109
FID C 10 110
FID C 10 111
FID C 10 112
FID C 10 113
FID C 10 114
FID C 10 115
FID C 10 116
FID C 10 117
FID C 10 118
FID C 10 119
FID C 10 120
FID C 10 121
FID C 10 122
FID C 10 123
FID C 10 124
FID C 10 125
FID C 10 126
FID C 10 127
FID C 10 128
SNT TRC
FID C 9 51
FID C 9 52
FID C 9 53
FID C 9 54
FID C 9 55
FID C 9 56
FID C 9 57
FID C 9 58
FID C 9 59
FID C 9 60
FID C 9 61
FID C 9 62
FID C 9 63
FID C 9 64
FID C 9 65
FID C 9 66
FID C 9 67
FID C 9 68
FID C 9 69
FID C 9 70
FID C 9 71
FID C 9 72
FID C 9 73
FID C 9 74
FID C 9 75
FID C 9 76
FID C 9 77
FID C 9 78
SNT TRC
FID C 3 982
SNT TRC
FID C 3 987
# NET 420
NET R_FT4232_CHC_TX 
SNT TOP T 13 37
FID C 4 458
FID C 5 313
FID C 3 1104
SNT TOP T 268 0
FID C 4 457
FID C 5 312
FID C 3 1103
SNT VIA
FID H 0 1206
FID C 4 456
FID C 6 250
FID C 3 1102
FID C 8 572
FID L 11 309
FID L 12 309
FID L 13 293
FID L 14 258
FID L 15 309
FID L 16 309
SNT TRC
FID C 3 1098
FID C 3 1099
FID C 3 1100
SNT TRC
FID C 3 1101
# NET 421
NET UART_FT4232_TX_FPGA_RX 
SNT TOP T 170 345
FID C 4 416
FID C 5 288
FID C 3 978
SNT TOP T 242 0
FID C 4 414
FID C 5 286
FID C 3 975
SNT TOP T 268 1
FID C 4 415
FID C 5 287
FID C 3 977
SNT VIA
FID H 0 719
FID C 4 413
FID C 6 216
FID C 3 973
FID C 9 50
FID C 8 503
FID L 11 288
FID L 12 288
FID L 13 272
FID L 14 237
FID L 15 288
FID L 16 288
SNT VIA
FID H 0 1260
FID C 4 412
FID C 6 215
FID C 3 972
FID C 9 49
FID C 10 80
FID C 8 502
FID L 11 287
FID L 12 287
FID L 13 271
FID L 14 236
FID L 15 287
FID L 16 287
SNT VIA
FID H 0 2487
FID C 3 979
FID C 10 81
FID C 8 504
FID L 11 289
FID L 12 289
FID L 13 273
FID L 14 238
FID L 15 289
FID L 16 289
SNT TRC
FID C 10 58
FID C 10 59
FID C 10 60
FID C 10 61
FID C 10 62
FID C 10 63
FID C 10 64
FID C 10 65
FID C 10 66
FID C 10 67
FID C 10 68
FID C 10 69
FID C 10 70
FID C 10 71
FID C 10 72
FID C 10 73
FID C 10 74
FID C 10 75
FID C 10 76
FID C 10 77
FID C 10 78
FID C 10 79
SNT TRC
FID C 9 24
FID C 9 25
FID C 9 26
FID C 9 27
FID C 9 28
FID C 9 29
FID C 9 30
FID C 9 31
FID C 9 32
FID C 9 33
FID C 9 34
FID C 9 35
FID C 9 36
FID C 9 37
FID C 9 38
FID C 9 39
FID C 9 40
FID C 9 41
FID C 9 42
FID C 9 43
FID C 9 44
FID C 9 45
FID C 9 46
FID C 9 47
FID C 9 48
SNT TRC
FID C 3 974
SNT TRC
FID C 3 976
SNT TRC
FID C 3 980
# NET 422
NET FPGA_OUT_I2C_BUFFER_EN 
SNT TOP T 170 257
FID C 4 1243
FID C 5 751
FID C 3 3245
SNT TOP T 205 0
FID C 4 1245
FID C 5 752
FID C 3 3250
SNT VIA
FID H 0 2232
FID C 4 1244
FID C 6 750
FID C 3 3247
FID C 8 2249
FID L 11 749
FID L 12 749
FID L 13 733
FID L 14 698
FID L 15 749
FID L 16 749
SNT VIA
FID H 0 2365
FID C 3 3244
FID C 8 2248
FID L 11 748
FID L 12 748
FID L 13 732
FID L 14 697
FID L 15 748
FID L 16 748
SNT TRC
FID C 8 2226
FID C 8 2227
FID C 8 2228
FID C 8 2229
FID C 8 2230
FID C 8 2231
FID C 8 2232
FID C 8 2233
FID C 8 2234
FID C 8 2235
FID C 8 2236
FID C 8 2237
FID C 8 2238
FID C 8 2239
FID C 8 2240
FID C 8 2241
FID C 8 2242
FID C 8 2243
FID C 8 2244
FID C 8 2245
FID C 8 2246
FID C 8 2247
SNT TRC
FID C 3 3246
SNT TRC
FID C 3 3248
FID C 3 3249
# NET 423
NET BF_PCIE_PERST_N 
SNT TOP T 200 0
FID C 4 3965
FID C 5 1888
FID C 3 8723
SNT TOP T 266 0
FID C 4 3967
FID C 5 1889
FID C 3 8743
SNT TOP T 597 3
FID C 4 3964
FID C 5 1887
FID C 3 8720
SNT VIA
FID H 0 204
FID C 4 3966
FID C 6 3104
FID C 3 8742
FID C 8 6973
FID L 11 1570
FID L 12 1570
FID L 13 2347
FID L 14 2346
FID L 15 1570
FID L 16 1570
SNT VIA
FID H 0 1093
FID C 4 3968
FID C 6 3105
FID C 3 8744
FID C 8 6974
FID L 11 1571
FID L 12 1571
FID L 13 2348
FID L 14 2347
FID L 15 1571
FID L 16 1571
SNT TRC
FID C 3 8721
FID C 3 8722
SNT TRC
FID C 3 8724
FID C 3 8725
FID C 3 8726
FID C 3 8727
FID C 3 8728
FID C 3 8729
FID C 3 8730
FID C 3 8731
FID C 3 8732
FID C 3 8733
FID C 3 8734
FID C 3 8735
FID C 3 8736
FID C 3 8737
SNT TRC
FID C 8 6963
FID C 8 6964
FID C 8 6965
FID C 8 6966
FID C 8 6967
FID C 8 6968
FID C 8 6969
FID C 8 6970
FID C 8 6971
FID C 8 6972
SNT TRC
FID C 3 8738
FID C 3 8739
FID C 3 8740
FID C 3 8741
# NET 424
NET SMA1_SIG_OUT_BF_EN_N 
SNT TOP T 32 0
FID H 0 156
FID C 6 666
FID C 3 2886
FID C 9 1533
FID C 8 2031
FID L 11 660
FID L 12 660
FID L 13 644
FID L 14 609
FID L 15 660
FID L 16 660
SNT TOP T 125 0
FID C 4 1097
FID C 5 658
FID C 3 2891
SNT TOP T 170 254
FID C 4 1095
FID C 5 657
FID C 3 2887
SNT TOP T 341 1
FID C 4 1098
FID C 5 659
FID C 3 2894
SNT VIA
FID H 0 701
FID C 4 1096
FID C 6 667
FID C 3 2890
FID C 9 1534
FID C 10 1932
FID C 8 2033
FID L 11 662
FID L 12 662
FID L 13 646
FID L 14 611
FID L 15 662
FID L 16 662
SNT VIA
FID H 0 2481
FID C 3 2888
FID C 10 1931
FID C 8 2032
FID L 11 661
FID L 12 661
FID L 13 645
FID L 14 610
FID L 15 661
FID L 16 661
SNT TRC
FID C 10 1914
FID C 10 1915
FID C 10 1916
FID C 10 1917
FID C 10 1918
FID C 10 1919
FID C 10 1920
FID C 10 1921
FID C 10 1922
FID C 10 1923
FID C 10 1924
FID C 10 1925
FID C 10 1926
FID C 10 1927
FID C 10 1928
FID C 10 1929
FID C 10 1930
SNT TRC
FID C 9 1516
FID C 9 1517
FID C 9 1518
FID C 9 1519
FID C 9 1520
FID C 9 1521
FID C 9 1522
FID C 9 1523
FID C 9 1524
FID C 9 1525
FID C 9 1526
FID C 9 1527
FID C 9 1528
FID C 9 1529
FID C 9 1530
FID C 9 1531
FID C 9 1532
SNT TRC
FID C 3 2884
FID C 3 2885
SNT TRC
FID C 3 2889
SNT TRC
FID C 3 2892
FID C 3 2893
# NET 425
NET FPGA_FCS_B 
SNT TOP T 170 392
FID C 4 8
FID C 5 5
FID C 3 22
SNT TOP T 213 0
FID C 4 7
FID C 5 4
FID C 3 19
SNT VIA
FID H 0 1117
FID C 4 6
FID C 6 6
FID C 3 18
FID C 10 5
FID C 8 11
FID L 11 4
FID L 12 4
FID L 13 4
FID L 14 4
FID L 15 4
FID L 16 4
SNT VIA
FID H 0 2107
FID C 3 20
FID C 10 6
FID C 8 12
FID L 11 5
FID L 12 5
FID L 13 5
FID L 14 5
FID L 15 5
FID L 16 5
SNT TRC
FID C 3 16
FID C 3 17
SNT TRC
FID C 10 0
FID C 10 1
FID C 10 2
FID C 10 3
FID C 10 4
SNT TRC
FID C 3 21
# NET 426
NET FPGA_FLASH_CS_N 
SNT TOP T 5 13
FID C 4 667
FID C 5 411
FID C 3 1772
SNT TOP T 213 1
FID C 4 666
FID C 5 410
FID C 3 1771
SNT VIA
FID H 0 222
FID C 4 665
FID C 6 413
FID C 3 1768
FID C 10 721
FID C 8 1142
FID L 11 432
FID L 12 432
FID L 13 416
FID L 14 381
FID L 15 432
FID L 16 432
SNT VIA
FID H 0 1119
FID C 4 668
FID C 6 414
FID C 3 1773
FID C 10 722
FID C 8 1143
FID L 11 433
FID L 12 433
FID L 13 417
FID L 14 382
FID L 15 433
FID L 16 433
SNT TRC
FID C 10 678
FID C 10 679
FID C 10 680
FID C 10 681
FID C 10 682
FID C 10 683
FID C 10 684
FID C 10 685
FID C 10 686
FID C 10 687
FID C 10 688
FID C 10 689
FID C 10 690
FID C 10 691
FID C 10 692
FID C 10 693
FID C 10 694
FID C 10 695
FID C 10 696
FID C 10 697
FID C 10 698
FID C 10 699
FID C 10 700
FID C 10 701
FID C 10 702
FID C 10 703
FID C 10 704
FID C 10 705
FID C 10 706
FID C 10 707
FID C 10 708
FID C 10 709
FID C 10 710
FID C 10 711
FID C 10 712
FID C 10 713
FID C 10 714
FID C 10 715
FID C 10 716
FID C 10 717
FID C 10 718
FID C 10 719
FID C 10 720
SNT TRC
FID C 3 1766
FID C 3 1767
SNT TRC
FID C 3 1769
FID C 3 1770
# NET 427
NET R_BNO080_EVN_SCL 
SNT TOP T 149 14
FID C 4 1306
FID C 5 786
FID C 3 3502
SNT TOP B 257 0
FID C 6 793
FID C 7 209
FID C 8 2361
SNT VIA
FID H 0 342
FID C 4 1307
FID C 6 794
FID C 3 3503
FID C 9 1879
FID C 8 2364
FID L 11 788
FID L 12 788
FID L 13 772
FID L 14 737
FID L 15 788
FID L 16 788
SNT VIA
FID H 0 2168
FID C 4 1308
FID C 6 795
FID C 3 3504
FID C 9 1880
FID C 8 2365
FID L 11 789
FID L 12 789
FID L 13 773
FID L 14 738
FID L 15 789
FID L 16 789
SNT TRC
FID C 9 1847
FID C 9 1848
FID C 9 1849
FID C 9 1850
FID C 9 1851
FID C 9 1852
FID C 9 1853
FID C 9 1854
FID C 9 1855
FID C 9 1856
FID C 9 1857
FID C 9 1858
FID C 9 1859
FID C 9 1860
FID C 9 1861
FID C 9 1862
FID C 9 1863
FID C 9 1864
FID C 9 1865
FID C 9 1866
FID C 9 1867
FID C 9 1868
FID C 9 1869
FID C 9 1870
FID C 9 1871
FID C 9 1872
FID C 9 1873
FID C 9 1874
FID C 9 1875
FID C 9 1876
FID C 9 1877
FID C 9 1878
SNT TRC
FID C 3 3500
FID C 3 3501
SNT TRC
FID C 8 2362
FID C 8 2363
# NET 428
NET SMA3_SIG_OUT_BF_EN_N 
SNT TOP T 30 0
FID H 0 158
FID C 6 639
FID C 3 2782
FID C 9 1355
FID C 8 1907
FID L 11 629
FID L 12 629
FID L 13 613
FID L 14 578
FID L 15 629
FID L 16 629
SNT TOP T 127 0
FID C 4 1049
FID C 5 634
FID C 3 2784
SNT TOP T 170 234
FID C 4 1050
FID C 5 635
FID C 3 2785
SNT TOP T 309 1
FID C 4 1048
FID C 5 633
FID C 3 2783
SNT VIA
FID H 0 710
FID C 4 1051
FID C 6 640
FID C 3 2787
FID C 9 1356
FID C 10 1753
FID C 8 1909
FID L 11 631
FID L 12 631
FID L 13 615
FID L 14 580
FID L 15 631
FID L 16 631
SNT VIA
FID H 0 2483
FID C 3 2786
FID C 10 1752
FID C 8 1908
FID L 11 630
FID L 12 630
FID L 13 614
FID L 14 579
FID L 15 630
FID L 16 630
SNT TRC
FID C 10 1726
FID C 10 1727
FID C 10 1728
FID C 10 1729
FID C 10 1730
FID C 10 1731
FID C 10 1732
FID C 10 1733
FID C 10 1734
FID C 10 1735
FID C 10 1736
FID C 10 1737
FID C 10 1738
FID C 10 1739
FID C 10 1740
FID C 10 1741
FID C 10 1742
FID C 10 1743
FID C 10 1744
FID C 10 1745
FID C 10 1746
FID C 10 1747
FID C 10 1748
FID C 10 1749
FID C 10 1750
FID C 10 1751
SNT TRC
FID C 9 1348
FID C 9 1349
FID C 9 1350
FID C 9 1351
FID C 9 1352
FID C 9 1353
FID C 9 1354
SNT TRC
FID C 3 2775
FID C 3 2776
FID C 3 2777
FID C 3 2778
FID C 3 2779
SNT TRC
FID C 3 2780
FID C 3 2781
SNT TRC
FID C 3 2788
# NET 429
NET BF_ANT3_IN 
SNT TOP T 127 2
FID C 4 944
FID C 5 573
FID C 3 2472
SNT TOP T 279 0
FID C 4 943
FID C 5 572
FID C 3 2471
SNT VIA
FID H 0 1091
FID C 4 942
FID C 6 564
FID C 3 2470
FID C 8 1637
FID L 11 566
FID L 12 566
FID L 13 550
FID L 14 515
FID L 15 566
FID L 16 566
SNT TRC
FID C 3 2465
FID C 3 2466
FID C 3 2467
SNT TRC
FID C 3 2468
FID C 3 2469
# NET 430
NET ANT3_IN 
SNT TOP T 170 472
FID C 4 1019
FID C 5 617
FID C 3 2711
SNT TOP T 279 1
FID C 4 1021
FID C 5 618
FID C 3 2713
SNT TOP B 14 1
FID C 6 621
FID C 7 184
FID C 8 1828
SNT VIA
FID H 0 198
FID C 4 1022
FID C 6 623
FID C 3 2714
FID C 8 1846
FID L 11 613
FID L 12 613
FID L 13 597
FID L 14 562
FID L 15 613
FID L 16 613
SNT VIA
FID H 0 1087
FID C 4 1020
FID C 6 622
FID C 3 2712
FID C 9 1347
FID C 8 1845
FID L 11 612
FID L 12 612
FID L 13 596
FID L 14 561
FID L 15 612
FID L 16 612
SNT VIA
FID H 0 2342
FID C 3 2709
FID C 9 1346
FID C 8 1844
FID L 11 611
FID L 12 611
FID L 13 595
FID L 14 560
FID L 15 611
FID L 16 611
SNT TRC
FID C 9 1308
FID C 9 1309
FID C 9 1310
FID C 9 1311
FID C 9 1312
FID C 9 1313
FID C 9 1314
FID C 9 1315
FID C 9 1316
FID C 9 1317
FID C 9 1318
FID C 9 1319
FID C 9 1320
FID C 9 1321
FID C 9 1322
FID C 9 1323
FID C 9 1324
FID C 9 1325
FID C 9 1326
FID C 9 1327
FID C 9 1328
FID C 9 1329
FID C 9 1330
FID C 9 1331
FID C 9 1332
FID C 9 1333
FID C 9 1334
FID C 9 1335
FID C 9 1336
FID C 9 1337
FID C 9 1338
FID C 9 1339
FID C 9 1340
FID C 9 1341
FID C 9 1342
FID C 9 1343
FID C 9 1344
FID C 9 1345
SNT TRC
FID C 8 1829
FID C 8 1830
SNT TRC
FID C 8 1831
FID C 8 1832
FID C 8 1833
FID C 8 1834
FID C 8 1835
FID C 8 1836
FID C 8 1837
FID C 8 1838
FID C 8 1839
FID C 8 1840
FID C 8 1841
FID C 8 1842
FID C 8 1843
SNT TRC
FID C 3 2702
FID C 3 2703
FID C 3 2704
FID C 3 2705
FID C 3 2706
FID C 3 2707
FID C 3 2708
SNT TRC
FID C 3 2710
# NET 431
NET SMA4_SIG_OUT_BF_EN_N 
SNT TOP T 29 0
FID H 0 159
FID C 6 628
FID C 3 2740
FID C 8 1870
FID L 11 618
FID L 12 618
FID L 13 602
FID L 14 567
FID L 15 618
FID L 16 618
SNT TOP T 128 0
FID C 4 1031
FID C 5 624
FID C 3 2742
SNT TOP T 170 211
FID C 4 1028
FID C 5 622
FID C 3 2736
SNT TOP T 311 1
FID C 4 1030
FID C 5 623
FID C 3 2741
SNT VIA
FID H 0 715
FID C 4 1029
FID C 6 627
FID C 3 2739
FID C 10 1584
FID C 8 1869
FID L 11 617
FID L 12 617
FID L 13 601
FID L 14 566
FID L 15 617
FID L 16 617
SNT VIA
FID H 0 2485
FID C 3 2737
FID C 10 1583
FID C 8 1868
FID L 11 616
FID L 12 616
FID L 13 600
FID L 14 565
FID L 15 616
FID L 16 616
SNT TRC
FID C 10 1560
FID C 10 1561
FID C 10 1562
FID C 10 1563
FID C 10 1564
FID C 10 1565
FID C 10 1566
FID C 10 1567
FID C 10 1568
FID C 10 1569
FID C 10 1570
FID C 10 1571
FID C 10 1572
FID C 10 1573
FID C 10 1574
FID C 10 1575
FID C 10 1576
FID C 10 1577
FID C 10 1578
FID C 10 1579
FID C 10 1580
FID C 10 1581
FID C 10 1582
SNT TRC
FID C 8 1852
FID C 8 1853
FID C 8 1854
FID C 8 1855
FID C 8 1856
FID C 8 1857
FID C 8 1858
FID C 8 1859
FID C 8 1860
FID C 8 1861
FID C 8 1862
FID C 8 1863
FID C 8 1864
FID C 8 1865
FID C 8 1866
FID C 8 1867
SNT TRC
FID C 3 2728
FID C 3 2729
FID C 3 2730
FID C 3 2731
FID C 3 2732
SNT TRC
FID C 3 2733
FID C 3 2734
FID C 3 2735
SNT TRC
FID C 3 2738
# NET 432
NET XP3R3V_BT 
SNT TOP T 181 0
FID C 4 2092
FID C 5 1253
FID C 3 5281
SNT TOP B 164 0
FID C 6 1441
FID C 7 517
FID C 8 3757
SNT VIA
FID H 0 1379
FID C 4 2093
FID C 6 1442
FID C 3 5282
FID C 8 3760
FID L 11 1220
FID L 12 1220
FID L 13 1062
FID L 14 1012
FID L 15 1220
FID L 16 1220
SNT TRC
FID C 8 3758
FID C 8 3759
SNT TRC
FID C 3 5278
FID C 3 5279
FID C 3 5280
# NET 433
NET BF_ANT4_IN 
SNT TOP T 128 2
FID C 4 941
FID C 5 571
FID C 3 2464
SNT TOP T 280 0
FID C 4 940
FID C 5 570
FID C 3 2463
SNT VIA
FID H 0 1092
FID C 4 939
FID C 6 563
FID C 3 2462
FID C 8 1636
FID L 11 565
FID L 12 565
FID L 13 549
FID L 14 514
FID L 15 565
FID L 16 565
SNT TRC
FID C 3 2458
FID C 3 2459
SNT TRC
FID C 3 2460
FID C 3 2461
# NET 434
NET ANT4_IN 
SNT TOP T 170 473
FID C 4 1014
FID C 5 614
FID C 3 2693
SNT TOP T 280 1
FID C 4 1012
FID C 5 613
FID C 3 2689
SNT TOP B 128 1
FID C 6 617
FID C 7 183
FID C 8 1820
SNT VIA
FID H 0 200
FID C 4 1011
FID C 6 616
FID C 3 2683
FID C 9 1214
FID C 10 1526
FID C 8 1819
FID L 11 605
FID L 12 605
FID L 13 589
FID L 14 554
FID L 15 605
FID L 16 605
SNT VIA
FID H 0 2149
FID C 4 1013
FID C 6 618
FID C 3 2690
FID C 10 1546
FID C 8 1823
FID L 11 606
FID L 12 606
FID L 13 590
FID L 14 555
FID L 15 606
FID L 16 606
SNT VIA
FID H 0 2344
FID C 3 2691
FID C 9 1256
FID C 8 1824
FID L 11 607
FID L 12 607
FID L 13 591
FID L 14 556
FID L 15 607
FID L 16 607
SNT TRC
FID C 10 1527
FID C 10 1528
FID C 10 1529
FID C 10 1530
FID C 10 1531
FID C 10 1532
FID C 10 1533
FID C 10 1534
FID C 10 1535
FID C 10 1536
FID C 10 1537
FID C 10 1538
FID C 10 1539
FID C 10 1540
FID C 10 1541
FID C 10 1542
FID C 10 1543
FID C 10 1544
FID C 10 1545
SNT TRC
FID C 9 1215
FID C 9 1216
FID C 9 1217
FID C 9 1218
FID C 9 1219
FID C 9 1220
FID C 9 1221
FID C 9 1222
FID C 9 1223
FID C 9 1224
FID C 9 1225
FID C 9 1226
FID C 9 1227
FID C 9 1228
FID C 9 1229
FID C 9 1230
FID C 9 1231
FID C 9 1232
FID C 9 1233
FID C 9 1234
FID C 9 1235
FID C 9 1236
FID C 9 1237
FID C 9 1238
FID C 9 1239
FID C 9 1240
FID C 9 1241
FID C 9 1242
FID C 9 1243
FID C 9 1244
FID C 9 1245
FID C 9 1246
FID C 9 1247
FID C 9 1248
FID C 9 1249
FID C 9 1250
FID C 9 1251
FID C 9 1252
FID C 9 1253
FID C 9 1254
FID C 9 1255
SNT TRC
FID C 8 1821
FID C 8 1822
SNT TRC
FID C 3 2684
FID C 3 2685
FID C 3 2686
FID C 3 2687
FID C 3 2688
SNT TRC
FID C 3 2692
# NET 435
NET BF_ANT1_IN 
SNT TOP T 125 2
FID C 4 937
FID C 5 568
FID C 3 2456
SNT TOP T 281 0
FID C 4 938
FID C 5 569
FID C 3 2457
SNT VIA
FID H 0 1089
FID C 4 936
FID C 6 562
FID C 3 2455
FID C 8 1635
FID L 11 564
FID L 12 564
FID L 13 548
FID L 14 513
FID L 15 564
FID L 16 564
SNT TRC
FID C 3 2449
FID C 3 2450
SNT TRC
FID C 3 2451
FID C 3 2452
FID C 3 2453
FID C 3 2454
# NET 436
NET ANT1_IN 
SNT TOP T 170 42
FID C 4 1002
FID C 5 609
FID C 3 2664
SNT TOP T 281 1
FID C 4 1004
FID C 5 610
FID C 3 2668
SNT TOP B 13 0
FID C 6 608
FID C 7 182
FID C 8 1787
SNT VIA
FID C 6 609
FID C 8 1802
SNT VIA
FID H 0 194
FID C 4 1003
FID C 6 611
FID C 3 2667
FID C 8 1805
FID L 11 599
FID L 12 599
FID L 13 583
FID L 14 548
FID L 15 599
FID L 16 599
SNT VIA
FID H 0 1403
FID C 4 1001
FID C 6 610
FID C 3 2663
FID C 10 1524
FID C 8 1803
FID L 11 597
FID L 12 597
FID L 13 581
FID L 14 546
FID L 15 597
FID L 16 597
SNT VIA
FID H 0 2104
FID C 3 2666
FID C 10 1525
FID C 8 1804
FID L 11 598
FID L 12 598
FID L 13 582
FID L 14 547
FID L 15 598
FID L 16 598
SNT TRC
FID C 10 1501
FID C 10 1502
FID C 10 1503
FID C 10 1504
FID C 10 1505
FID C 10 1506
FID C 10 1507
FID C 10 1508
FID C 10 1509
FID C 10 1510
FID C 10 1511
FID C 10 1512
FID C 10 1513
FID C 10 1514
FID C 10 1515
FID C 10 1516
FID C 10 1517
FID C 10 1518
FID C 10 1519
FID C 10 1520
FID C 10 1521
FID C 10 1522
FID C 10 1523
SNT TRC
FID C 8 1764
FID C 8 1765
FID C 8 1766
FID C 8 1767
FID C 8 1768
FID C 8 1769
FID C 8 1770
FID C 8 1771
FID C 8 1772
FID C 8 1773
FID C 8 1774
FID C 8 1775
FID C 8 1776
FID C 8 1777
FID C 8 1778
FID C 8 1779
FID C 8 1780
FID C 8 1781
FID C 8 1782
FID C 8 1783
FID C 8 1784
FID C 8 1785
FID C 8 1786
SNT TRC
FID C 8 1788
FID C 8 1789
SNT TRC
FID C 8 1790
FID C 8 1791
FID C 8 1792
FID C 8 1793
FID C 8 1794
FID C 8 1795
FID C 8 1796
FID C 8 1797
FID C 8 1798
FID C 8 1799
FID C 8 1800
FID C 8 1801
SNT TRC
FID C 3 2659
FID C 3 2660
FID C 3 2661
FID C 3 2662
SNT TRC
FID C 3 2665
# NET 437
NET BF_ANT2_IN 
SNT TOP T 126 2
FID C 4 934
FID C 5 566
FID C 3 2447
SNT TOP T 282 0
FID C 4 935
FID C 5 567
FID C 3 2448
SNT VIA
FID H 0 1090
FID C 4 933
FID C 6 561
FID C 3 2446
FID C 8 1634
FID L 11 563
FID L 12 563
FID L 13 547
FID L 14 512
FID L 15 563
FID L 16 563
SNT TRC
FID C 3 2442
SNT TRC
FID C 3 2443
FID C 3 2444
FID C 3 2445
# NET 438
NET ANT2_IN 
SNT TOP T 170 41
FID C 4 995
FID C 5 606
FID C 3 2646
SNT TOP T 282 1
FID C 4 993
FID C 5 605
FID C 3 2643
SNT TOP B 12 0
FID C 6 603
FID C 7 181
FID C 8 1756
SNT VIA
FID H 0 196
FID C 4 994
FID C 6 604
FID C 3 2644
FID C 8 1758
FID L 11 591
FID L 12 591
FID L 13 575
FID L 14 540
FID L 15 591
FID L 16 591
SNT VIA
FID H 0 1085
FID C 4 996
FID C 6 605
FID C 3 2648
FID C 10 1475
FID C 8 1760
FID L 11 593
FID L 12 593
FID L 13 577
FID L 14 542
FID L 15 593
FID L 16 593
SNT VIA
FID H 0 2340
FID C 3 2645
FID C 10 1474
FID C 8 1759
FID L 11 592
FID L 12 592
FID L 13 576
FID L 14 541
FID L 15 592
FID L 16 592
SNT TRC
FID C 10 1445
FID C 10 1446
FID C 10 1447
FID C 10 1448
FID C 10 1449
FID C 10 1450
FID C 10 1451
FID C 10 1452
FID C 10 1453
FID C 10 1454
FID C 10 1455
FID C 10 1456
FID C 10 1457
FID C 10 1458
FID C 10 1459
FID C 10 1460
FID C 10 1461
FID C 10 1462
FID C 10 1463
FID C 10 1464
FID C 10 1465
FID C 10 1466
FID C 10 1467
FID C 10 1468
FID C 10 1469
FID C 10 1470
FID C 10 1471
FID C 10 1472
FID C 10 1473
SNT TRC
FID C 8 1744
FID C 8 1745
FID C 8 1746
FID C 8 1747
FID C 8 1748
FID C 8 1749
FID C 8 1750
FID C 8 1751
FID C 8 1752
FID C 8 1753
FID C 8 1754
FID C 8 1755
SNT TRC
FID C 8 1757
SNT TRC
FID C 3 2640
FID C 3 2641
FID C 3 2642
SNT TRC
FID C 3 2647
# NET 439
NET FPGA_OUT_SMA2_LED_RED_N 
SNT TOP T 170 144
FID C 4 861
FID C 5 523
FID C 3 2265
SNT TOP T 301 0
FID C 4 860
FID C 5 522
FID C 3 2264
SNT VIA
FID H 0 1158
FID C 4 859
FID C 6 526
FID C 3 2263
FID C 10 1176
FID C 8 1522
FID L 11 526
FID L 12 526
FID L 13 510
FID L 14 475
FID L 15 526
FID L 16 526
SNT VIA
FID H 0 2131
FID C 3 2257
FID C 10 1175
FID C 8 1521
FID L 11 525
FID L 12 525
FID L 13 509
FID L 14 474
FID L 15 525
FID L 16 525
SNT TRC
FID C 10 1150
FID C 10 1151
FID C 10 1152
FID C 10 1153
FID C 10 1154
FID C 10 1155
FID C 10 1156
FID C 10 1157
FID C 10 1158
FID C 10 1159
FID C 10 1160
FID C 10 1161
FID C 10 1162
FID C 10 1163
FID C 10 1164
FID C 10 1165
FID C 10 1166
FID C 10 1167
FID C 10 1168
FID C 10 1169
FID C 10 1170
FID C 10 1171
FID C 10 1172
FID C 10 1173
FID C 10 1174
SNT TRC
FID C 3 2258
SNT TRC
FID C 3 2259
FID C 3 2260
FID C 3 2261
FID C 3 2262
# NET 440
NET FPGA_OUT_SMA3_LED_BLUE_N 
SNT TOP T 170 126
FID C 4 858
FID C 5 521
FID C 3 2255
SNT TOP T 292 0
FID C 4 855
FID C 5 520
FID C 3 2251
SNT VIA
FID H 0 270
FID C 4 856
FID C 6 524
FID C 3 2253
FID C 10 1148
FID C 8 1519
FID L 11 523
FID L 12 523
FID L 13 507
FID L 14 472
FID L 15 523
FID L 16 523
SNT VIA
FID H 0 271
FID C 4 857
FID C 6 525
FID C 3 2254
FID C 10 1149
FID C 8 1520
FID L 11 524
FID L 12 524
FID L 13 508
FID L 14 473
FID L 15 524
FID L 16 524
SNT VIA
FID H 0 1159
FID C 4 854
FID C 6 523
FID C 3 2250
FID C 10 1146
FID C 8 1517
FID L 11 521
FID L 12 521
FID L 13 505
FID L 14 470
FID L 15 521
FID L 16 521
SNT VIA
FID H 0 2132
FID C 3 2252
FID C 10 1147
FID C 8 1518
FID L 11 522
FID L 12 522
FID L 13 506
FID L 14 471
FID L 15 522
FID L 16 522
SNT TRC
FID C 10 1110
FID C 10 1111
FID C 10 1112
FID C 10 1113
FID C 10 1114
FID C 10 1115
FID C 10 1116
FID C 10 1117
FID C 10 1118
FID C 10 1119
FID C 10 1120
FID C 10 1121
FID C 10 1122
FID C 10 1123
FID C 10 1124
FID C 10 1125
FID C 10 1126
FID C 10 1127
FID C 10 1128
FID C 10 1129
FID C 10 1130
FID C 10 1131
FID C 10 1132
SNT TRC
FID C 8 1513
FID C 8 1514
FID C 8 1515
FID C 8 1516
SNT TRC
FID C 10 1133
FID C 10 1134
FID C 10 1135
FID C 10 1136
FID C 10 1137
FID C 10 1138
FID C 10 1139
FID C 10 1140
FID C 10 1141
FID C 10 1142
FID C 10 1143
FID C 10 1144
FID C 10 1145
SNT TRC
FID C 3 2249
SNT TRC
FID C 3 2256
# NET 441
NET FPGA_OUT_SMA3_LED_GREEN_N 
SNT TOP T 170 104
FID C 4 853
FID C 5 519
FID C 3 2248
SNT TOP T 313 0
FID C 4 850
FID C 5 518
FID C 3 2242
SNT VIA
FID H 0 272
FID C 4 851
FID C 6 521
FID C 3 2246
FID C 10 1108
FID C 8 1511
FID L 11 519
FID L 12 519
FID L 13 503
FID L 14 468
FID L 15 519
FID L 16 519
SNT VIA
FID H 0 273
FID C 4 852
FID C 6 522
FID C 3 2247
FID C 10 1109
FID C 8 1512
FID L 11 520
FID L 12 520
FID L 13 504
FID L 14 469
FID L 15 520
FID L 16 520
SNT VIA
FID H 0 1160
FID C 4 849
FID C 6 520
FID C 3 2241
FID C 10 1106
FID C 8 1509
FID L 11 517
FID L 12 517
FID L 13 501
FID L 14 466
FID L 15 517
FID L 16 517
SNT VIA
FID H 0 2133
FID C 3 2243
FID C 10 1107
FID C 8 1510
FID L 11 518
FID L 12 518
FID L 13 502
FID L 14 467
FID L 15 518
FID L 16 518
SNT TRC
FID C 10 1078
FID C 10 1079
FID C 10 1080
FID C 10 1081
FID C 10 1082
FID C 10 1083
FID C 10 1084
FID C 10 1085
FID C 10 1086
FID C 10 1087
FID C 10 1088
FID C 10 1089
FID C 10 1090
FID C 10 1091
FID C 10 1092
FID C 10 1093
FID C 10 1094
FID C 10 1095
FID C 10 1096
FID C 10 1097
FID C 10 1098
SNT TRC
FID C 10 1099
FID C 10 1100
FID C 10 1101
FID C 10 1102
FID C 10 1103
FID C 10 1104
FID C 10 1105
SNT TRC
FID C 8 1505
FID C 8 1506
FID C 8 1507
FID C 8 1508
SNT TRC
FID C 3 2238
FID C 3 2239
FID C 3 2240
SNT TRC
FID C 3 2244
FID C 3 2245
# NET 442
NET FPGA_OUT_SMA3_LED_RED_N 
SNT TOP T 170 105
FID C 4 846
FID C 5 516
FID C 3 2234
SNT TOP T 290 0
FID C 4 848
FID C 5 517
FID C 3 2237
SNT VIA
FID H 0 274
FID C 4 847
FID C 6 519
FID C 3 2236
FID C 10 1077
FID C 8 1504
FID L 11 516
FID L 12 516
FID L 13 500
FID L 14 465
FID L 15 516
FID L 16 516
SNT VIA
FID H 0 275
FID C 4 844
FID C 6 517
FID C 3 2230
FID C 10 1074
FID C 8 1501
FID L 11 513
FID L 12 513
FID L 13 497
FID L 14 462
FID L 15 513
FID L 16 513
SNT VIA
FID H 0 1161
FID C 4 845
FID C 6 518
FID C 3 2232
FID C 10 1076
FID C 8 1503
FID L 11 515
FID L 12 515
FID L 13 499
FID L 14 464
FID L 15 515
FID L 16 515
SNT VIA
FID H 0 2134
FID C 3 2231
FID C 10 1075
FID C 8 1502
FID L 11 514
FID L 12 514
FID L 13 498
FID L 14 463
FID L 15 514
FID L 16 514
SNT TRC
FID C 10 1044
FID C 10 1045
FID C 10 1046
FID C 10 1047
FID C 10 1048
FID C 10 1049
FID C 10 1050
FID C 10 1051
FID C 10 1052
FID C 10 1053
FID C 10 1054
FID C 10 1055
FID C 10 1056
FID C 10 1057
FID C 10 1058
FID C 10 1059
FID C 10 1060
FID C 10 1061
FID C 10 1062
FID C 10 1063
FID C 10 1064
FID C 10 1065
SNT TRC
FID C 10 1066
FID C 10 1067
FID C 10 1068
FID C 10 1069
FID C 10 1070
FID C 10 1071
FID C 10 1072
FID C 10 1073
SNT TRC
FID C 8 1497
FID C 8 1498
FID C 8 1499
FID C 8 1500
SNT TRC
FID C 3 2233
SNT TRC
FID C 3 2235
# NET 443
NET SMA3_SIG_IN_BF_EN_N 
SNT TOP T 34 0
FID H 0 154
FID C 6 641
FID C 3 2796
FID C 9 1368
FID C 8 1910
FID L 11 632
FID L 12 632
FID L 13 616
FID L 14 581
FID L 15 632
FID L 16 632
SNT TOP T 127 6
FID C 4 1052
FID C 5 636
FID C 3 2794
SNT TOP T 170 212
FID C 4 1054
FID C 5 638
FID C 3 2799
SNT TOP T 310 1
FID C 4 1053
FID C 5 637
FID C 3 2795
SNT VIA
FID H 0 709
FID C 4 1056
FID C 6 643
FID C 3 2802
FID C 9 1375
FID C 10 1776
FID C 8 1913
FID L 11 635
FID L 12 635
FID L 13 619
FID L 14 584
FID L 15 635
FID L 16 635
SNT VIA
FID H 0 1254
FID C 4 1055
FID C 6 642
FID C 3 2801
FID C 9 1374
FID C 8 1912
FID L 11 634
FID L 12 634
FID L 13 618
FID L 14 583
FID L 15 634
FID L 16 634
SNT VIA
FID H 0 2482
FID C 3 2800
FID C 10 1775
FID C 8 1911
FID L 11 633
FID L 12 633
FID L 13 617
FID L 14 582
FID L 15 633
FID L 16 633
SNT TRC
FID C 10 1754
FID C 10 1755
FID C 10 1756
FID C 10 1757
FID C 10 1758
FID C 10 1759
FID C 10 1760
FID C 10 1761
FID C 10 1762
FID C 10 1763
FID C 10 1764
FID C 10 1765
FID C 10 1766
FID C 10 1767
FID C 10 1768
FID C 10 1769
FID C 10 1770
FID C 10 1771
FID C 10 1772
FID C 10 1773
FID C 10 1774
SNT TRC
FID C 9 1357
FID C 9 1358
FID C 9 1359
FID C 9 1360
FID C 9 1361
FID C 9 1362
FID C 9 1363
FID C 9 1364
FID C 9 1365
FID C 9 1366
FID C 9 1367
SNT TRC
FID C 3 2789
FID C 3 2790
FID C 3 2791
FID C 3 2792
FID C 3 2793
SNT TRC
FID C 3 2797
FID C 3 2798
SNT TRC
FID C 9 1369
FID C 9 1370
FID C 9 1371
FID C 9 1372
FID C 9 1373
SNT TRC
FID C 3 2803
# NET 444
NET SMA4_SIG_IN_BF_EN_N 
SNT TOP T 33 0
FID H 0 155
FID C 6 630
FID C 3 2750
FID C 8 1898
FID L 11 621
FID L 12 621
FID L 13 605
FID L 14 570
FID L 15 621
FID L 16 621
SNT TOP T 128 6
FID C 4 1034
FID C 5 626
FID C 3 2751
SNT TOP T 170 233
FID C 4 1032
FID C 5 625
FID C 3 2746
SNT TOP B 189 1
FID C 6 632
FID C 7 186
FID C 8 1900
SNT VIA
FID H 0 714
FID C 4 1033
FID C 6 629
FID C 3 2748
FID C 10 1609
FID C 8 1895
FID L 11 620
FID L 12 620
FID L 13 604
FID L 14 569
FID L 15 620
FID L 16 620
SNT VIA
FID H 0 1256
FID C 4 1035
FID C 6 631
FID C 3 2752
FID C 8 1899
FID L 11 622
FID L 12 622
FID L 13 606
FID L 14 571
FID L 15 622
FID L 16 622
SNT VIA
FID H 0 2484
FID C 3 2747
FID C 10 1608
FID C 8 1894
FID L 11 619
FID L 12 619
FID L 13 603
FID L 14 568
FID L 15 619
FID L 16 619
SNT TRC
FID C 10 1585
FID C 10 1586
FID C 10 1587
FID C 10 1588
FID C 10 1589
FID C 10 1590
FID C 10 1591
FID C 10 1592
FID C 10 1593
FID C 10 1594
FID C 10 1595
FID C 10 1596
FID C 10 1597
FID C 10 1598
FID C 10 1599
FID C 10 1600
FID C 10 1601
FID C 10 1602
FID C 10 1603
FID C 10 1604
FID C 10 1605
FID C 10 1606
FID C 10 1607
SNT TRC
FID C 8 1871
FID C 8 1872
FID C 8 1873
FID C 8 1874
FID C 8 1875
FID C 8 1876
FID C 8 1877
FID C 8 1878
FID C 8 1879
FID C 8 1880
FID C 8 1881
FID C 8 1882
FID C 8 1883
FID C 8 1884
FID C 8 1885
FID C 8 1886
FID C 8 1887
FID C 8 1888
SNT TRC
FID C 3 2743
FID C 3 2744
FID C 3 2745
SNT TRC
FID C 8 1889
FID C 8 1890
FID C 8 1891
FID C 8 1892
FID C 8 1893
SNT TRC
FID C 3 2749
SNT TRC
FID C 8 1896
FID C 8 1897
# NET 445
NET SMA1_SIG_IN_BF_EN_N 
SNT TOP T 36 0
FID H 0 151
FID C 6 668
FID C 3 2901
FID C 8 2039
FID L 11 663
FID L 12 663
FID L 13 647
FID L 14 612
FID L 15 663
FID L 16 663
SNT TOP T 125 6
FID C 4 1100
FID C 5 661
FID C 3 2903
SNT TOP T 170 255
FID C 4 1101
FID C 5 662
FID C 3 2904
SNT TOP T 306 1
FID C 4 1099
FID C 5 660
FID C 3 2902
SNT VIA
FID H 0 1246
FID C 4 1102
FID C 6 669
FID C 3 2906
FID C 10 1972
FID C 8 2041
FID L 11 665
FID L 12 665
FID L 13 649
FID L 14 614
FID L 15 665
FID L 16 665
SNT VIA
FID H 0 2480
FID C 3 2905
FID C 10 1971
FID C 8 2040
FID L 11 664
FID L 12 664
FID L 13 648
FID L 14 613
FID L 15 664
FID L 16 664
SNT TRC
FID C 10 1933
FID C 10 1934
FID C 10 1935
FID C 10 1936
FID C 10 1937
FID C 10 1938
FID C 10 1939
FID C 10 1940
FID C 10 1941
FID C 10 1942
FID C 10 1943
FID C 10 1944
FID C 10 1945
FID C 10 1946
FID C 10 1947
FID C 10 1948
FID C 10 1949
FID C 10 1950
FID C 10 1951
FID C 10 1952
FID C 10 1953
FID C 10 1954
FID C 10 1955
FID C 10 1956
FID C 10 1957
FID C 10 1958
FID C 10 1959
FID C 10 1960
FID C 10 1961
FID C 10 1962
FID C 10 1963
FID C 10 1964
FID C 10 1965
FID C 10 1966
FID C 10 1967
FID C 10 1968
FID C 10 1969
FID C 10 1970
SNT TRC
FID C 8 2034
FID C 8 2035
FID C 8 2036
FID C 8 2037
FID C 8 2038
SNT TRC
FID C 3 2895
FID C 3 2896
FID C 3 2897
SNT TRC
FID C 3 2898
FID C 3 2899
FID C 3 2900
SNT TRC
FID C 3 2907
# NET 446
NET SMA2_SIG_IN_BF_EN_N 
SNT TOP T 35 0
FID H 0 152
FID C 6 653
FID C 3 2847
FID C 8 1939
FID L 11 647
FID L 12 647
FID L 13 631
FID L 14 596
FID L 15 647
FID L 16 647
SNT TOP T 126 6
FID C 4 1076
FID C 5 650
FID C 3 2849
SNT TOP T 170 276
FID C 4 1073
FID C 5 648
FID C 3 2839
SNT TOP T 308 1
FID C 4 1075
FID C 5 649
FID C 3 2848
SNT VIA
FID H 0 1249
FID C 4 1074
FID C 6 652
FID C 3 2841
FID C 10 1913
FID C 8 1938
FID L 11 646
FID L 12 646
FID L 13 630
FID L 14 595
FID L 15 646
FID L 16 646
SNT VIA
FID H 0 2146
FID C 3 2840
FID C 10 1912
FID C 8 1937
FID L 11 645
FID L 12 645
FID L 13 629
FID L 14 594
FID L 15 645
FID L 16 645
SNT TRC
FID C 10 1896
FID C 10 1897
FID C 10 1898
FID C 10 1899
FID C 10 1900
FID C 10 1901
FID C 10 1902
FID C 10 1903
FID C 10 1904
FID C 10 1905
FID C 10 1906
FID C 10 1907
FID C 10 1908
FID C 10 1909
FID C 10 1910
FID C 10 1911
SNT TRC
FID C 8 1923
FID C 8 1924
FID C 8 1925
FID C 8 1926
FID C 8 1927
FID C 8 1928
FID C 8 1929
FID C 8 1930
FID C 8 1931
FID C 8 1932
FID C 8 1933
FID C 8 1934
FID C 8 1935
FID C 8 1936
SNT TRC
FID C 3 2842
SNT TRC
FID C 3 2843
FID C 3 2844
SNT TRC
FID C 3 2845
FID C 3 2846
# NET 447
NET SMA1_LED_BLUE_N 
SNT TOP T 120 9
FID C 4 1115
FID C 5 667
FID C 3 2926
SNT TOP T 296 0
FID C 4 1119
FID C 5 668
FID C 3 2932
SNT VIA
FID H 0 698
FID C 4 1120
FID C 6 681
FID C 3 2933
FID C 9 1571
FID C 8 2116
FID L 11 677
FID L 12 677
FID L 13 661
FID L 14 626
FID L 15 677
FID L 16 677
SNT VIA
FID H 0 1243
FID C 4 1116
FID C 6 678
FID C 3 2929
FID C 9 1570
FID C 10 2006
FID C 8 2113
FID L 11 674
FID L 12 674
FID L 13 658
FID L 14 623
FID L 15 674
FID L 16 674
SNT VIA
FID H 0 1935
FID C 4 1118
FID C 6 680
FID C 3 2931
FID C 8 2115
FID L 11 676
FID L 12 676
FID L 13 660
FID L 14 625
FID L 15 676
FID L 16 676
SNT VIA
FID H 0 1936
FID C 4 1117
FID C 6 679
FID C 3 2930
FID C 10 2007
FID C 8 2114
FID L 11 675
FID L 12 675
FID L 13 659
FID L 14 624
FID L 15 675
FID L 16 675
SNT TRC
FID C 8 2094
FID C 8 2095
FID C 8 2096
FID C 8 2097
FID C 8 2098
FID C 8 2099
FID C 8 2100
FID C 8 2101
FID C 8 2102
FID C 8 2103
FID C 8 2104
FID C 8 2105
FID C 8 2106
FID C 8 2107
FID C 8 2108
FID C 8 2109
FID C 8 2110
FID C 8 2111
FID C 8 2112
SNT TRC
FID C 10 1997
FID C 10 1998
FID C 10 1999
FID C 10 2000
FID C 10 2001
FID C 10 2002
FID C 10 2003
FID C 10 2004
FID C 10 2005
SNT TRC
FID C 9 1560
FID C 9 1561
FID C 9 1562
FID C 9 1563
FID C 9 1564
FID C 9 1565
FID C 9 1566
FID C 9 1567
FID C 9 1568
FID C 9 1569
SNT TRC
FID C 3 2927
FID C 3 2928
SNT TRC
FID C 3 2934
# NET 448
NET SMA1_LED_GREEN_N 
SNT TOP T 120 7
FID C 4 1109
FID C 5 665
FID C 3 2917
SNT TOP T 318 0
FID C 4 1113
FID C 5 666
FID C 3 2923
SNT VIA
FID H 0 699
FID C 4 1114
FID C 6 677
FID C 3 2924
FID C 9 1559
FID C 8 2093
FID L 11 673
FID L 12 673
FID L 13 657
FID L 14 622
FID L 15 673
FID L 16 673
SNT VIA
FID H 0 1244
FID C 4 1110
FID C 6 674
FID C 3 2918
FID C 9 1558
FID C 10 1995
FID C 8 2090
FID L 11 670
FID L 12 670
FID L 13 654
FID L 14 619
FID L 15 670
FID L 16 670
SNT VIA
FID H 0 1937
FID C 4 1112
FID C 6 676
FID C 3 2922
FID C 8 2092
FID L 11 672
FID L 12 672
FID L 13 656
FID L 14 621
FID L 15 672
FID L 16 672
SNT VIA
FID H 0 1938
FID C 4 1111
FID C 6 675
FID C 3 2921
FID C 10 1996
FID C 8 2091
FID L 11 671
FID L 12 671
FID L 13 655
FID L 14 620
FID L 15 671
FID L 16 671
SNT TRC
FID C 8 2067
FID C 8 2068
FID C 8 2069
FID C 8 2070
FID C 8 2071
FID C 8 2072
FID C 8 2073
FID C 8 2074
FID C 8 2075
FID C 8 2076
FID C 8 2077
FID C 8 2078
FID C 8 2079
FID C 8 2080
FID C 8 2081
FID C 8 2082
FID C 8 2083
FID C 8 2084
FID C 8 2085
FID C 8 2086
FID C 8 2087
FID C 8 2088
FID C 8 2089
SNT TRC
FID C 10 1986
FID C 10 1987
FID C 10 1988
FID C 10 1989
FID C 10 1990
FID C 10 1991
FID C 10 1992
FID C 10 1993
FID C 10 1994
SNT TRC
FID C 9 1544
FID C 9 1545
FID C 9 1546
FID C 9 1547
FID C 9 1548
FID C 9 1549
FID C 9 1550
FID C 9 1551
FID C 9 1552
FID C 9 1553
FID C 9 1554
FID C 9 1555
FID C 9 1556
FID C 9 1557
SNT TRC
FID C 3 2919
FID C 3 2920
SNT TRC
FID C 3 2925
# NET 449
NET SMA1_LED_RED_N 
SNT TOP T 120 8
FID C 4 1103
FID C 5 663
FID C 3 2908
SNT TOP T 320 0
FID C 4 1108
FID C 5 664
FID C 3 2915
SNT VIA
FID H 0 700
FID C 4 1107
FID C 6 673
FID C 3 2914
FID C 9 1543
FID C 8 2066
FID L 11 669
FID L 12 669
FID L 13 653
FID L 14 618
FID L 15 669
FID L 16 669
SNT VIA
FID H 0 1245
FID C 4 1106
FID C 6 672
FID C 3 2913
FID C 9 1542
FID C 10 1985
FID C 8 2065
FID L 11 668
FID L 12 668
FID L 13 652
FID L 14 617
FID L 15 668
FID L 16 668
SNT VIA
FID H 0 1939
FID C 4 1104
FID C 6 670
FID C 3 2909
FID C 8 2063
FID L 11 666
FID L 12 666
FID L 13 650
FID L 14 615
FID L 15 666
FID L 16 666
SNT VIA
FID H 0 1940
FID C 4 1105
FID C 6 671
FID C 3 2910
FID C 10 1984
FID C 8 2064
FID L 11 667
FID L 12 667
FID L 13 651
FID L 14 616
FID L 15 667
FID L 16 667
SNT TRC
FID C 8 2042
FID C 8 2043
FID C 8 2044
FID C 8 2045
FID C 8 2046
FID C 8 2047
FID C 8 2048
FID C 8 2049
FID C 8 2050
FID C 8 2051
FID C 8 2052
FID C 8 2053
FID C 8 2054
FID C 8 2055
FID C 8 2056
FID C 8 2057
FID C 8 2058
FID C 8 2059
FID C 8 2060
FID C 8 2061
FID C 8 2062
SNT TRC
FID C 10 1973
FID C 10 1974
FID C 10 1975
FID C 10 1976
FID C 10 1977
FID C 10 1978
FID C 10 1979
FID C 10 1980
FID C 10 1981
FID C 10 1982
FID C 10 1983
SNT TRC
FID C 9 1535
FID C 9 1536
FID C 9 1537
FID C 9 1538
FID C 9 1539
FID C 9 1540
FID C 9 1541
SNT TRC
FID C 3 2911
FID C 3 2912
SNT TRC
FID C 3 2916
# NET 450
NET SMA2_LED_BLUE_N 
SNT TOP T 120 13
FID C 4 1089
FID C 5 655
FID C 3 2875
SNT TOP T 299 0
FID C 4 1091
FID C 5 656
FID C 3 2880
SNT VIA
FID H 0 702
FID C 4 1090
FID C 6 662
FID C 3 2879
FID C 9 1514
FID C 8 2027
FID L 11 656
FID L 12 656
FID L 13 640
FID L 14 605
FID L 15 656
FID L 16 656
SNT VIA
FID H 0 703
FID C 4 1092
FID C 6 663
FID C 3 2881
FID C 8 2028
FID L 11 657
FID L 12 657
FID L 13 641
FID L 14 606
FID L 15 657
FID L 16 657
SNT VIA
FID H 0 1248
FID C 4 1093
FID C 6 664
FID C 3 2882
FID C 9 1515
FID C 8 2029
FID L 11 658
FID L 12 658
FID L 13 642
FID L 14 607
FID L 15 658
FID L 16 658
SNT VIA
FID H 0 1941
FID C 4 1094
FID C 6 665
FID C 3 2883
FID C 8 2030
FID L 11 659
FID L 12 659
FID L 13 643
FID L 14 608
FID L 15 659
FID L 16 659
SNT TRC
FID C 3 2871
FID C 3 2872
FID C 3 2873
FID C 3 2874
SNT TRC
FID C 8 1998
FID C 8 1999
FID C 8 2000
FID C 8 2001
FID C 8 2002
FID C 8 2003
FID C 8 2004
FID C 8 2005
FID C 8 2006
FID C 8 2007
FID C 8 2008
FID C 8 2009
FID C 8 2010
FID C 8 2011
FID C 8 2012
SNT TRC
FID C 9 1488
FID C 9 1489
FID C 9 1490
FID C 9 1491
FID C 9 1492
FID C 9 1493
FID C 9 1494
FID C 9 1495
FID C 9 1496
FID C 9 1497
FID C 9 1498
FID C 9 1499
FID C 9 1500
FID C 9 1501
FID C 9 1502
FID C 9 1503
FID C 9 1504
FID C 9 1505
FID C 9 1506
FID C 9 1507
FID C 9 1508
FID C 9 1509
FID C 9 1510
FID C 9 1511
FID C 9 1512
FID C 9 1513
SNT TRC
FID C 8 2013
FID C 8 2014
FID C 8 2015
FID C 8 2016
FID C 8 2017
FID C 8 2018
FID C 8 2019
FID C 8 2020
FID C 8 2021
FID C 8 2022
FID C 8 2023
FID C 8 2024
FID C 8 2025
FID C 8 2026
SNT TRC
FID C 3 2876
FID C 3 2877
FID C 3 2878
# NET 451
NET SMA2_LED_GREEN_N 
SNT TOP T 120 11
FID C 4 1083
FID C 5 653
FID C 3 2864
SNT TOP T 321 0
FID C 4 1085
FID C 5 654
FID C 3 2866
SNT VIA
FID H 0 704
FID C 4 1084
FID C 6 658
FID C 3 2865
FID C 9 1486
FID C 8 1994
FID L 11 652
FID L 12 652
FID L 13 636
FID L 14 601
FID L 15 652
FID L 16 652
SNT VIA
FID H 0 705
FID C 4 1086
FID C 6 659
FID C 3 2867
FID C 8 1995
FID L 11 653
FID L 12 653
FID L 13 637
FID L 14 602
FID L 15 653
FID L 16 653
SNT VIA
FID H 0 1942
FID C 4 1088
FID C 6 661
FID C 3 2870
FID C 8 1997
FID L 11 655
FID L 12 655
FID L 13 639
FID L 14 604
FID L 15 655
FID L 16 655
SNT VIA
FID H 0 2265
FID C 4 1087
FID C 6 660
FID C 3 2869
FID C 9 1487
FID C 8 1996
FID L 11 654
FID L 12 654
FID L 13 638
FID L 14 603
FID L 15 654
FID L 16 654
SNT TRC
FID C 9 1454
FID C 9 1455
FID C 9 1456
FID C 9 1457
FID C 9 1458
FID C 9 1459
FID C 9 1460
FID C 9 1461
FID C 9 1462
FID C 9 1463
FID C 9 1464
FID C 9 1465
FID C 9 1466
FID C 9 1467
FID C 9 1468
FID C 9 1469
FID C 9 1470
FID C 9 1471
FID C 9 1472
FID C 9 1473
FID C 9 1474
FID C 9 1475
FID C 9 1476
FID C 9 1477
FID C 9 1478
FID C 9 1479
FID C 9 1480
FID C 9 1481
FID C 9 1482
FID C 9 1483
FID C 9 1484
FID C 9 1485
SNT TRC
FID C 8 1971
FID C 8 1972
FID C 8 1973
FID C 8 1974
FID C 8 1975
FID C 8 1976
FID C 8 1977
FID C 8 1978
FID C 8 1979
FID C 8 1980
FID C 8 1981
FID C 8 1982
FID C 8 1983
FID C 8 1984
FID C 8 1985
FID C 8 1986
SNT TRC
FID C 3 2861
FID C 3 2862
FID C 3 2863
SNT TRC
FID C 8 1987
FID C 8 1988
FID C 8 1989
FID C 8 1990
FID C 8 1991
FID C 8 1992
FID C 8 1993
SNT TRC
FID C 3 2868
# NET 452
NET SMA2_LED_RED_N 
SNT TOP T 120 12
FID C 4 1077
FID C 5 651
FID C 3 2854
SNT TOP T 323 0
FID C 4 1079
FID C 5 652
FID C 3 2856
SNT VIA
FID H 0 706
FID C 4 1078
FID C 6 654
FID C 3 2855
FID C 9 1452
FID C 8 1967
FID L 11 648
FID L 12 648
FID L 13 632
FID L 14 597
FID L 15 648
FID L 16 648
SNT VIA
FID H 0 707
FID C 4 1080
FID C 6 655
FID C 3 2858
FID C 8 1968
FID L 11 649
FID L 12 649
FID L 13 633
FID L 14 598
FID L 15 649
FID L 16 649
SNT VIA
FID H 0 1943
FID C 4 1082
FID C 6 657
FID C 3 2860
FID C 8 1970
FID L 11 651
FID L 12 651
FID L 13 635
FID L 14 600
FID L 15 651
FID L 16 651
SNT VIA
FID H 0 2266
FID C 4 1081
FID C 6 656
FID C 3 2859
FID C 9 1453
FID C 8 1969
FID L 11 650
FID L 12 650
FID L 13 634
FID L 14 599
FID L 15 650
FID L 16 650
SNT TRC
FID C 8 1940
FID C 8 1941
FID C 8 1942
FID C 8 1943
FID C 8 1944
FID C 8 1945
FID C 8 1946
FID C 8 1947
FID C 8 1948
FID C 8 1949
FID C 8 1950
FID C 8 1951
FID C 8 1952
FID C 8 1953
FID C 8 1954
FID C 8 1955
SNT TRC
FID C 3 2850
FID C 3 2851
FID C 3 2852
FID C 3 2853
SNT TRC
FID C 9 1420
FID C 9 1421
FID C 9 1422
FID C 9 1423
FID C 9 1424
FID C 9 1425
FID C 9 1426
FID C 9 1427
FID C 9 1428
FID C 9 1429
FID C 9 1430
FID C 9 1431
FID C 9 1432
FID C 9 1433
FID C 9 1434
FID C 9 1435
FID C 9 1436
FID C 9 1437
FID C 9 1438
FID C 9 1439
FID C 9 1440
FID C 9 1441
FID C 9 1442
FID C 9 1443
FID C 9 1444
FID C 9 1445
FID C 9 1446
FID C 9 1447
FID C 9 1448
FID C 9 1449
FID C 9 1450
FID C 9 1451
SNT TRC
FID C 8 1956
FID C 8 1957
FID C 8 1958
FID C 8 1959
FID C 8 1960
FID C 8 1961
FID C 8 1962
FID C 8 1963
FID C 8 1964
FID C 8 1965
FID C 8 1966
SNT TRC
FID C 3 2857
# NET 453
NET SMA3_LED_BLUE_N 
SNT TOP T 120 16
FID C 4 1065
FID C 5 643
FID C 3 2819
SNT TOP T 291 0
FID C 4 1068
FID C 5 644
FID C 3 2826
SNT VIA
FID H 0 1251
FID C 4 1067
FID C 6 649
FID C 3 2825
FID C 10 1889
FID C 8 1919
FID L 11 641
FID L 12 641
FID L 13 625
FID L 14 590
FID L 15 641
FID L 16 641
SNT VIA
FID H 0 1944
FID C 4 1066
FID C 6 648
FID C 3 2822
FID C 10 1888
FID C 8 1918
FID L 11 640
FID L 12 640
FID L 13 624
FID L 14 589
FID L 15 640
FID L 16 640
SNT TRC
FID C 10 1851
FID C 10 1852
FID C 10 1853
FID C 10 1854
FID C 10 1855
FID C 10 1856
FID C 10 1857
FID C 10 1858
FID C 10 1859
FID C 10 1860
FID C 10 1861
FID C 10 1862
FID C 10 1863
FID C 10 1864
FID C 10 1865
FID C 10 1866
FID C 10 1867
FID C 10 1868
FID C 10 1869
FID C 10 1870
FID C 10 1871
FID C 10 1872
FID C 10 1873
FID C 10 1874
FID C 10 1875
FID C 10 1876
FID C 10 1877
FID C 10 1878
FID C 10 1879
FID C 10 1880
FID C 10 1881
FID C 10 1882
FID C 10 1883
FID C 10 1884
FID C 10 1885
FID C 10 1886
FID C 10 1887
SNT TRC
FID C 3 2820
FID C 3 2821
SNT TRC
FID C 3 2823
FID C 3 2824
# NET 454
NET SMA3_LED_GREEN_N 
SNT TOP T 120 14
FID C 4 1061
FID C 5 641
FID C 3 2811
SNT TOP T 314 0
FID C 4 1064
FID C 5 642
FID C 3 2818
SNT VIA
FID H 0 1252
FID C 4 1063
FID C 6 647
FID C 3 2817
FID C 10 1850
FID C 8 1917
FID L 11 639
FID L 12 639
FID L 13 623
FID L 14 588
FID L 15 639
FID L 16 639
SNT VIA
FID H 0 1945
FID C 4 1062
FID C 6 646
FID C 3 2816
FID C 10 1849
FID C 8 1916
FID L 11 638
FID L 12 638
FID L 13 622
FID L 14 587
FID L 15 638
FID L 16 638
SNT TRC
FID C 10 1819
FID C 10 1820
FID C 10 1821
FID C 10 1822
FID C 10 1823
FID C 10 1824
FID C 10 1825
FID C 10 1826
FID C 10 1827
FID C 10 1828
FID C 10 1829
FID C 10 1830
FID C 10 1831
FID C 10 1832
FID C 10 1833
FID C 10 1834
FID C 10 1835
FID C 10 1836
FID C 10 1837
FID C 10 1838
FID C 10 1839
FID C 10 1840
FID C 10 1841
FID C 10 1842
FID C 10 1843
FID C 10 1844
FID C 10 1845
FID C 10 1846
FID C 10 1847
FID C 10 1848
SNT TRC
FID C 3 2812
FID C 3 2813
SNT TRC
FID C 3 2814
FID C 3 2815
# NET 455
NET SMA3_LED_RED_N 
SNT TOP T 120 15
FID C 4 1057
FID C 5 639
FID C 3 2804
SNT TOP T 312 0
FID C 4 1060
FID C 5 640
FID C 3 2810
SNT VIA
FID H 0 1253
FID C 4 1059
FID C 6 645
FID C 3 2809
FID C 10 1818
FID C 8 1915
FID L 11 637
FID L 12 637
FID L 13 621
FID L 14 586
FID L 15 637
FID L 16 637
SNT VIA
FID H 0 1946
FID C 4 1058
FID C 6 644
FID C 3 2805
FID C 10 1817
FID C 8 1914
FID L 11 636
FID L 12 636
FID L 13 620
FID L 14 585
FID L 15 636
FID L 16 636
SNT TRC
FID C 10 1777
FID C 10 1778
FID C 10 1779
FID C 10 1780
FID C 10 1781
FID C 10 1782
FID C 10 1783
FID C 10 1784
FID C 10 1785
FID C 10 1786
FID C 10 1787
FID C 10 1788
FID C 10 1789
FID C 10 1790
FID C 10 1791
FID C 10 1792
FID C 10 1793
FID C 10 1794
FID C 10 1795
FID C 10 1796
FID C 10 1797
FID C 10 1798
FID C 10 1799
FID C 10 1800
FID C 10 1801
FID C 10 1802
FID C 10 1803
FID C 10 1804
FID C 10 1805
FID C 10 1806
FID C 10 1807
FID C 10 1808
FID C 10 1809
FID C 10 1810
FID C 10 1811
FID C 10 1812
FID C 10 1813
FID C 10 1814
FID C 10 1815
FID C 10 1816
SNT TRC
FID C 3 2806
FID C 3 2807
SNT TRC
FID C 3 2808
# NET 456
NET SMA4_LED_BLUE_N 
SNT TOP T 120 20
FID C 4 1044
FID C 5 631
FID C 3 2767
SNT TOP T 294 0
FID C 4 1047
FID C 5 632
FID C 3 2774
SNT VIA
FID H 0 711
FID C 4 1046
FID C 6 638
FID C 3 2773
FID C 10 1725
FID C 8 1906
FID L 11 628
FID L 12 628
FID L 13 612
FID L 14 577
FID L 15 628
FID L 16 628
SNT VIA
FID H 0 2267
FID C 4 1045
FID C 6 637
FID C 3 2772
FID C 10 1724
FID C 8 1905
FID L 11 627
FID L 12 627
FID L 13 611
FID L 14 576
FID L 15 627
FID L 16 627
SNT TRC
FID C 10 1683
FID C 10 1684
FID C 10 1685
FID C 10 1686
FID C 10 1687
FID C 10 1688
FID C 10 1689
FID C 10 1690
FID C 10 1691
FID C 10 1692
FID C 10 1693
FID C 10 1694
FID C 10 1695
FID C 10 1696
FID C 10 1697
FID C 10 1698
FID C 10 1699
FID C 10 1700
FID C 10 1701
FID C 10 1702
FID C 10 1703
FID C 10 1704
FID C 10 1705
FID C 10 1706
FID C 10 1707
FID C 10 1708
FID C 10 1709
FID C 10 1710
FID C 10 1711
FID C 10 1712
FID C 10 1713
FID C 10 1714
FID C 10 1715
FID C 10 1716
FID C 10 1717
FID C 10 1718
FID C 10 1719
FID C 10 1720
FID C 10 1721
FID C 10 1722
FID C 10 1723
SNT TRC
FID C 3 2768
FID C 3 2769
SNT TRC
FID C 3 2770
FID C 3 2771
# NET 457
NET SMA4_LED_GREEN_N 
SNT TOP T 120 18
FID C 4 1040
FID C 5 629
FID C 3 2760
SNT TOP T 317 0
FID C 4 1043
FID C 5 630
FID C 3 2766
SNT VIA
FID H 0 712
FID C 4 1042
FID C 6 636
FID C 3 2765
FID C 10 1682
FID C 8 1904
FID L 11 626
FID L 12 626
FID L 13 610
FID L 14 575
FID L 15 626
FID L 16 626
SNT VIA
FID H 0 2268
FID C 4 1041
FID C 6 635
FID C 3 2763
FID C 10 1681
FID C 8 1903
FID L 11 625
FID L 12 625
FID L 13 609
FID L 14 574
FID L 15 625
FID L 16 625
SNT TRC
FID C 10 1647
FID C 10 1648
FID C 10 1649
FID C 10 1650
FID C 10 1651
FID C 10 1652
FID C 10 1653
FID C 10 1654
FID C 10 1655
FID C 10 1656
FID C 10 1657
FID C 10 1658
FID C 10 1659
FID C 10 1660
FID C 10 1661
FID C 10 1662
FID C 10 1663
FID C 10 1664
FID C 10 1665
FID C 10 1666
FID C 10 1667
FID C 10 1668
FID C 10 1669
FID C 10 1670
FID C 10 1671
FID C 10 1672
FID C 10 1673
FID C 10 1674
FID C 10 1675
FID C 10 1676
FID C 10 1677
FID C 10 1678
FID C 10 1679
FID C 10 1680
SNT TRC
FID C 3 2761
FID C 3 2762
SNT TRC
FID C 3 2764
# NET 458
NET SMA4_LED_RED_N 
SNT TOP T 120 19
FID C 4 1036
FID C 5 627
FID C 3 2753
SNT TOP T 315 0
FID C 4 1039
FID C 5 628
FID C 3 2759
SNT VIA
FID H 0 713
FID C 4 1038
FID C 6 634
FID C 3 2757
FID C 10 1646
FID C 8 1902
FID L 11 624
FID L 12 624
FID L 13 608
FID L 14 573
FID L 15 624
FID L 16 624
SNT VIA
FID H 0 2269
FID C 4 1037
FID C 6 633
FID C 3 2756
FID C 10 1645
FID C 8 1901
FID L 11 623
FID L 12 623
FID L 13 607
FID L 14 572
FID L 15 623
FID L 16 623
SNT TRC
FID C 10 1610
FID C 10 1611
FID C 10 1612
FID C 10 1613
FID C 10 1614
FID C 10 1615
FID C 10 1616
FID C 10 1617
FID C 10 1618
FID C 10 1619
FID C 10 1620
FID C 10 1621
FID C 10 1622
FID C 10 1623
FID C 10 1624
FID C 10 1625
FID C 10 1626
FID C 10 1627
FID C 10 1628
FID C 10 1629
FID C 10 1630
FID C 10 1631
FID C 10 1632
FID C 10 1633
FID C 10 1634
FID C 10 1635
FID C 10 1636
FID C 10 1637
FID C 10 1638
FID C 10 1639
FID C 10 1640
FID C 10 1641
FID C 10 1642
FID C 10 1643
FID C 10 1644
SNT TRC
FID C 3 2754
FID C 3 2755
SNT TRC
FID C 3 2758
# NET 459
NET GPS_SMA_LED_BLUE_N 
SNT TOP T 120 23
FID C 4 1129
FID C 5 673
FID C 3 2948
SNT TOP T 289 0
FID C 4 1132
FID C 5 674
FID C 3 2954
SNT VIA
FID H 0 310
FID C 4 1131
FID C 6 687
FID C 3 2953
FID C 10 2109
FID C 8 2122
FID L 11 683
FID L 12 683
FID L 13 667
FID L 14 632
FID L 15 683
FID L 16 683
SNT VIA
FID H 0 2243
FID C 4 1130
FID C 6 686
FID C 3 2951
FID C 10 2108
FID C 8 2121
FID L 11 682
FID L 12 682
FID L 13 666
FID L 14 631
FID L 15 682
FID L 16 682
SNT TRC
FID C 10 2070
FID C 10 2071
FID C 10 2072
FID C 10 2073
FID C 10 2074
FID C 10 2075
FID C 10 2076
FID C 10 2077
FID C 10 2078
FID C 10 2079
FID C 10 2080
FID C 10 2081
FID C 10 2082
FID C 10 2083
FID C 10 2084
FID C 10 2085
FID C 10 2086
FID C 10 2087
FID C 10 2088
FID C 10 2089
FID C 10 2090
FID C 10 2091
FID C 10 2092
FID C 10 2093
FID C 10 2094
FID C 10 2095
FID C 10 2096
FID C 10 2097
FID C 10 2098
FID C 10 2099
FID C 10 2100
FID C 10 2101
FID C 10 2102
FID C 10 2103
FID C 10 2104
FID C 10 2105
FID C 10 2106
FID C 10 2107
SNT TRC
FID C 3 2949
FID C 3 2950
SNT TRC
FID C 3 2952
# NET 460
NET GPS_SMA_LED_GREEN_N 
SNT TOP T 120 21
FID C 4 1125
FID C 5 671
FID C 3 2941
SNT TOP T 288 0
FID C 4 1128
FID C 5 672
FID C 3 2947
SNT VIA
FID H 0 311
FID C 4 1127
FID C 6 685
FID C 3 2946
FID C 10 2069
FID C 8 2120
FID L 11 681
FID L 12 681
FID L 13 665
FID L 14 630
FID L 15 681
FID L 16 681
SNT VIA
FID H 0 2244
FID C 4 1126
FID C 6 684
FID C 3 2944
FID C 10 2068
FID C 8 2119
FID L 11 680
FID L 12 680
FID L 13 664
FID L 14 629
FID L 15 680
FID L 16 680
SNT TRC
FID C 10 2043
FID C 10 2044
FID C 10 2045
FID C 10 2046
FID C 10 2047
FID C 10 2048
FID C 10 2049
FID C 10 2050
FID C 10 2051
FID C 10 2052
FID C 10 2053
FID C 10 2054
FID C 10 2055
FID C 10 2056
FID C 10 2057
FID C 10 2058
FID C 10 2059
FID C 10 2060
FID C 10 2061
FID C 10 2062
FID C 10 2063
FID C 10 2064
FID C 10 2065
FID C 10 2066
FID C 10 2067
SNT TRC
FID C 3 2942
FID C 3 2943
SNT TRC
FID C 3 2945
# NET 461
NET GPS_SMA_LED_RED_N 
SNT TOP T 120 22
FID C 4 1121
FID C 5 669
FID C 3 2935
SNT TOP T 284 0
FID C 4 1124
FID C 5 670
FID C 3 2940
SNT VIA
FID H 0 312
FID C 4 1123
FID C 6 683
FID C 3 2939
FID C 10 2042
FID C 8 2118
FID L 11 679
FID L 12 679
FID L 13 663
FID L 14 628
FID L 15 679
FID L 16 679
SNT VIA
FID H 0 2245
FID C 4 1122
FID C 6 682
FID C 3 2937
FID C 10 2041
FID C 8 2117
FID L 11 678
FID L 12 678
FID L 13 662
FID L 14 627
FID L 15 678
FID L 16 678
SNT TRC
FID C 10 2008
FID C 10 2009
FID C 10 2010
FID C 10 2011
FID C 10 2012
FID C 10 2013
FID C 10 2014
FID C 10 2015
FID C 10 2016
FID C 10 2017
FID C 10 2018
FID C 10 2019
FID C 10 2020
FID C 10 2021
FID C 10 2022
FID C 10 2023
FID C 10 2024
FID C 10 2025
FID C 10 2026
FID C 10 2027
FID C 10 2028
FID C 10 2029
FID C 10 2030
FID C 10 2031
FID C 10 2032
FID C 10 2033
FID C 10 2034
FID C 10 2035
FID C 10 2036
FID C 10 2037
FID C 10 2038
FID C 10 2039
FID C 10 2040
SNT TRC
FID C 3 2936
SNT TRC
FID C 3 2938
# NET 462
NET FPGA_OUT_SMA4_LED_BLUE_N 
SNT TOP T 170 150
FID C 4 842
FID C 5 514
FID C 3 2227
SNT TOP T 295 0
FID C 4 843
FID C 5 515
FID C 3 2229
SNT VIA
FID H 0 1162
FID C 4 841
FID C 6 516
FID C 3 2226
FID C 10 1043
FID C 8 1496
FID L 11 512
FID L 12 512
FID L 13 496
FID L 14 461
FID L 15 512
FID L 16 512
SNT VIA
FID H 0 2135
FID C 3 2225
FID C 10 1042
FID C 8 1495
FID L 11 511
FID L 12 511
FID L 13 495
FID L 14 460
FID L 15 511
FID L 16 511
SNT TRC
FID C 10 1009
FID C 10 1010
FID C 10 1011
FID C 10 1012
FID C 10 1013
FID C 10 1014
FID C 10 1015
FID C 10 1016
FID C 10 1017
FID C 10 1018
FID C 10 1019
FID C 10 1020
FID C 10 1021
FID C 10 1022
FID C 10 1023
FID C 10 1024
FID C 10 1025
FID C 10 1026
FID C 10 1027
FID C 10 1028
FID C 10 1029
FID C 10 1030
FID C 10 1031
FID C 10 1032
FID C 10 1033
FID C 10 1034
FID C 10 1035
FID C 10 1036
FID C 10 1037
FID C 10 1038
FID C 10 1039
FID C 10 1040
FID C 10 1041
SNT TRC
FID C 3 2223
FID C 3 2224
SNT TRC
FID C 3 2228
# NET 463
NET FPGA_OUT_SMA4_LED_GREEN_N 
SNT TOP T 170 128
FID C 4 839
FID C 5 512
FID C 3 2220
SNT TOP T 316 0
FID C 4 840
FID C 5 513
FID C 3 2222
SNT VIA
FID H 0 1163
FID C 4 838
FID C 6 515
FID C 3 2219
FID C 10 1008
FID C 8 1494
FID L 11 510
FID L 12 510
FID L 13 494
FID L 14 459
FID L 15 510
FID L 16 510
SNT VIA
FID H 0 2136
FID C 3 2218
FID C 10 1007
FID C 8 1493
FID L 11 509
FID L 12 509
FID L 13 493
FID L 14 458
FID L 15 509
FID L 16 509
SNT TRC
FID C 10 978
FID C 10 979
FID C 10 980
FID C 10 981
FID C 10 982
FID C 10 983
FID C 10 984
FID C 10 985
FID C 10 986
FID C 10 987
FID C 10 988
FID C 10 989
FID C 10 990
FID C 10 991
FID C 10 992
FID C 10 993
FID C 10 994
FID C 10 995
FID C 10 996
FID C 10 997
FID C 10 998
FID C 10 999
FID C 10 1000
FID C 10 1001
FID C 10 1002
FID C 10 1003
FID C 10 1004
FID C 10 1005
FID C 10 1006
SNT TRC
FID C 3 2216
FID C 3 2217
SNT TRC
FID C 3 2221
# NET 464
NET R_LM75B_2_I2C_SDA 
SNT TOP T 186 0
FID C 4 966
FID C 5 588
FID C 3 2523
SNT TOP T 346 1
FID C 4 967
FID C 5 589
FID C 3 2531
SNT VIA
FID H 0 2254
FID C 4 968
FID C 6 586
FID C 3 2532
FID C 8 1689
FID L 11 574
FID L 12 574
FID L 13 558
FID L 14 523
FID L 15 574
FID L 16 574
SNT TRC
FID C 3 2524
FID C 3 2525
FID C 3 2526
FID C 3 2527
SNT TRC
FID C 3 2528
FID C 3 2529
FID C 3 2530
# NET 465
NET R_LM75B_3_I2C_SDA 
SNT TOP T 188 0
FID C 4 965
FID C 5 587
FID C 3 2522
SNT TOP T 422 1
FID C 4 963
FID C 5 586
FID C 3 2516
SNT VIA
FID H 0 1217
FID C 4 964
FID C 6 585
FID C 3 2521
FID C 8 1688
FID L 11 573
FID L 12 573
FID L 13 557
FID L 14 522
FID L 15 573
FID L 16 573
SNT TRC
FID C 3 2517
FID C 3 2518
SNT TRC
FID C 3 2519
FID C 3 2520
# NET 466
NET UNNAMED_6_LM75BDPTSSOP8_I59_A2 
SNT TOP T 186 4
FID C 4 954
FID C 5 580
FID C 3 2492
SNT TOP T 342 1
FID C 4 956
FID C 5 581
FID C 3 2498
SNT TOP B 212 0
FID C 6 572
FID C 7 168
FID C 8 1650
SNT VIA
FID H 0 2284
FID C 4 955
FID C 6 571
FID C 3 2497
FID C 8 1649
FID L 11 570
FID L 12 570
FID L 13 554
FID L 14 519
FID L 15 570
FID L 16 570
SNT TRC
FID C 3 2493
FID C 3 2494
SNT TRC
FID C 8 1647
FID C 8 1648
SNT TRC
FID C 3 2495
FID C 3 2496
# NET 467
NET UNNAMED_6_LM75BDPTSSOP8_I81_A2 
SNT TOP T 188 4
FID C 4 945
FID C 5 574
FID C 3 2477
SNT TOP T 413 1
FID C 4 947
FID C 5 575
FID C 3 2479
SNT TOP B 338 0
FID C 6 565
FID C 7 165
FID C 8 1639
SNT VIA
FID H 0 1335
FID C 4 946
FID C 6 566
FID C 3 2478
FID C 8 1640
FID L 11 567
FID L 12 567
FID L 13 551
FID L 14 516
FID L 15 567
FID L 16 567
SNT TRC
FID C 3 2473
FID C 3 2474
FID C 3 2475
SNT TRC
FID C 3 2476
SNT TRC
FID C 8 1638
# NET 468
NET UNNAMED_6_LM75BDPTSSOP8_I59_A1 
SNT TOP T 186 5
FID C 4 957
FID C 5 582
FID C 3 2499
SNT TOP T 343 1
FID C 4 959
FID C 5 583
FID C 3 2506
SNT TOP B 213 0
FID C 6 574
FID C 7 169
FID C 8 1654
SNT VIA
FID H 0 2283
FID C 4 958
FID C 6 573
FID C 3 2505
FID C 8 1653
FID L 11 571
FID L 12 571
FID L 13 555
FID L 14 520
FID L 15 571
FID L 16 571
SNT TRC
FID C 8 1651
FID C 8 1652
SNT TRC
FID C 3 2500
FID C 3 2501
SNT TRC
FID C 3 2502
FID C 3 2503
FID C 3 2504
# NET 469
NET UNNAMED_6_LM75BDPTSSOP8_I81_A1 
SNT TOP T 188 5
FID C 4 948
FID C 5 576
FID C 3 2483
SNT TOP T 412 1
FID C 4 950
FID C 5 577
FID C 3 2485
SNT TOP B 337 0
FID C 6 567
FID C 7 166
FID C 8 1642
SNT VIA
FID H 0 1334
FID C 4 949
FID C 6 568
FID C 3 2484
FID C 8 1643
FID L 11 568
FID L 12 568
FID L 13 552
FID L 14 517
FID L 15 568
FID L 16 568
SNT TRC
FID C 3 2480
FID C 3 2481
SNT TRC
FID C 3 2482
SNT TRC
FID C 8 1641
# NET 470
NET UNNAMED_6_LM75BDPTSSOP8_I59_A0 
SNT TOP T 186 6
FID C 4 960
FID C 5 584
FID C 3 2507
SNT TOP T 344 1
FID C 4 962
FID C 5 585
FID C 3 2515
SNT TOP B 226 0
FID C 6 576
FID C 7 170
FID C 8 1658
SNT VIA
FID H 0 2282
FID C 4 961
FID C 6 575
FID C 3 2514
FID C 8 1657
FID L 11 572
FID L 12 572
FID L 13 556
FID L 14 521
FID L 15 572
FID L 16 572
SNT TRC
FID C 3 2508
FID C 3 2509
FID C 3 2510
FID C 3 2511
SNT TRC
FID C 3 2512
FID C 3 2513
SNT TRC
FID C 8 1655
FID C 8 1656
# NET 471
NET UNNAMED_6_LM75BDPTSSOP8_I81_A0 
SNT TOP T 188 6
FID C 4 952
FID C 5 579
FID C 3 2490
SNT TOP T 411 1
FID C 4 951
FID C 5 578
FID C 3 2489
SNT TOP B 336 0
FID C 6 569
FID C 7 167
FID C 8 1645
SNT VIA
FID H 0 1333
FID C 4 953
FID C 6 570
FID C 3 2491
FID C 8 1646
FID L 11 569
FID L 12 569
FID L 13 553
FID L 14 518
FID L 15 569
FID L 16 569
SNT TRC
FID C 3 2486
FID C 3 2487
SNT TRC
FID C 3 2488
SNT TRC
FID C 8 1644
# NET 472
NET FPGA_IN_LM75B_INT2_N 
SNT TOP T 41 0
FID H 0 146
FID C 6 590
FID C 3 2560
FID C 9 1098
FID C 8 1695
FID L 11 580
FID L 12 580
FID L 13 564
FID L 14 529
FID L 15 580
FID L 16 580
SNT TOP T 170 307
FID C 4 973
FID C 5 593
FID C 3 2547
SNT TOP T 186 2
FID C 4 976
FID C 5 595
FID C 3 2559
SNT TOP T 347 1
FID C 4 975
FID C 5 594
FID C 3 2551
SNT VIA
FID H 0 230
FID C 4 974
FID C 6 589
FID C 3 2549
FID C 9 1097
FID C 10 1407
FID C 8 1693
FID L 11 578
FID L 12 578
FID L 13 562
FID L 14 527
FID L 15 578
FID L 16 578
SNT VIA
FID H 0 2109
FID C 3 2550
FID C 10 1408
FID C 8 1694
FID L 11 579
FID L 12 579
FID L 13 563
FID L 14 528
FID L 15 579
FID L 16 579
SNT TRC
FID C 10 1391
FID C 10 1392
FID C 10 1393
FID C 10 1394
FID C 10 1395
FID C 10 1396
FID C 10 1397
FID C 10 1398
FID C 10 1399
FID C 10 1400
FID C 10 1401
FID C 10 1402
FID C 10 1403
FID C 10 1404
FID C 10 1405
FID C 10 1406
SNT TRC
FID C 9 1089
FID C 9 1090
FID C 9 1091
FID C 9 1092
FID C 9 1093
FID C 9 1094
FID C 9 1095
FID C 9 1096
SNT TRC
FID C 3 2548
SNT TRC
FID C 3 2552
FID C 3 2553
SNT TRC
FID C 3 2554
FID C 3 2555
FID C 3 2556
FID C 3 2557
FID C 3 2558
# NET 473
NET FPGA_IN_LM75B_INT3_N 
SNT TOP T 42 0
FID H 0 145
FID C 6 587
FID C 3 2541
FID C 10 1389
FID C 8 1690
FID L 11 575
FID L 12 575
FID L 13 559
FID L 14 524
FID L 15 575
FID L 16 575
SNT TOP T 170 303
FID C 4 971
FID C 5 592
FID C 3 2544
SNT TOP T 188 2
FID C 4 970
FID C 5 591
FID C 3 2542
SNT TOP T 414 1
FID C 4 969
FID C 5 590
FID C 3 2540
SNT VIA
FID H 0 1407
FID C 4 972
FID C 6 588
FID C 3 2546
FID C 9 1088
FID C 10 1390
FID C 8 1692
FID L 11 577
FID L 12 577
FID L 13 561
FID L 14 526
FID L 15 577
FID L 16 577
SNT VIA
FID H 0 2110
FID C 3 2543
FID C 9 1087
FID C 8 1691
FID L 11 576
FID L 12 576
FID L 13 560
FID L 14 525
FID L 15 576
FID L 16 576
SNT TRC
FID C 3 2533
FID C 3 2534
FID C 3 2535
FID C 3 2536
FID C 3 2537
SNT TRC
FID C 3 2538
FID C 3 2539
SNT TRC
FID C 9 1059
FID C 9 1060
FID C 9 1061
FID C 9 1062
FID C 9 1063
FID C 9 1064
FID C 9 1065
FID C 9 1066
FID C 9 1067
FID C 9 1068
FID C 9 1069
FID C 9 1070
FID C 9 1071
FID C 9 1072
FID C 9 1073
FID C 9 1074
FID C 9 1075
FID C 9 1076
FID C 9 1077
FID C 9 1078
FID C 9 1079
FID C 9 1080
FID C 9 1081
FID C 9 1082
FID C 9 1083
FID C 9 1084
FID C 9 1085
FID C 9 1086
SNT TRC
FID C 10 1367
FID C 10 1368
FID C 10 1369
FID C 10 1370
FID C 10 1371
FID C 10 1372
FID C 10 1373
FID C 10 1374
FID C 10 1375
FID C 10 1376
FID C 10 1377
FID C 10 1378
FID C 10 1379
FID C 10 1380
FID C 10 1381
FID C 10 1382
FID C 10 1383
FID C 10 1384
FID C 10 1385
FID C 10 1386
FID C 10 1387
FID C 10 1388
SNT TRC
FID C 3 2545
# NET 474
NET FPGA_OUT_SMA4_LED_RED_N 
SNT TOP T 170 171
FID C 4 837
FID C 5 511
FID C 3 2214
SNT TOP T 293 0
FID C 4 835
FID C 5 510
FID C 3 2211
SNT VIA
FID H 0 1164
FID C 4 836
FID C 6 514
FID C 3 2213
FID C 10 977
FID C 8 1492
FID L 11 508
FID L 12 508
FID L 13 492
FID L 14 457
FID L 15 508
FID L 16 508
SNT VIA
FID H 0 2137
FID C 3 2212
FID C 10 976
FID C 8 1491
FID L 11 507
FID L 12 507
FID L 13 491
FID L 14 456
FID L 15 507
FID L 16 507
SNT TRC
FID C 10 946
FID C 10 947
FID C 10 948
FID C 10 949
FID C 10 950
FID C 10 951
FID C 10 952
FID C 10 953
FID C 10 954
FID C 10 955
FID C 10 956
FID C 10 957
FID C 10 958
FID C 10 959
FID C 10 960
FID C 10 961
FID C 10 962
FID C 10 963
FID C 10 964
FID C 10 965
FID C 10 966
FID C 10 967
FID C 10 968
FID C 10 969
FID C 10 970
FID C 10 971
FID C 10 972
FID C 10 973
FID C 10 974
FID C 10 975
SNT TRC
FID C 3 2207
FID C 3 2208
FID C 3 2209
FID C 3 2210
SNT TRC
FID C 3 2215
# NET 475
NET FPGA_OUT_GPS_LED_BLUE_N 
SNT TOP T 170 85
FID C 4 892
FID C 5 539
FID C 3 2328
SNT TOP T 286 0
FID C 4 889
FID C 5 538
FID C 3 2323
SNT VIA
FID H 0 254
FID C 4 891
FID C 6 542
FID C 3 2326
FID C 9 1058
FID C 10 1366
FID C 8 1606
FID L 11 548
FID L 12 548
FID L 13 532
FID L 14 497
FID L 15 548
FID L 16 548
SNT VIA
FID H 0 1147
FID C 4 890
FID C 6 541
FID C 3 2324
FID C 9 1057
FID C 8 1604
FID L 11 546
FID L 12 546
FID L 13 530
FID L 14 495
FID L 15 546
FID L 16 546
SNT VIA
FID H 0 2121
FID C 3 2325
FID C 10 1365
FID C 8 1605
FID L 11 547
FID L 12 547
FID L 13 531
FID L 14 496
FID L 15 547
FID L 16 547
SNT TRC
FID C 10 1342
FID C 10 1343
FID C 10 1344
FID C 10 1345
FID C 10 1346
FID C 10 1347
FID C 10 1348
FID C 10 1349
FID C 10 1350
FID C 10 1351
FID C 10 1352
FID C 10 1353
FID C 10 1354
FID C 10 1355
FID C 10 1356
FID C 10 1357
FID C 10 1358
FID C 10 1359
FID C 10 1360
FID C 10 1361
FID C 10 1362
FID C 10 1363
FID C 10 1364
SNT TRC
FID C 9 1045
FID C 9 1046
FID C 9 1047
FID C 9 1048
FID C 9 1049
FID C 9 1050
FID C 9 1051
FID C 9 1052
FID C 9 1053
FID C 9 1054
FID C 9 1055
FID C 9 1056
SNT TRC
FID C 3 2319
FID C 3 2320
FID C 3 2321
FID C 3 2322
SNT TRC
FID C 3 2327
# NET 476
NET FPGA_OUT_GPS_LED_GREEN_N 
SNT TOP T 170 19
FID C 4 887
FID C 5 537
FID C 3 2317
SNT TOP T 287 0
FID C 4 885
FID C 5 536
FID C 3 2313
SNT VIA
FID H 0 255
FID C 4 886
FID C 6 538
FID C 3 2314
FID C 9 1043
FID C 8 1601
FID L 11 543
FID L 12 543
FID L 13 527
FID L 14 492
FID L 15 543
FID L 16 543
SNT VIA
FID H 0 256
FID C 4 888
FID C 6 540
FID C 3 2318
FID C 9 1044
FID C 10 1341
FID C 8 1603
FID L 11 545
FID L 12 545
FID L 13 529
FID L 14 494
FID L 15 545
FID L 16 545
SNT VIA
FID H 0 2218
FID C 6 539
FID C 3 2316
FID C 10 1340
FID C 8 1602
FID L 11 544
FID L 12 544
FID L 13 528
FID L 14 493
FID L 15 544
FID L 16 544
SNT TRC
FID C 9 1029
FID C 9 1030
FID C 9 1031
FID C 9 1032
FID C 9 1033
FID C 9 1034
FID C 9 1035
FID C 9 1036
FID C 9 1037
FID C 9 1038
FID C 9 1039
FID C 9 1040
FID C 9 1041
FID C 9 1042
SNT TRC
FID C 10 1318
FID C 10 1319
FID C 10 1320
FID C 10 1321
FID C 10 1322
FID C 10 1323
FID C 10 1324
FID C 10 1325
FID C 10 1326
FID C 10 1327
FID C 10 1328
FID C 10 1329
FID C 10 1330
FID C 10 1331
FID C 10 1332
FID C 10 1333
FID C 10 1334
FID C 10 1335
FID C 10 1336
FID C 10 1337
FID C 10 1338
FID C 10 1339
SNT TRC
FID C 3 2310
FID C 3 2311
FID C 3 2312
SNT TRC
FID C 3 2315
# NET 477
NET FPGA_OUT_GPS_LED_RED_N 
SNT TOP T 170 17
FID C 4 883
FID C 5 535
FID C 3 2308
SNT TOP T 285 0
FID C 4 880
FID C 5 534
FID C 3 2304
SNT VIA
FID H 0 257
FID C 4 881
FID C 6 535
FID C 3 2305
FID C 9 1027
FID C 8 1598
FID L 11 540
FID L 12 540
FID L 13 524
FID L 14 489
FID L 15 540
FID L 16 540
SNT VIA
FID H 0 258
FID C 4 884
FID C 6 537
FID C 3 2309
FID C 9 1028
FID C 10 1317
FID C 8 1600
FID L 11 542
FID L 12 542
FID L 13 526
FID L 14 491
FID L 15 542
FID L 16 542
SNT VIA
FID H 0 1148
FID C 4 882
FID C 6 536
FID C 3 2306
FID C 10 1316
FID C 8 1599
FID L 11 541
FID L 12 541
FID L 13 525
FID L 14 490
FID L 15 541
FID L 16 541
SNT TRC
FID C 9 1002
FID C 9 1003
FID C 9 1004
FID C 9 1005
FID C 9 1006
FID C 9 1007
FID C 9 1008
FID C 9 1009
FID C 9 1010
FID C 9 1011
FID C 9 1012
FID C 9 1013
FID C 9 1014
FID C 9 1015
FID C 9 1016
FID C 9 1017
FID C 9 1018
FID C 9 1019
FID C 9 1020
FID C 9 1021
FID C 9 1022
FID C 9 1023
FID C 9 1024
FID C 9 1025
FID C 9 1026
SNT TRC
FID C 10 1298
FID C 10 1299
FID C 10 1300
FID C 10 1301
FID C 10 1302
FID C 10 1303
FID C 10 1304
FID C 10 1305
FID C 10 1306
FID C 10 1307
FID C 10 1308
FID C 10 1309
FID C 10 1310
FID C 10 1311
FID C 10 1312
FID C 10 1313
FID C 10 1314
FID C 10 1315
SNT TRC
FID C 3 2302
FID C 3 2303
SNT TRC
FID C 3 2307
# NET 478
NET FPGA_IO_FT_USBDET_RST_N 
SNT TOP T 170 36
FID C 4 603
FID C 5 381
FID C 3 1627
SNT TOP T 238 1
FID C 4 604
FID C 5 382
FID C 3 1628
SNT VIA
FID H 0 248
FID C 4 602
FID C 6 363
FID C 3 1624
FID C 9 867
FID C 8 928
FID L 11 394
FID L 12 394
FID L 13 378
FID L 14 343
FID L 15 394
FID L 16 394
SNT VIA
FID H 0 1141
FID C 4 605
FID C 6 364
FID C 3 1629
FID C 8 930
FID L 11 396
FID L 12 396
FID L 13 380
FID L 14 345
FID L 15 396
FID L 16 396
SNT VIA
FID H 0 2117
FID C 3 1626
FID C 9 868
FID C 8 929
FID L 11 395
FID L 12 395
FID L 13 379
FID L 14 344
FID L 15 395
FID L 16 395
SNT TRC
FID C 9 850
FID C 9 851
FID C 9 852
FID C 9 853
FID C 9 854
FID C 9 855
FID C 9 856
FID C 9 857
FID C 9 858
FID C 9 859
FID C 9 860
FID C 9 861
FID C 9 862
FID C 9 863
FID C 9 864
FID C 9 865
FID C 9 866
SNT TRC
FID C 8 925
FID C 8 926
FID C 8 927
SNT TRC
FID C 3 1620
FID C 3 1621
FID C 3 1622
FID C 3 1623
SNT TRC
FID C 3 1625
# NET 479
NET FTDI_EE_DO 
SNT TOP B 107 3
FID C 6 268
FID C 7 89
FID C 8 601
SNT TOP B 160 1
FID C 6 267
FID C 7 88
FID C 8 600
SNT TOP B 348 1
FID C 6 266
FID C 7 87
FID C 8 597
SNT VIA
FID C 6 265
FID C 8 596
SNT TRC
FID C 8 592
FID C 8 593
SNT TRC
FID C 8 594
FID C 8 595
SNT TRC
FID C 8 598
FID C 8 599
# NET 480
NET FTDI_EE_CS 
SNT TOP T 13 62
FID C 4 481
FID C 5 325
FID C 3 1270
SNT TOP B 107 0
FID C 6 273
FID C 7 92
FID C 8 622
SNT TOP B 159 1
FID C 6 274
FID C 7 93
FID C 8 623
SNT VIA
FID H 0 1187
FID C 4 482
FID C 6 272
FID C 3 1271
FID C 8 621
FID L 11 322
FID L 12 322
FID L 13 306
FID L 14 271
FID L 15 322
FID L 16 322
SNT TRC
FID C 3 1227
FID C 3 1228
FID C 3 1229
FID C 3 1230
FID C 3 1231
FID C 3 1232
FID C 3 1233
FID C 3 1234
FID C 3 1235
FID C 3 1236
FID C 3 1237
FID C 3 1238
FID C 3 1239
FID C 3 1240
FID C 3 1241
FID C 3 1242
FID C 3 1243
FID C 3 1244
FID C 3 1245
FID C 3 1246
FID C 3 1247
FID C 3 1248
FID C 3 1249
FID C 3 1250
FID C 3 1251
FID C 3 1252
FID C 3 1253
FID C 3 1254
FID C 3 1255
FID C 3 1256
FID C 3 1257
FID C 3 1258
FID C 3 1259
FID C 3 1260
FID C 3 1261
FID C 3 1262
FID C 3 1263
FID C 3 1264
FID C 3 1265
FID C 3 1266
FID C 3 1267
FID C 3 1268
FID C 3 1269
SNT TRC
FID C 8 618
FID C 8 619
SNT TRC
FID C 8 620
# NET 481
NET FTDI_EE_CLK 
SNT TOP T 13 61
FID C 4 483
FID C 5 326
FID C 3 1315
SNT TOP B 107 1
FID C 6 276
FID C 7 94
FID C 8 628
SNT TOP B 158 1
FID C 6 277
FID C 7 95
FID C 8 629
SNT VIA
FID H 0 1186
FID C 4 484
FID C 6 275
FID C 3 1316
FID C 8 627
FID L 11 323
FID L 12 323
FID L 13 307
FID L 14 272
FID L 15 323
FID L 16 323
SNT TRC
FID C 3 1272
FID C 3 1273
FID C 3 1274
FID C 3 1275
FID C 3 1276
FID C 3 1277
FID C 3 1278
FID C 3 1279
FID C 3 1280
FID C 3 1281
FID C 3 1282
FID C 3 1283
FID C 3 1284
FID C 3 1285
FID C 3 1286
FID C 3 1287
FID C 3 1288
FID C 3 1289
FID C 3 1290
FID C 3 1291
FID C 3 1292
FID C 3 1293
FID C 3 1294
FID C 3 1295
FID C 3 1296
FID C 3 1297
FID C 3 1298
FID C 3 1299
FID C 3 1300
FID C 3 1301
FID C 3 1302
FID C 3 1303
FID C 3 1304
FID C 3 1305
FID C 3 1306
FID C 3 1307
FID C 3 1308
FID C 3 1309
FID C 3 1310
FID C 3 1311
FID C 3 1312
FID C 3 1313
FID C 3 1314
SNT TRC
FID C 8 624
FID C 8 625
SNT TRC
FID C 8 626
# NET 482
NET MUX1_SEL 
SNT TOP T 6 0
FID C 4 48
FID C 5 35
FID C 3 160
SNT TOP T 50 0
FID H 0 115
FID C 6 30
FID C 3 159
FID C 8 56
FID L 11 22
FID L 12 22
FID L 13 22
FID L 14 22
FID L 15 22
FID L 16 22
SNT TOP T 232 0
FID C 4 49
FID C 5 36
FID C 3 161
SNT TOP T 233 0
FID C 4 50
FID C 5 37
FID C 3 163
SNT TOP B 131 0
FID C 6 31
FID C 7 13
FID C 8 57
SNT TOP B 153 0
FID C 6 32
FID C 7 14
FID C 8 59
SNT TRC
FID C 8 54
FID C 8 55
SNT TRC
FID C 3 155
FID C 3 156
SNT TRC
FID C 3 157
FID C 3 158
SNT TRC
FID C 3 162
SNT TRC
FID C 8 58
# NET 483
NET FPGA_OUT_MUX1_SEL 
SNT TOP T 170 210
FID C 4 598
FID C 5 379
FID C 3 1616
SNT TOP T 233 1
FID C 4 601
FID C 5 380
FID C 3 1619
SNT VIA
FID H 0 260
FID C 4 599
FID C 6 361
FID C 3 1617
FID C 9 848
FID C 8 923
FID L 11 392
FID L 12 392
FID L 13 376
FID L 14 341
FID L 15 392
FID L 16 392
SNT VIA
FID H 0 261
FID C 4 597
FID C 6 360
FID C 3 1614
FID C 9 847
FID C 8 922
FID L 11 391
FID L 12 391
FID L 13 375
FID L 14 340
FID L 15 391
FID L 16 391
SNT VIA
FID H 0 1150
FID C 4 600
FID C 6 362
FID C 3 1618
FID C 9 849
FID C 8 924
FID L 11 393
FID L 12 393
FID L 13 377
FID L 14 342
FID L 15 393
FID L 16 393
SNT VIA
FID H 0 2122
FID C 3 1609
FID C 9 809
FID C 8 921
FID L 11 390
FID L 12 390
FID L 13 374
FID L 14 339
FID L 15 390
FID L 16 390
SNT TRC
FID C 9 810
FID C 9 811
FID C 9 812
FID C 9 813
FID C 9 814
FID C 9 815
FID C 9 816
FID C 9 817
FID C 9 818
FID C 9 819
FID C 9 820
FID C 9 821
FID C 9 822
FID C 9 823
FID C 9 824
FID C 9 825
FID C 9 826
FID C 9 827
FID C 9 828
FID C 9 829
FID C 9 830
FID C 9 831
FID C 9 832
SNT TRC
FID C 9 833
FID C 9 834
FID C 9 835
FID C 9 836
FID C 9 837
FID C 9 838
FID C 9 839
FID C 9 840
FID C 9 841
FID C 9 842
FID C 9 843
FID C 9 844
FID C 9 845
FID C 9 846
SNT TRC
FID C 3 1610
FID C 3 1611
FID C 3 1612
SNT TRC
FID C 3 1613
SNT TRC
FID C 3 1615
# NET 484
NET FT4232_MUX1_SEL 
SNT TOP T 13 20
FID C 4 530
FID C 5 347
FID C 3 1449
SNT TOP T 232 1
FID C 4 532
FID C 5 348
FID C 3 1451
SNT VIA
FID H 0 295
FID C 4 529
FID C 6 308
FID C 3 1448
FID C 9 508
FID C 8 735
FID L 11 348
FID L 12 348
FID L 13 332
FID L 14 297
FID L 15 348
FID L 16 348
SNT VIA
FID H 0 1174
FID C 4 531
FID C 6 309
FID C 3 1450
FID C 9 509
FID C 8 736
FID L 11 349
FID L 12 349
FID L 13 333
FID L 14 298
FID L 15 349
FID L 16 349
SNT TRC
FID C 9 487
FID C 9 488
FID C 9 489
FID C 9 490
FID C 9 491
FID C 9 492
FID C 9 493
FID C 9 494
FID C 9 495
FID C 9 496
FID C 9 497
FID C 9 498
FID C 9 499
FID C 9 500
FID C 9 501
FID C 9 502
FID C 9 503
FID C 9 504
FID C 9 505
FID C 9 506
FID C 9 507
SNT TRC
FID C 3 1446
SNT TRC
FID C 3 1447
# NET 485
NET SEC_EEPROM_SDA 
SNT TOP T 7 4
FID C 4 431
FID C 5 296
FID C 3 1014
SNT TOP B 331 1
FID C 6 230
FID C 7 74
FID C 8 532
SNT VIA
FID H 0 1224
FID C 4 430
FID C 6 231
FID C 3 1013
FID C 8 533
FID L 11 299
FID L 12 299
FID L 13 283
FID L 14 248
FID L 15 299
FID L 16 299
SNT TRC
FID C 8 530
FID C 8 531
SNT TRC
FID C 3 1011
FID C 3 1012
# NET 486
NET FTDI_EE_DAT 
SNT TOP T 13 60
FID C 4 480
FID C 5 324
FID C 3 1226
SNT TOP B 107 2
FID C 6 271
FID C 7 91
FID C 8 617
SNT TOP B 348 0
FID C 6 269
FID C 7 90
FID C 8 615
SNT VIA
FID H 0 1188
FID C 4 479
FID C 6 270
FID C 3 1225
FID C 8 616
FID L 11 321
FID L 12 321
FID L 13 305
FID L 14 270
FID L 15 321
FID L 16 321
SNT TRC
FID C 8 602
FID C 8 603
FID C 8 604
FID C 8 605
FID C 8 606
FID C 8 607
FID C 8 608
FID C 8 609
FID C 8 610
FID C 8 611
FID C 8 612
SNT TRC
FID C 8 613
FID C 8 614
SNT TRC
FID C 3 1220
FID C 3 1221
FID C 3 1222
FID C 3 1223
FID C 3 1224
# NET 487
NET XP3R3V_FT_PG 
SNT TOP T 115 3
FID C 4 235
FID C 5 205
FID C 3 656
SNT TOP T 237 0
FID C 4 237
FID C 5 206
FID C 3 661
SNT VIA
FID H 0 1034
FID C 4 238
FID C 6 74
FID C 3 662
FID C 8 287
FID L 11 184
FID L 12 184
FID L 13 184
FID L 14 184
FID L 15 184
FID L 16 184
SNT VIA
FID H 0 1390
FID C 4 236
FID C 6 73
FID C 3 660
FID C 8 286
FID L 11 183
FID L 12 183
FID L 13 183
FID L 14 183
FID L 15 183
FID L 16 183
SNT TRC
FID C 8 269
FID C 8 270
FID C 8 271
FID C 8 272
FID C 8 273
FID C 8 274
FID C 8 275
FID C 8 276
FID C 8 277
FID C 8 278
FID C 8 279
FID C 8 280
FID C 8 281
FID C 8 282
FID C 8 283
FID C 8 284
FID C 8 285
SNT TRC
FID C 3 657
FID C 3 658
FID C 3 659
SNT TRC
FID C 3 663
FID C 3 664
# NET 488
NET MUX2_SEL 
SNT TOP T 2 5
FID C 4 47
FID C 5 34
FID C 3 154
SNT TOP T 3 5
FID C 4 43
FID C 5 30
FID C 3 150
SNT TOP T 5 0
FID C 4 44
FID C 5 31
FID C 3 151
SNT TOP T 51 0
FID H 0 106
FID C 6 27
FID C 3 149
FID C 8 50
FID L 11 21
FID L 12 21
FID L 13 21
FID L 14 21
FID L 15 21
FID L 16 21
SNT TOP T 230 1
FID C 4 46
FID C 5 33
FID C 3 153
SNT TOP T 231 1
FID C 4 45
FID C 5 32
FID C 3 152
SNT TOP B 130 1
FID C 6 28
FID C 7 11
FID C 8 51
SNT TOP B 152 1
FID C 6 29
FID C 7 12
FID C 8 53
SNT TRC
FID C 3 133
FID C 3 134
FID C 3 135
FID C 3 136
FID C 3 137
SNT TRC
FID C 8 48
FID C 8 49
SNT TRC
FID C 3 138
FID C 3 139
FID C 3 140
SNT TRC
FID C 3 141
FID C 3 142
FID C 3 143
SNT TRC
FID C 3 144
FID C 3 145
FID C 3 146
SNT TRC
FID C 3 147
SNT TRC
FID C 3 148
SNT TRC
FID C 8 52
# NET 489
NET UNNAMED_524_RESISTOR_I432_2 
SNT TOP T 5 14
FID C 4 363
FID C 5 253
FID C 3 846
SNT TOP T 235 1
FID C 4 364
FID C 5 254
FID C 3 847
SNT VIA
FID H 0 1318
FID C 4 362
FID C 6 181
FID C 3 844
FID C 8 441
FID L 11 264
FID L 12 264
FID L 13 248
FID L 14 213
FID L 15 264
FID L 16 264
SNT TRC
FID C 3 842
FID C 3 843
SNT TRC
FID C 3 845
# NET 490
NET XP12R0V_A_ISET 
SNT TOP T 189 4
FID C 4 2113
FID C 5 1267
FID C 3 5329
SNT TOP T 331 1
FID C 4 2115
FID C 5 1268
FID C 3 5333
SNT VIA
FID H 0 1348
FID C 4 2114
FID C 6 1451
FID C 3 5330
FID C 8 3776
FID L 11 1227
FID L 12 1227
FID L 13 1069
FID L 14 1019
FID L 15 1227
FID L 16 1227
SNT TRC
FID C 3 5331
FID C 3 5332
SNT TRC
FID C 3 5334
FID C 3 5335
# NET 491
NET UNNAMED_524_FT4232HLREELQFP64_7 
SNT TOP T 13 13
FID C 4 372
FID C 5 260
FID C 3 871
SNT TOP B 151 1
FID C 6 184
FID C 7 58
FID C 8 446
SNT VIA
FID H 0 1316
FID C 4 371
FID C 6 185
FID C 3 870
FID C 8 447
FID L 11 267
FID L 12 267
FID L 13 251
FID L 14 216
FID L 15 267
FID L 16 267
SNT TRC
FID C 8 444
FID C 8 445
SNT TRC
FID C 3 868
FID C 3 869
# NET 492
NET FPGA_OUT_MUX2_SEL 
SNT TOP T 170 188
FID C 4 593
FID C 5 377
FID C 3 1605
SNT TOP T 231 0
FID C 4 596
FID C 5 378
FID C 3 1608
SNT VIA
FID H 0 262
FID C 4 594
FID C 6 358
FID C 3 1606
FID C 9 807
FID C 8 919
FID L 11 388
FID L 12 388
FID L 13 372
FID L 14 337
FID L 15 388
FID L 16 388
SNT VIA
FID H 0 263
FID C 4 592
FID C 6 357
FID C 3 1603
FID C 9 806
FID C 8 918
FID L 11 387
FID L 12 387
FID L 13 371
FID L 14 336
FID L 15 387
FID L 16 387
SNT VIA
FID H 0 1151
FID C 4 595
FID C 6 359
FID C 3 1607
FID C 9 808
FID C 8 920
FID L 11 389
FID L 12 389
FID L 13 373
FID L 14 338
FID L 15 389
FID L 16 389
SNT VIA
FID H 0 2123
FID C 3 1597
FID C 9 778
FID C 8 917
FID L 11 386
FID L 12 386
FID L 13 370
FID L 14 335
FID L 15 386
FID L 16 386
SNT TRC
FID C 3 1598
FID C 3 1599
FID C 3 1600
FID C 3 1601
SNT TRC
FID C 3 1602
SNT TRC
FID C 9 779
FID C 9 780
FID C 9 781
FID C 9 782
SNT TRC
FID C 9 783
FID C 9 784
FID C 9 785
FID C 9 786
FID C 9 787
FID C 9 788
FID C 9 789
FID C 9 790
FID C 9 791
FID C 9 792
FID C 9 793
FID C 9 794
FID C 9 795
FID C 9 796
FID C 9 797
FID C 9 798
FID C 9 799
FID C 9 800
FID C 9 801
FID C 9 802
FID C 9 803
FID C 9 804
FID C 9 805
SNT TRC
FID C 3 1604
# NET 493
NET FT4232_MUX2_SEL 
SNT TOP T 13 21
FID C 4 528
FID C 5 346
FID C 3 1445
SNT TOP T 230 0
FID C 4 526
FID C 5 345
FID C 3 1441
SNT VIA
FID H 0 296
FID C 4 527
FID C 6 307
FID C 3 1442
FID C 9 486
FID C 8 734
FID L 11 347
FID L 12 347
FID L 13 331
FID L 14 296
FID L 15 347
FID L 16 347
SNT VIA
FID H 0 1175
FID C 4 525
FID C 6 306
FID C 3 1440
FID C 9 485
FID C 8 733
FID L 11 346
FID L 12 346
FID L 13 330
FID L 14 295
FID L 15 346
FID L 16 346
SNT TRC
FID C 9 461
FID C 9 462
FID C 9 463
FID C 9 464
FID C 9 465
FID C 9 466
FID C 9 467
FID C 9 468
FID C 9 469
FID C 9 470
FID C 9 471
FID C 9 472
FID C 9 473
FID C 9 474
FID C 9 475
FID C 9 476
FID C 9 477
FID C 9 478
FID C 9 479
FID C 9 480
FID C 9 481
FID C 9 482
FID C 9 483
FID C 9 484
SNT TRC
FID C 3 1439
SNT TRC
FID C 3 1443
FID C 3 1444
# NET 494
NET UNNAMED_524_FT4232HLREELQFP64_6 
SNT TOP T 13 5
FID C 4 374
FID C 5 261
FID C 3 875
SNT TOP B 349 0
FID C 6 186
FID C 7 59
FID C 8 450
SNT VIA
FID H 0 1315
FID C 4 373
FID C 6 187
FID C 3 874
FID C 8 451
FID L 11 268
FID L 12 268
FID L 13 252
FID L 14 217
FID L 15 268
FID L 16 268
SNT TRC
FID C 8 448
FID C 8 449
SNT TRC
FID C 3 872
FID C 3 873
# NET 495
NET R_FT4232_TDO 
SNT TOP T 13 17
FID C 4 439
FID C 5 302
FID C 3 1052
SNT TOP B 139 0
FID C 6 235
FID C 7 77
FID C 8 546
SNT TOP B 156 0
FID C 6 234
FID C 7 76
FID C 8 544
SNT VIA
FID H 0 1214
FID C 4 438
FID C 6 236
FID C 3 1051
FID C 8 547
FID L 11 301
FID L 12 301
FID L 13 285
FID L 14 250
FID L 15 301
FID L 16 301
SNT TRC
FID C 3 1049
FID C 3 1050
SNT TRC
FID C 8 539
FID C 8 540
FID C 8 541
FID C 8 542
FID C 8 543
SNT TRC
FID C 8 545
# NET 496
NET R_FT4232_TCK 
SNT TOP T 13 15
FID C 4 443
FID C 5 304
FID C 3 1064
SNT TOP B 141 0
FID C 6 239
FID C 7 79
FID C 8 556
SNT VIA
FID H 0 1212
FID C 4 442
FID C 6 240
FID C 3 1063
FID C 8 557
FID L 11 303
FID L 12 303
FID L 13 287
FID L 14 252
FID L 15 303
FID L 16 303
SNT TRC
FID C 3 1060
FID C 3 1061
FID C 3 1062
SNT TRC
FID C 8 554
FID C 8 555
# NET 497
NET FT4232_TCK_SCLK 
SNT TOP T 6 3
FID C 4 503
FID C 5 334
FID C 3 1351
SNT TOP B 141 1
FID C 6 294
FID C 7 101
FID C 8 665
SNT VIA
FID H 0 302
FID C 4 504
FID C 6 295
FID C 3 1352
FID C 9 418
FID C 8 666
FID L 11 335
FID L 12 335
FID L 13 319
FID L 14 284
FID L 15 335
FID L 16 335
SNT VIA
FID H 0 1181
FID C 4 502
FID C 6 293
FID C 3 1350
FID C 9 417
FID C 8 664
FID L 11 334
FID L 12 334
FID L 13 318
FID L 14 283
FID L 15 334
FID L 16 334
SNT TRC
FID C 9 333
FID C 9 334
FID C 9 335
FID C 9 336
FID C 9 337
FID C 9 338
FID C 9 339
FID C 9 340
FID C 9 341
FID C 9 342
FID C 9 343
FID C 9 344
FID C 9 345
FID C 9 346
FID C 9 347
FID C 9 348
FID C 9 349
FID C 9 350
FID C 9 351
FID C 9 352
FID C 9 353
FID C 9 354
FID C 9 355
FID C 9 356
FID C 9 357
FID C 9 358
FID C 9 359
FID C 9 360
FID C 9 361
FID C 9 362
FID C 9 363
FID C 9 364
FID C 9 365
FID C 9 366
FID C 9 367
FID C 9 368
FID C 9 369
FID C 9 370
FID C 9 371
FID C 9 372
FID C 9 373
FID C 9 374
FID C 9 375
FID C 9 376
FID C 9 377
FID C 9 378
FID C 9 379
FID C 9 380
FID C 9 381
FID C 9 382
FID C 9 383
FID C 9 384
FID C 9 385
FID C 9 386
FID C 9 387
FID C 9 388
FID C 9 389
FID C 9 390
FID C 9 391
FID C 9 392
FID C 9 393
FID C 9 394
FID C 9 395
FID C 9 396
FID C 9 397
FID C 9 398
FID C 9 399
FID C 9 400
FID C 9 401
FID C 9 402
FID C 9 403
FID C 9 404
FID C 9 405
FID C 9 406
FID C 9 407
FID C 9 408
FID C 9 409
FID C 9 410
FID C 9 411
FID C 9 412
FID C 9 413
FID C 9 414
FID C 9 415
FID C 9 416
SNT TRC
FID C 3 1348
FID C 3 1349
SNT TRC
FID C 8 661
FID C 8 662
FID C 8 663
# NET 498
NET R_FT4232_TDI 
SNT TOP T 13 16
FID C 4 441
FID C 5 303
FID C 3 1059
SNT TOP B 140 0
FID C 6 237
FID C 7 78
FID C 8 552
SNT VIA
FID H 0 1213
FID C 4 440
FID C 6 238
FID C 3 1058
FID C 8 553
FID L 11 302
FID L 12 302
FID L 13 286
FID L 14 251
FID L 15 302
FID L 16 302
SNT TRC
FID C 3 1053
FID C 3 1054
FID C 3 1055
FID C 3 1056
FID C 3 1057
SNT TRC
FID C 8 548
FID C 8 549
FID C 8 550
FID C 8 551
# NET 499
NET FT4232_TDI_MOSI 
SNT TOP T 6 6
FID C 4 500
FID C 5 333
FID C 3 1346
SNT TOP B 140 1
FID C 6 292
FID C 7 100
FID C 8 660
SNT VIA
FID H 0 303
FID C 4 501
FID C 6 291
FID C 3 1347
FID C 9 332
FID C 8 659
FID L 11 333
FID L 12 333
FID L 13 317
FID L 14 282
FID L 15 333
FID L 16 333
SNT VIA
FID H 0 1182
FID C 4 499
FID C 6 290
FID C 3 1345
FID C 9 331
FID C 8 655
FID L 11 332
FID L 12 332
FID L 13 316
FID L 14 281
FID L 15 332
FID L 16 332
SNT TRC
FID C 9 258
FID C 9 259
FID C 9 260
FID C 9 261
FID C 9 262
FID C 9 263
FID C 9 264
FID C 9 265
FID C 9 266
FID C 9 267
FID C 9 268
FID C 9 269
FID C 9 270
FID C 9 271
FID C 9 272
FID C 9 273
FID C 9 274
FID C 9 275
FID C 9 276
FID C 9 277
FID C 9 278
FID C 9 279
FID C 9 280
FID C 9 281
FID C 9 282
FID C 9 283
FID C 9 284
FID C 9 285
FID C 9 286
FID C 9 287
FID C 9 288
FID C 9 289
FID C 9 290
FID C 9 291
FID C 9 292
FID C 9 293
FID C 9 294
FID C 9 295
FID C 9 296
FID C 9 297
FID C 9 298
FID C 9 299
FID C 9 300
FID C 9 301
FID C 9 302
FID C 9 303
FID C 9 304
FID C 9 305
FID C 9 306
FID C 9 307
FID C 9 308
FID C 9 309
FID C 9 310
FID C 9 311
FID C 9 312
FID C 9 313
FID C 9 314
FID C 9 315
FID C 9 316
FID C 9 317
FID C 9 318
FID C 9 319
FID C 9 320
FID C 9 321
FID C 9 322
FID C 9 323
FID C 9 324
FID C 9 325
FID C 9 326
FID C 9 327
FID C 9 328
FID C 9 329
FID C 9 330
SNT TRC
FID C 3 1343
FID C 3 1344
SNT TRC
FID C 8 656
FID C 8 657
FID C 8 658
# NET 500
NET FT4232_TDO_MISO 
SNT TOP T 6 8
FID C 4 497
FID C 5 332
FID C 3 1341
SNT TOP B 139 1
FID C 6 289
FID C 7 99
FID C 8 654
SNT VIA
FID H 0 304
FID C 4 498
FID C 6 288
FID C 3 1342
FID C 9 257
FID C 8 653
FID L 11 331
FID L 12 331
FID L 13 315
FID L 14 280
FID L 15 331
FID L 16 331
SNT VIA
FID H 0 1183
FID C 4 496
FID C 6 287
FID C 3 1340
FID C 9 256
FID C 8 652
FID L 11 330
FID L 12 330
FID L 13 314
FID L 14 279
FID L 15 330
FID L 16 330
SNT TRC
FID C 9 211
FID C 9 212
FID C 9 213
FID C 9 214
FID C 9 215
FID C 9 216
FID C 9 217
FID C 9 218
FID C 9 219
FID C 9 220
FID C 9 221
FID C 9 222
FID C 9 223
FID C 9 224
FID C 9 225
FID C 9 226
FID C 9 227
FID C 9 228
FID C 9 229
FID C 9 230
FID C 9 231
FID C 9 232
FID C 9 233
FID C 9 234
FID C 9 235
FID C 9 236
FID C 9 237
FID C 9 238
FID C 9 239
FID C 9 240
FID C 9 241
FID C 9 242
FID C 9 243
FID C 9 244
FID C 9 245
FID C 9 246
FID C 9 247
FID C 9 248
FID C 9 249
FID C 9 250
FID C 9 251
FID C 9 252
FID C 9 253
FID C 9 254
FID C 9 255
SNT TRC
FID C 8 648
FID C 8 649
FID C 8 650
FID C 8 651
SNT TRC
FID C 3 1337
FID C 3 1338
FID C 3 1339
# NET 501
NET R_FT4232_TMS 
SNT TOP T 13 18
FID C 4 437
FID C 5 301
FID C 3 1048
SNT TOP B 138 0
FID C 6 232
FID C 7 75
FID C 8 537
SNT VIA
FID H 0 1215
FID C 4 436
FID C 6 233
FID C 3 1047
FID C 8 538
FID L 11 300
FID L 12 300
FID L 13 284
FID L 14 249
FID L 15 300
FID L 16 300
SNT TRC
FID C 3 1044
FID C 3 1045
FID C 3 1046
SNT TRC
FID C 8 534
FID C 8 535
FID C 8 536
# NET 502
NET FT4232_TMS_SPICS_N 
SNT TOP T 6 11
FID C 4 494
FID C 5 331
FID C 3 1335
SNT TOP B 138 1
FID C 6 285
FID C 7 98
FID C 8 646
SNT VIA
FID H 0 305
FID C 4 495
FID C 6 286
FID C 3 1336
FID C 9 210
FID C 8 647
FID L 11 329
FID L 12 329
FID L 13 313
FID L 14 278
FID L 15 329
FID L 16 329
SNT VIA
FID H 0 1184
FID C 4 493
FID C 6 284
FID C 3 1334
FID C 9 209
FID C 8 644
FID L 11 328
FID L 12 328
FID L 13 312
FID L 14 277
FID L 15 328
FID L 16 328
SNT TRC
FID C 9 176
FID C 9 177
FID C 9 178
FID C 9 179
FID C 9 180
FID C 9 181
FID C 9 182
FID C 9 183
FID C 9 184
FID C 9 185
FID C 9 186
FID C 9 187
FID C 9 188
FID C 9 189
FID C 9 190
FID C 9 191
FID C 9 192
FID C 9 193
FID C 9 194
FID C 9 195
FID C 9 196
FID C 9 197
FID C 9 198
FID C 9 199
FID C 9 200
FID C 9 201
FID C 9 202
FID C 9 203
FID C 9 204
FID C 9 205
FID C 9 206
FID C 9 207
FID C 9 208
SNT TRC
FID C 3 1332
FID C 3 1333
SNT TRC
FID C 8 645
# NET 503
NET R_FT4232_I2C_SCL 
SNT TOP T 13 25
FID C 4 450
FID C 5 308
FID C 3 1088
SNT TOP T 229 0
FID C 4 451
FID C 5 309
FID C 3 1089
SNT VIA
FID H 0 1209
FID C 4 449
FID C 6 244
FID C 3 1087
FID C 8 562
FID L 11 306
FID L 12 306
FID L 13 290
FID L 14 255
FID L 15 306
FID L 16 306
SNT TRC
FID C 3 1080
FID C 3 1081
FID C 3 1082
FID C 3 1083
FID C 3 1084
SNT TRC
FID C 3 1085
FID C 3 1086
# NET 504
NET FT4232_I2C_SCL 
SNT TOP T 4 5
FID C 4 543
FID C 5 353
FID C 3 1475
SNT TOP T 4 12
FID C 4 542
FID C 5 352
FID C 3 1473
SNT TOP T 229 1
FID C 4 546
FID C 5 354
FID C 3 1478
SNT TOP B 155 0
FID C 6 319
FID C 7 104
FID C 8 778
SNT VIA
FID H 0 289
FID C 4 540
FID C 6 316
FID C 3 1467
FID C 9 556
FID C 8 760
FID L 11 354
FID L 12 354
FID L 13 338
FID L 14 303
FID L 15 354
FID L 16 354
SNT VIA
FID H 0 290
FID C 4 544
FID C 6 318
FID C 3 1476
FID C 10 246
FID C 8 777
FID L 11 356
FID L 12 356
FID L 13 340
FID L 14 305
FID L 15 356
FID L 16 356
SNT VIA
FID H 0 291
FID C 4 545
FID C 6 320
FID C 3 1477
FID C 9 582
FID C 8 779
FID L 11 357
FID L 12 357
FID L 13 341
FID L 14 306
FID L 15 357
FID L 16 357
SNT VIA
FID H 0 1172
FID C 4 541
FID C 6 317
FID C 3 1472
FID C 10 245
FID C 8 776
FID L 11 355
FID L 12 355
FID L 13 339
FID L 14 304
FID L 15 355
FID L 16 355
SNT TRC
FID C 10 218
FID C 10 219
FID C 10 220
FID C 10 221
FID C 10 222
FID C 10 223
FID C 10 224
FID C 10 225
FID C 10 226
FID C 10 227
FID C 10 228
FID C 10 229
FID C 10 230
FID C 10 231
FID C 10 232
FID C 10 233
FID C 10 234
FID C 10 235
FID C 10 236
FID C 10 237
FID C 10 238
FID C 10 239
FID C 10 240
FID C 10 241
FID C 10 242
FID C 10 243
FID C 10 244
SNT TRC
FID C 9 557
FID C 9 558
FID C 9 559
FID C 9 560
FID C 9 561
FID C 9 562
FID C 9 563
FID C 9 564
FID C 9 565
FID C 9 566
FID C 9 567
FID C 9 568
FID C 9 569
FID C 9 570
FID C 9 571
FID C 9 572
FID C 9 573
FID C 9 574
FID C 9 575
FID C 9 576
FID C 9 577
FID C 9 578
FID C 9 579
FID C 9 580
FID C 9 581
SNT TRC
FID C 8 761
FID C 8 762
FID C 8 763
FID C 8 764
FID C 8 765
FID C 8 766
FID C 8 767
FID C 8 768
FID C 8 769
FID C 8 770
FID C 8 771
FID C 8 772
FID C 8 773
SNT TRC
FID C 3 1468
FID C 3 1469
SNT TRC
FID C 8 774
FID C 8 775
SNT TRC
FID C 3 1470
FID C 3 1471
SNT TRC
FID C 3 1474
# NET 505
NET R_FT4232_I2C_SDA_OUT 
SNT TOP T 13 26
FID C 4 445
FID C 5 305
FID C 3 1072
SNT TOP T 228 0
FID C 4 446
FID C 5 306
FID C 3 1073
SNT VIA
FID H 0 1211
FID C 4 444
FID C 6 241
FID C 3 1071
FID C 8 558
FID L 11 304
FID L 12 304
FID L 13 288
FID L 14 253
FID L 15 304
FID L 16 304
SNT TRC
FID C 3 1065
FID C 3 1066
FID C 3 1067
FID C 3 1068
SNT TRC
FID C 3 1069
FID C 3 1070
# NET 506
NET FT4232_I2C_SDA 
SNT TOP T 4 2
FID C 4 537
FID C 5 350
FID C 3 1464
SNT TOP T 4 9
FID C 4 535
FID C 5 349
FID C 3 1460
SNT TOP T 228 1
FID C 4 538
FID C 5 351
FID C 3 1465
SNT TOP B 137 1
FID C 6 314
FID C 7 102
FID C 8 757
SNT TOP B 154 0
FID C 6 315
FID C 7 103
FID C 8 758
SNT VIA
FID H 0 292
FID C 4 533
FID C 6 310
FID C 3 1456
FID C 9 554
FID C 8 739
FID L 11 350
FID L 12 350
FID L 13 334
FID L 14 299
FID L 15 350
FID L 16 350
SNT VIA
FID H 0 293
FID C 4 536
FID C 6 312
FID C 3 1463
FID C 10 217
FID C 8 755
FID L 11 352
FID L 12 352
FID L 13 336
FID L 14 301
FID L 15 352
FID L 16 352
SNT VIA
FID H 0 294
FID C 4 539
FID C 6 313
FID C 3 1466
FID C 9 555
FID C 8 756
FID L 11 353
FID L 12 353
FID L 13 337
FID L 14 302
FID L 15 353
FID L 16 353
SNT VIA
FID H 0 1173
FID C 4 534
FID C 6 311
FID C 3 1459
FID C 10 216
FID C 8 754
FID L 11 351
FID L 12 351
FID L 13 335
FID L 14 300
FID L 15 351
FID L 16 351
SNT TRC
FID C 9 510
FID C 9 511
FID C 9 512
FID C 9 513
FID C 9 514
FID C 9 515
FID C 9 516
FID C 9 517
FID C 9 518
FID C 9 519
FID C 9 520
FID C 9 521
FID C 9 522
FID C 9 523
FID C 9 524
FID C 9 525
FID C 9 526
FID C 9 527
FID C 9 528
FID C 9 529
FID C 9 530
FID C 9 531
FID C 9 532
FID C 9 533
FID C 9 534
FID C 9 535
FID C 9 536
FID C 9 537
FID C 9 538
FID C 9 539
FID C 9 540
FID C 9 541
FID C 9 542
FID C 9 543
FID C 9 544
FID C 9 545
FID C 9 546
FID C 9 547
FID C 9 548
FID C 9 549
FID C 9 550
FID C 9 551
FID C 9 552
FID C 9 553
SNT TRC
FID C 3 1452
FID C 3 1453
FID C 3 1454
FID C 3 1455
SNT TRC
FID C 8 737
FID C 8 738
SNT TRC
FID C 8 740
FID C 8 741
FID C 8 742
FID C 8 743
FID C 8 744
FID C 8 745
FID C 8 746
FID C 8 747
FID C 8 748
FID C 8 749
FID C 8 750
FID C 8 751
FID C 8 752
FID C 8 753
SNT TRC
FID C 10 210
FID C 10 211
FID C 10 212
FID C 10 213
FID C 10 214
FID C 10 215
SNT TRC
FID C 3 1457
FID C 3 1458
SNT TRC
FID C 3 1461
FID C 3 1462
SNT TRC
FID C 8 759
# NET 507
NET R_FT4232_I2C_SDA_IN 
SNT TOP T 13 27
FID C 4 448
FID C 5 307
FID C 3 1079
SNT TOP B 137 0
FID C 6 242
FID C 7 80
FID C 8 560
SNT VIA
FID H 0 1210
FID C 4 447
FID C 6 243
FID C 3 1078
FID C 8 561
FID L 11 305
FID L 12 305
FID L 13 289
FID L 14 254
FID L 15 305
FID L 16 305
SNT TRC
FID C 3 1074
FID C 3 1075
FID C 3 1076
FID C 3 1077
SNT TRC
FID C 8 559
# NET 508
NET FPGA_PCA9546_I2C_SDA 
SNT TOP T 4 1
FID C 4 579
FID C 5 369
FID C 3 1550
SNT TOP T 170 389
FID C 4 576
FID C 5 367
FID C 3 1544
SNT TOP T 246 1
FID C 4 578
FID C 5 368
FID C 3 1549
SNT VIA
FID H 0 277
FID C 4 575
FID C 6 347
FID C 3 1541
FID C 10 466
FID C 8 877
FID L 11 374
FID L 12 374
FID L 13 358
FID L 14 323
FID L 15 374
FID L 16 374
SNT VIA
FID H 0 1167
FID C 4 577
FID C 6 348
FID C 3 1548
FID C 8 879
FID L 11 376
FID L 12 376
FID L 13 360
FID L 14 325
FID L 15 376
FID L 16 376
SNT VIA
FID H 0 2370
FID C 3 1543
FID C 10 467
FID C 8 878
FID L 11 375
FID L 12 375
FID L 13 359
FID L 14 324
FID L 15 375
FID L 16 375
SNT TRC
FID C 10 461
FID C 10 462
FID C 10 463
FID C 10 464
FID C 10 465
SNT TRC
FID C 8 842
FID C 8 843
FID C 8 844
FID C 8 845
FID C 8 846
FID C 8 847
FID C 8 848
FID C 8 849
FID C 8 850
FID C 8 851
FID C 8 852
FID C 8 853
FID C 8 854
FID C 8 855
FID C 8 856
FID C 8 857
FID C 8 858
FID C 8 859
FID C 8 860
FID C 8 861
FID C 8 862
FID C 8 863
FID C 8 864
FID C 8 865
FID C 8 866
FID C 8 867
FID C 8 868
FID C 8 869
FID C 8 870
FID C 8 871
FID C 8 872
FID C 8 873
FID C 8 874
FID C 8 875
FID C 8 876
SNT TRC
FID C 3 1539
FID C 3 1540
SNT TRC
FID C 3 1542
SNT TRC
FID C 3 1545
FID C 3 1546
FID C 3 1547
# NET 509
NET FPGA_PCA9546_I2C_SCL 
SNT TOP T 4 4
FID C 4 584
FID C 5 372
FID C 3 1565
SNT TOP T 170 324
FID C 4 581
FID C 5 370
FID C 3 1562
SNT TOP T 245 1
FID C 4 583
FID C 5 371
FID C 3 1564
SNT VIA
FID H 0 276
FID C 4 580
FID C 6 349
FID C 3 1559
FID C 10 476
FID C 8 902
FID L 11 377
FID L 12 377
FID L 13 361
FID L 14 326
FID L 15 377
FID L 16 377
SNT VIA
FID H 0 1166
FID C 4 582
FID C 6 350
FID C 3 1563
FID C 8 904
FID L 11 379
FID L 12 379
FID L 13 363
FID L 14 328
FID L 15 379
FID L 16 379
SNT VIA
FID H 0 2369
FID C 3 1561
FID C 10 477
FID C 8 903
FID L 11 378
FID L 12 378
FID L 13 362
FID L 14 327
FID L 15 378
FID L 16 378
SNT TRC
FID C 8 880
FID C 8 881
FID C 8 882
FID C 8 883
FID C 8 884
FID C 8 885
FID C 8 886
FID C 8 887
FID C 8 888
FID C 8 889
FID C 8 890
FID C 8 891
FID C 8 892
FID C 8 893
FID C 8 894
FID C 8 895
FID C 8 896
FID C 8 897
FID C 8 898
FID C 8 899
FID C 8 900
FID C 8 901
SNT TRC
FID C 10 468
FID C 10 469
FID C 10 470
FID C 10 471
FID C 10 472
FID C 10 473
FID C 10 474
FID C 10 475
SNT TRC
FID C 3 1551
FID C 3 1552
FID C 3 1553
SNT TRC
FID C 3 1554
FID C 3 1555
FID C 3 1556
FID C 3 1557
FID C 3 1558
SNT TRC
FID C 3 1560
# NET 510
NET FPGA_EEPROM_I2C_SDA 
SNT TOP T 4 10
FID C 4 673
FID C 5 413
FID C 3 1803
SNT TOP T 170 60
FID C 4 675
FID C 5 415
FID C 3 1805
SNT TOP T 244 1
FID C 4 674
FID C 5 414
FID C 3 1804
SNT VIA
FID H 0 1116
FID C 4 672
FID C 6 418
FID C 3 1795
FID C 8 1148
FID L 11 436
FID L 12 436
FID L 13 420
FID L 14 385
FID L 15 436
FID L 16 436
SNT TRC
FID C 3 1778
FID C 3 1779
FID C 3 1780
FID C 3 1781
FID C 3 1782
FID C 3 1783
FID C 3 1784
FID C 3 1785
FID C 3 1786
FID C 3 1787
FID C 3 1788
FID C 3 1789
FID C 3 1790
FID C 3 1791
SNT TRC
FID C 3 1792
FID C 3 1793
FID C 3 1794
SNT TRC
FID C 3 1796
FID C 3 1797
FID C 3 1798
FID C 3 1799
FID C 3 1800
FID C 3 1801
FID C 3 1802
# NET 511
NET FPGA_EEPROM_I2C_SCL 
SNT TOP T 4 13
FID C 4 678
FID C 5 417
FID C 3 1845
SNT TOP T 170 59
FID C 4 679
FID C 5 418
FID C 3 1846
SNT TOP T 243 1
FID C 4 677
FID C 5 416
FID C 3 1844
SNT VIA
FID H 0 1115
FID C 4 676
FID C 6 419
FID C 3 1838
FID C 8 1149
FID L 11 437
FID L 12 437
FID L 13 421
FID L 14 386
FID L 15 437
FID L 16 437
SNT TRC
FID C 3 1806
FID C 3 1807
FID C 3 1808
FID C 3 1809
FID C 3 1810
FID C 3 1811
FID C 3 1812
FID C 3 1813
FID C 3 1814
FID C 3 1815
FID C 3 1816
FID C 3 1817
FID C 3 1818
FID C 3 1819
FID C 3 1820
FID C 3 1821
FID C 3 1822
FID C 3 1823
FID C 3 1824
FID C 3 1825
FID C 3 1826
FID C 3 1827
FID C 3 1828
FID C 3 1829
FID C 3 1830
FID C 3 1831
FID C 3 1832
FID C 3 1833
FID C 3 1834
SNT TRC
FID C 3 1835
FID C 3 1836
FID C 3 1837
SNT TRC
FID C 3 1839
FID C 3 1840
FID C 3 1841
FID C 3 1842
FID C 3 1843
# NET 512
NET MUX3_SEL 
SNT TOP T 4 0
FID C 4 40
FID C 5 27
FID C 3 130
SNT TOP T 52 0
FID H 0 105
FID C 6 24
FID C 3 129
FID C 8 45
FID L 11 20
FID L 12 20
FID L 13 20
FID L 14 20
FID L 15 20
FID L 16 20
SNT TOP T 226 1
FID C 4 42
FID C 5 29
FID C 3 132
SNT TOP T 227 1
FID C 4 41
FID C 5 28
FID C 3 131
SNT TOP B 129 1
FID C 6 25
FID C 7 9
FID C 8 46
SNT TOP B 150 1
FID C 6 26
FID C 7 10
FID C 8 47
SNT TRC
FID C 3 122
SNT TRC
FID C 3 123
FID C 3 124
FID C 3 125
SNT TRC
FID C 8 42
FID C 8 43
SNT TRC
FID C 8 44
SNT TRC
FID C 3 126
FID C 3 127
FID C 3 128
# NET 513
NET UNNAMED_524_RESISTOR_I463_2 
SNT TOP T 4 14
FID C 4 361
FID C 5 252
FID C 3 841
SNT TOP T 234 1
FID C 4 360
FID C 5 251
FID C 3 840
SNT VIA
FID H 0 1319
FID C 4 359
FID C 6 180
FID C 3 839
FID C 8 440
FID L 11 263
FID L 12 263
FID L 13 247
FID L 14 212
FID L 15 263
FID L 16 263
SNT TRC
FID C 3 835
SNT TRC
FID C 3 836
FID C 3 837
FID C 3 838
# NET 514
NET FPGA_OUT_MUX3_SEL 
SNT TOP T 170 190
FID C 4 591
FID C 5 376
FID C 3 1596
SNT TOP T 227 0
FID C 4 590
FID C 5 375
FID C 3 1595
SNT VIA
FID H 0 264
FID C 4 589
FID C 6 356
FID C 3 1575
FID C 9 777
FID C 8 916
FID L 11 385
FID L 12 385
FID L 13 369
FID L 14 334
FID L 15 385
FID L 16 385
SNT VIA
FID H 0 2219
FID C 6 355
FID C 3 1574
FID C 9 765
FID C 8 915
FID L 11 384
FID L 12 384
FID L 13 368
FID L 14 333
FID L 15 384
FID L 16 384
SNT TRC
FID C 9 766
FID C 9 767
FID C 9 768
FID C 9 769
FID C 9 770
FID C 9 771
FID C 9 772
FID C 9 773
FID C 9 774
FID C 9 775
FID C 9 776
SNT TRC
FID C 3 1576
SNT TRC
FID C 3 1577
FID C 3 1578
FID C 3 1579
FID C 3 1580
FID C 3 1581
FID C 3 1582
FID C 3 1583
FID C 3 1584
FID C 3 1585
FID C 3 1586
FID C 3 1587
FID C 3 1588
FID C 3 1589
FID C 3 1590
FID C 3 1591
FID C 3 1592
FID C 3 1593
FID C 3 1594
# NET 515
NET FT4232_MUX3_SEL 
SNT TOP T 13 22
FID C 4 523
FID C 5 344
FID C 3 1437
SNT TOP T 226 0
FID C 4 522
FID C 5 343
FID C 3 1436
SNT VIA
FID H 0 297
FID C 4 520
FID C 6 303
FID C 3 1410
FID C 9 434
FID C 8 730
FID L 11 343
FID L 12 343
FID L 13 327
FID L 14 292
FID L 15 343
FID L 16 343
SNT VIA
FID H 0 298
FID C 4 524
FID C 6 305
FID C 3 1438
FID C 9 460
FID C 8 732
FID L 11 345
FID L 12 345
FID L 13 329
FID L 14 294
FID L 15 345
FID L 16 345
SNT VIA
FID H 0 1176
FID C 4 521
FID C 6 304
FID C 3 1435
FID C 8 731
FID L 11 344
FID L 12 344
FID L 13 328
FID L 14 293
FID L 15 344
FID L 16 344
SNT TRC
FID C 3 1411
FID C 3 1412
FID C 3 1413
FID C 3 1414
FID C 3 1415
FID C 3 1416
FID C 3 1417
FID C 3 1418
FID C 3 1419
SNT TRC
FID C 9 435
FID C 9 436
FID C 9 437
FID C 9 438
FID C 9 439
FID C 9 440
FID C 9 441
FID C 9 442
FID C 9 443
FID C 9 444
FID C 9 445
FID C 9 446
FID C 9 447
FID C 9 448
FID C 9 449
FID C 9 450
FID C 9 451
FID C 9 452
FID C 9 453
FID C 9 454
FID C 9 455
FID C 9 456
FID C 9 457
FID C 9 458
FID C 9 459
SNT TRC
FID C 3 1420
FID C 3 1421
FID C 3 1422
FID C 3 1423
FID C 3 1424
FID C 3 1425
FID C 3 1426
FID C 3 1427
FID C 3 1428
FID C 3 1429
FID C 3 1430
SNT TRC
FID C 3 1431
FID C 3 1432
FID C 3 1433
FID C 3 1434
# NET 516
NET UNNAMED_525_ISL80101IRAJZDFN10_ 
SNT TOP T 115 2
FID C 4 335
FID C 5 232
FID C 3 793
SNT TOP T 248 1
FID C 4 338
FID C 5 234
FID C 3 802
SNT TOP T 426 0
FID C 4 337
FID C 5 233
FID C 3 801
SNT TOP B 109 0
FID C 6 173
FID C 7 56
FID C 8 429
SNT VIA
FID H 0 1324
FID C 4 336
FID C 6 174
FID C 3 798
FID C 8 432
FID L 11 258
FID L 12 258
FID L 13 242
FID L 14 207
FID L 15 258
FID L 16 258
SNT TRC
FID C 8 430
FID C 8 431
SNT TRC
FID C 3 794
FID C 3 795
SNT TRC
FID C 3 796
FID C 3 797
SNT TRC
FID C 3 799
FID C 3 800
# NET 517
NET FPGA_IN_MAC_10MHZ_OUT 
SNT TOP T 170 430
FID C 4 1267
FID C 5 765
FID C 3 3295
SNT TOP B 17 1
FID C 6 766
FID C 7 202
FID C 8 2302
SNT TOP B 167 1
FID C 6 764
FID C 7 201
FID C 8 2298
SNT VIA
FID H 0 1127
FID C 4 1266
FID C 6 765
FID C 3 3293
FID C 10 2329
FID C 8 2299
FID L 11 763
FID L 12 763
FID L 13 747
FID L 14 712
FID L 15 763
FID L 16 763
SNT VIA
FID H 0 2111
FID C 3 3294
FID C 10 2330
FID C 8 2300
FID L 11 764
FID L 12 764
FID L 13 748
FID L 14 713
FID L 15 764
FID L 16 764
SNT TRC
FID C 10 2322
FID C 10 2323
FID C 10 2324
FID C 10 2325
FID C 10 2326
FID C 10 2327
FID C 10 2328
SNT TRC
FID C 8 2297
SNT TRC
FID C 3 3296
SNT TRC
FID C 8 2301
# NET 518
NET PCIE_PERST_N 
SNT TOP T 199 1
FID C 4 26
FID C 5 18
FID C 3 88
SNT TOP T 200 1
FID C 4 25
FID C 5 17
FID C 3 81
SNT TOP T 598 2
FID C 4 29
FID C 5 19
FID C 3 93
SNT VIA
FID H 0 336
FID C 4 30
FID C 6 14
FID C 3 94
FID C 9 7
FID C 10 19
FID C 8 20
FID L 11 13
FID L 12 13
FID L 13 13
FID L 14 13
FID L 15 13
FID L 16 13
SNT VIA
FID H 0 337
FID C 4 28
FID C 6 13
FID C 3 92
FID C 10 18
FID C 8 19
FID L 11 12
FID L 12 12
FID L 13 12
FID L 14 12
FID L 15 12
FID L 16 12
SNT VIA
FID H 0 1198
FID C 4 27
FID C 6 12
FID C 3 89
FID C 9 0
FID C 8 18
FID L 11 11
FID L 12 11
FID L 13 11
FID L 14 11
FID L 15 11
FID L 16 11
SNT TRC
FID C 3 79
FID C 3 80
SNT TRC
FID C 3 82
FID C 3 83
FID C 3 84
FID C 3 85
FID C 3 86
FID C 3 87
SNT TRC
FID C 10 7
FID C 10 8
FID C 10 9
FID C 10 10
FID C 10 11
FID C 10 12
FID C 10 13
FID C 10 14
FID C 10 15
FID C 10 16
FID C 10 17
SNT TRC
FID C 9 1
FID C 9 2
FID C 9 3
FID C 9 4
FID C 9 5
FID C 9 6
SNT TRC
FID C 3 90
FID C 3 91
# NET 519
NET FPGA_OUT_PCA9546_RST_N 
SNT TOP T 170 411
FID C 4 1242
FID C 5 750
FID C 3 3242
SNT TOP B 271 0
FID C 6 748
FID C 7 196
FID C 8 2223
SNT VIA
FID H 0 2158
FID C 4 1241
FID C 6 749
FID C 3 3240
FID C 10 2211
FID C 8 2224
FID L 11 746
FID L 12 746
FID L 13 730
FID L 14 695
FID L 15 746
FID L 16 746
SNT VIA
FID H 0 2367
FID C 3 3241
FID C 10 2212
FID C 8 2225
FID L 11 747
FID L 12 747
FID L 13 731
FID L 14 696
FID L 15 747
FID L 16 747
SNT TRC
FID C 10 2181
FID C 10 2182
FID C 10 2183
FID C 10 2184
FID C 10 2185
FID C 10 2186
FID C 10 2187
FID C 10 2188
FID C 10 2189
FID C 10 2190
FID C 10 2191
FID C 10 2192
FID C 10 2193
FID C 10 2194
FID C 10 2195
FID C 10 2196
FID C 10 2197
FID C 10 2198
FID C 10 2199
FID C 10 2200
FID C 10 2201
FID C 10 2202
FID C 10 2203
FID C 10 2204
FID C 10 2205
FID C 10 2206
FID C 10 2207
FID C 10 2208
FID C 10 2209
FID C 10 2210
SNT TRC
FID C 8 2218
FID C 8 2219
FID C 8 2220
FID C 8 2221
FID C 8 2222
SNT TRC
FID C 3 3243
# NET 520
NET SHT3X_I2C_SDA 
SNT TOP T 421 0
FID C 4 2391
FID C 5 1389
FID C 3 5842
SNT TOP T 604 5
FID C 4 2390
FID C 5 1388
FID C 3 5839
SNT TOP B 342 1
FID C 6 1709
FID C 7 615
FID C 8 4236
SNT VIA
FID H 0 697
FID C 4 2393
FID C 6 1708
FID C 3 5844
FID C 10 3471
FID C 8 4235
FID L 11 1379
FID L 12 1379
FID L 13 1147
FID L 14 1146
FID L 15 1379
FID L 16 1379
SNT VIA
FID H 0 1242
FID C 4 2392
FID C 6 1707
FID C 3 5843
FID C 10 3470
FID C 8 4234
FID L 11 1378
FID L 12 1378
FID L 13 1146
FID L 14 1145
FID L 15 1378
FID L 16 1378
SNT TRC
FID C 10 3402
FID C 10 3403
FID C 10 3404
FID C 10 3405
FID C 10 3406
FID C 10 3407
FID C 10 3408
FID C 10 3409
FID C 10 3410
FID C 10 3411
FID C 10 3412
FID C 10 3413
FID C 10 3414
FID C 10 3415
FID C 10 3416
FID C 10 3417
FID C 10 3418
FID C 10 3419
FID C 10 3420
FID C 10 3421
FID C 10 3422
FID C 10 3423
FID C 10 3424
FID C 10 3425
FID C 10 3426
FID C 10 3427
FID C 10 3428
FID C 10 3429
FID C 10 3430
FID C 10 3431
FID C 10 3432
FID C 10 3433
FID C 10 3434
FID C 10 3435
FID C 10 3436
FID C 10 3437
FID C 10 3438
FID C 10 3439
FID C 10 3440
FID C 10 3441
FID C 10 3442
FID C 10 3443
FID C 10 3444
FID C 10 3445
FID C 10 3446
FID C 10 3447
FID C 10 3448
FID C 10 3449
FID C 10 3450
FID C 10 3451
FID C 10 3452
FID C 10 3453
FID C 10 3454
FID C 10 3455
FID C 10 3456
FID C 10 3457
FID C 10 3458
FID C 10 3459
FID C 10 3460
FID C 10 3461
FID C 10 3462
FID C 10 3463
FID C 10 3464
FID C 10 3465
FID C 10 3466
FID C 10 3467
FID C 10 3468
FID C 10 3469
SNT TRC
FID C 3 5831
FID C 3 5832
FID C 3 5833
FID C 3 5834
FID C 3 5835
FID C 3 5836
FID C 3 5837
FID C 3 5838
SNT TRC
FID C 8 4231
FID C 8 4232
FID C 8 4233
SNT TRC
FID C 3 5840
FID C 3 5841
# NET 521
NET SHT3X_I2C_SCL 
SNT TOP T 419 0
FID C 4 2396
FID C 5 1391
FID C 3 5855
SNT TOP T 604 6
FID C 4 2394
FID C 5 1390
FID C 3 5853
SNT TOP B 340 1
FID C 6 1711
FID C 7 616
FID C 8 4239
SNT VIA
FID H 0 696
FID C 4 2397
FID C 6 1712
FID C 3 5856
FID C 10 3507
FID C 8 4240
FID L 11 1381
FID L 12 1381
FID L 13 1149
FID L 14 1148
FID L 15 1381
FID L 16 1381
SNT VIA
FID H 0 1241
FID C 4 2395
FID C 6 1710
FID C 3 5854
FID C 10 3506
FID C 8 4238
FID L 11 1380
FID L 12 1380
FID L 13 1148
FID L 14 1147
FID L 15 1380
FID L 16 1380
SNT TRC
FID C 10 3472
FID C 10 3473
FID C 10 3474
FID C 10 3475
FID C 10 3476
FID C 10 3477
FID C 10 3478
FID C 10 3479
FID C 10 3480
FID C 10 3481
FID C 10 3482
FID C 10 3483
FID C 10 3484
FID C 10 3485
FID C 10 3486
FID C 10 3487
FID C 10 3488
FID C 10 3489
FID C 10 3490
FID C 10 3491
FID C 10 3492
FID C 10 3493
FID C 10 3494
FID C 10 3495
FID C 10 3496
FID C 10 3497
FID C 10 3498
FID C 10 3499
FID C 10 3500
FID C 10 3501
FID C 10 3502
FID C 10 3503
FID C 10 3504
FID C 10 3505
SNT TRC
FID C 8 4237
SNT TRC
FID C 3 5845
SNT TRC
FID C 3 5846
FID C 3 5847
FID C 3 5848
FID C 3 5849
FID C 3 5850
FID C 3 5851
FID C 3 5852
# NET 522
NET R_SHT3X_I2C_SDA 
SNT TOP T 142 0
FID C 4 3739
FID C 5 1768
FID C 3 7861
SNT TOP T 421 1
FID C 4 3741
FID C 5 1769
FID C 3 7867
SNT VIA
FID H 0 2260
FID C 4 3740
FID C 6 2898
FID C 3 7866
FID C 8 5904
FID L 11 1422
FID L 12 1422
FID L 13 2199
FID L 14 2198
FID L 15 1422
FID L 16 1422
SNT TRC
FID C 3 7862
FID C 3 7863
FID C 3 7864
SNT TRC
FID C 3 7865
# NET 523
NET R_SHT3X_I2C_SCL 
SNT TOP T 142 3
FID C 4 3742
FID C 5 1770
FID C 3 7868
SNT TOP T 419 1
FID C 4 3744
FID C 5 1771
FID C 3 7874
SNT VIA
FID H 0 2259
FID C 4 3743
FID C 6 2899
FID C 3 7873
FID C 8 5905
FID L 11 1423
FID L 12 1423
FID L 13 2200
FID L 14 2199
FID L 15 1423
FID L 16 1423
SNT TRC
FID C 3 7869
FID C 3 7870
FID C 3 7871
SNT TRC
FID C 3 7872
# NET 524
NET SHT3X_ADDR 
SNT TOP T 142 1
FID C 4 2398
FID C 5 1392
FID C 3 5857
SNT TOP T 420 1
FID C 4 2400
FID C 5 1393
FID C 3 5863
SNT TOP B 341 0
FID C 6 1713
FID C 7 617
FID C 8 4243
SNT VIA
FID H 0 2264
FID C 4 2399
FID C 6 1714
FID C 3 5862
FID C 8 4244
FID L 11 1382
FID L 12 1382
FID L 13 1150
FID L 14 1149
FID L 15 1382
FID L 16 1382
SNT TRC
FID C 3 5858
FID C 3 5859
SNT TRC
FID C 8 4241
FID C 8 4242
SNT TRC
FID C 3 5860
FID C 3 5861
# NET 525
NET UNNAMED_15_MP5022CGQVZQFN22_I_2 
SNT TOP T 189 1
FID C 4 2222
FID C 5 1323
FID C 3 5499
SNT TOP T 324 1
FID C 4 2224
FID C 5 1324
FID C 3 5503
SNT VIA
FID H 0 1301
FID C 4 2223
FID C 6 1533
FID C 3 5500
FID C 8 3905
FID L 11 1283
FID L 12 1283
FID L 13 1094
FID L 14 1064
FID L 15 1283
FID L 16 1283
SNT TRC
FID C 3 5501
FID C 3 5502
SNT TRC
FID C 3 5504
# NET 526
NET R_ICP10100_I2C_SDA 
SNT TOP T 148 3
FID C 4 3783
FID C 5 1792
FID C 3 8102
SNT TOP T 305 1
FID C 4 3782
FID C 5 1791
FID C 3 8101
SNT VIA
FID H 0 1216
FID C 4 3781
FID C 6 2926
FID C 3 8100
FID C 8 5974
FID L 11 1442
FID L 12 1442
FID L 13 2219
FID L 14 2218
FID L 15 1442
FID L 16 1442
SNT TRC
FID C 3 8095
FID C 3 8096
FID C 3 8097
SNT TRC
FID C 3 8098
FID C 3 8099
# NET 527
NET R_ICP10100_I2C_SCL 
SNT TOP T 148 1
FID C 4 3786
FID C 5 1794
FID C 3 8111
SNT TOP T 340 1
FID C 4 3785
FID C 5 1793
FID C 3 8110
SNT VIA
FID H 0 2171
FID C 4 3784
FID C 6 2927
FID C 3 8109
FID C 8 5975
FID L 11 1443
FID L 12 1443
FID L 13 2220
FID L 14 2219
FID L 15 1443
FID L 16 1443
SNT TRC
FID C 3 8103
FID C 3 8104
FID C 3 8105
SNT TRC
FID C 3 8106
FID C 3 8107
FID C 3 8108
# NET 528
NET BNO080_I2C_SDA 
SNT TOP T 604 10
FID C 4 3961
FID C 5 1885
FID C 3 8707
SNT TOP B 235 0
FID C 6 3100
FID C 7 903
FID C 8 6937
SNT TOP B 238 1
FID C 6 3099
FID C 7 902
FID C 8 6935
SNT VIA
FID H 0 1099
FID C 4 3960
FID C 6 3098
FID C 3 8706
FID C 8 6934
FID L 11 1568
FID L 12 1568
FID L 13 2345
FID L 14 2344
FID L 15 1568
FID L 16 1568
SNT TRC
FID C 3 8686
FID C 3 8687
FID C 3 8688
FID C 3 8689
FID C 3 8690
FID C 3 8691
FID C 3 8692
FID C 3 8693
FID C 3 8694
FID C 3 8695
FID C 3 8696
FID C 3 8697
FID C 3 8698
FID C 3 8699
FID C 3 8700
FID C 3 8701
FID C 3 8702
FID C 3 8703
FID C 3 8704
FID C 3 8705
SNT TRC
FID C 8 6893
FID C 8 6894
FID C 8 6895
FID C 8 6896
FID C 8 6897
FID C 8 6898
FID C 8 6899
FID C 8 6900
FID C 8 6901
FID C 8 6902
FID C 8 6903
FID C 8 6904
FID C 8 6905
FID C 8 6906
FID C 8 6907
FID C 8 6908
FID C 8 6909
FID C 8 6910
FID C 8 6911
FID C 8 6912
FID C 8 6913
FID C 8 6914
FID C 8 6915
FID C 8 6916
FID C 8 6917
FID C 8 6918
FID C 8 6919
FID C 8 6920
FID C 8 6921
FID C 8 6922
FID C 8 6923
FID C 8 6924
FID C 8 6925
FID C 8 6926
FID C 8 6927
FID C 8 6928
FID C 8 6929
FID C 8 6930
FID C 8 6931
FID C 8 6932
FID C 8 6933
SNT TRC
FID C 8 6936
# NET 529
NET BNO080_I2C_SCL 
SNT TOP T 604 11
FID C 4 3963
FID C 5 1886
FID C 3 8719
SNT TOP B 236 0
FID C 6 3102
FID C 7 904
FID C 8 6960
SNT TOP B 237 1
FID C 6 3103
FID C 7 905
FID C 8 6962
SNT VIA
FID H 0 1098
FID C 4 3962
FID C 6 3101
FID C 3 8718
FID C 8 6959
FID L 11 1569
FID L 12 1569
FID L 13 2346
FID L 14 2345
FID L 15 1569
FID L 16 1569
SNT TRC
FID C 8 6938
FID C 8 6939
FID C 8 6940
FID C 8 6941
FID C 8 6942
FID C 8 6943
FID C 8 6944
FID C 8 6945
FID C 8 6946
FID C 8 6947
FID C 8 6948
FID C 8 6949
FID C 8 6950
FID C 8 6951
FID C 8 6952
FID C 8 6953
FID C 8 6954
FID C 8 6955
FID C 8 6956
FID C 8 6957
FID C 8 6958
SNT TRC
FID C 3 8708
FID C 3 8709
FID C 3 8710
FID C 3 8711
FID C 3 8712
FID C 3 8713
FID C 3 8714
FID C 3 8715
FID C 3 8716
FID C 3 8717
SNT TRC
FID C 8 6961
# NET 530
NET R_BNO080_I2C_SDA 
SNT TOP T 149 19
FID C 4 1209
FID C 5 726
FID C 3 3143
SNT TOP B 235 1
FID C 6 724
FID C 7 194
FID C 8 2180
SNT VIA
FID H 0 2253
FID C 4 1208
FID C 6 723
FID C 3 3142
FID C 8 2179
FID L 11 711
FID L 12 711
FID L 13 695
FID L 14 660
FID L 15 711
FID L 16 711
SNT TRC
FID C 3 3139
FID C 3 3140
FID C 3 3141
SNT TRC
FID C 8 2175
FID C 8 2176
FID C 8 2177
FID C 8 2178
# NET 531
NET R_BNO080_I2C_SCL 
SNT TOP T 149 18
FID C 4 1211
FID C 5 727
FID C 3 3148
SNT TOP B 236 1
FID C 6 726
FID C 7 195
FID C 8 2184
SNT VIA
FID H 0 1202
FID C 4 1210
FID C 6 725
FID C 3 3147
FID C 8 2183
FID L 11 712
FID L 12 712
FID L 13 696
FID L 14 661
FID L 15 712
FID L 16 712
SNT TRC
FID C 8 2181
FID C 8 2182
SNT TRC
FID C 3 3144
FID C 3 3145
FID C 3 3146
# NET 532
NET FPGA_OUT_BNO080_RST_N 
SNT TOP T 170 236
FID C 4 1249
FID C 5 754
FID C 3 3256
SNT TOP T 354 1
FID C 4 1248
FID C 5 753
FID C 3 3254
SNT VIA
FID H 0 253
FID C 4 1246
FID C 6 751
FID C 3 3252
FID C 9 1772
FID C 10 2236
FID C 8 2251
FID L 11 751
FID L 12 751
FID L 13 735
FID L 14 700
FID L 15 751
FID L 16 751
SNT VIA
FID H 0 1146
FID C 4 1247
FID C 6 752
FID C 3 3253
FID C 9 1773
FID C 8 2252
FID L 11 752
FID L 12 752
FID L 13 736
FID L 14 701
FID L 15 752
FID L 16 752
SNT VIA
FID H 0 2363
FID C 3 3251
FID C 10 2235
FID C 8 2250
FID L 11 750
FID L 12 750
FID L 13 734
FID L 14 699
FID L 15 750
FID L 16 750
SNT TRC
FID C 10 2213
FID C 10 2214
FID C 10 2215
FID C 10 2216
FID C 10 2217
FID C 10 2218
FID C 10 2219
FID C 10 2220
FID C 10 2221
FID C 10 2222
FID C 10 2223
FID C 10 2224
FID C 10 2225
FID C 10 2226
FID C 10 2227
FID C 10 2228
FID C 10 2229
FID C 10 2230
FID C 10 2231
FID C 10 2232
FID C 10 2233
FID C 10 2234
SNT TRC
FID C 9 1768
FID C 9 1769
FID C 9 1770
FID C 9 1771
SNT TRC
FID C 3 3255
SNT TRC
FID C 3 3257
# NET 533
NET R_BNO080_INT_N 
SNT TOP T 47 0
FID H 0 120
FID C 6 2931
FID C 3 8133
FID C 9 2443
FID C 8 5979
FID L 11 1447
FID L 12 1447
FID L 13 2224
FID L 14 2223
FID L 15 1447
FID L 16 1447
SNT TOP T 149 13
FID C 4 3794
FID C 5 1800
FID C 3 8132
SNT TOP T 353 1
FID C 4 3793
FID C 5 1799
FID C 3 8131
SNT VIA
FID H 0 1203
FID C 4 3792
FID C 6 2930
FID C 3 8130
FID C 9 2442
FID C 8 5978
FID L 11 1446
FID L 12 1446
FID L 13 2223
FID L 14 2222
FID L 15 1446
FID L 16 1446
SNT TRC
FID C 9 2433
FID C 9 2434
FID C 9 2435
FID C 9 2436
FID C 9 2437
FID C 9 2438
FID C 9 2439
FID C 9 2440
FID C 9 2441
SNT TRC
FID C 3 8125
FID C 3 8126
FID C 3 8127
SNT TRC
FID C 3 8128
FID C 3 8129
# NET 534
NET UNNAMED_15_MP5022CGQVZQFN22_I21 
SNT TOP T 189 2
FID C 4 2225
FID C 5 1325
FID C 3 5505
SNT TOP T 325 1
FID C 4 2227
FID C 5 1326
FID C 3 5512
SNT VIA
FID H 0 1300
FID C 4 2226
FID C 6 1534
FID C 3 5506
FID C 8 3906
FID L 11 1284
FID L 12 1284
FID L 13 1095
FID L 14 1065
FID L 15 1284
FID L 16 1284
SNT TRC
FID C 3 5507
FID C 3 5508
FID C 3 5509
SNT TRC
FID C 3 5510
FID C 3 5511
# NET 535
NET FPGA_OUT_BNO080_BOOT_N 
SNT TOP T 170 278
FID C 4 1251
FID C 5 755
FID C 3 3260
SNT TOP B 347 0
FID C 6 753
FID C 7 197
FID C 8 2257
SNT VIA
FID H 0 1145
FID C 4 1250
FID C 6 754
FID C 3 3259
FID C 10 2265
FID C 8 2258
FID L 11 754
FID L 12 754
FID L 13 738
FID L 14 703
FID L 15 754
FID L 16 754
SNT VIA
FID H 0 2120
FID C 3 3258
FID C 10 2264
FID C 8 2253
FID L 11 753
FID L 12 753
FID L 13 737
FID L 14 702
FID L 15 753
FID L 16 753
SNT TRC
FID C 10 2237
FID C 10 2238
FID C 10 2239
FID C 10 2240
FID C 10 2241
FID C 10 2242
FID C 10 2243
FID C 10 2244
FID C 10 2245
FID C 10 2246
FID C 10 2247
FID C 10 2248
FID C 10 2249
FID C 10 2250
FID C 10 2251
FID C 10 2252
FID C 10 2253
FID C 10 2254
FID C 10 2255
FID C 10 2256
FID C 10 2257
FID C 10 2258
FID C 10 2259
FID C 10 2260
FID C 10 2261
FID C 10 2262
FID C 10 2263
SNT TRC
FID C 8 2254
FID C 8 2255
FID C 8 2256
SNT TRC
FID C 3 3261
# NET 536
NET UART_MAC_RX_FPGA_TX 
SNT TOP T 170 39
FID C 4 1873
FID C 5 1117
FID C 3 4647
SNT TOP T 358 1
FID C 4 1872
FID C 5 1116
FID C 3 4646
SNT VIA
FID H 0 1262
FID C 4 1871
FID C 6 1267
FID C 3 4645
FID C 8 3324
FID L 11 1098
FID L 12 1098
FID L 13 951
FID L 14 901
FID L 15 1098
FID L 16 1098
SNT TRC
FID C 3 4637
FID C 3 4638
FID C 3 4639
FID C 3 4640
FID C 3 4641
SNT TRC
FID C 3 4642
FID C 3 4643
FID C 3 4644
# NET 537
NET UNNAMED_524_FT4232HLREELQFP64_5 
SNT TOP T 13 33
FID C 4 375
FID C 5 262
FID C 3 876
SNT TOP T 69 0
FID H 0 103
FID C 6 188
FID C 3 879
FID C 8 452
FID L 11 269
FID L 12 269
FID L 13 253
FID L 14 218
FID L 15 269
FID L 16 269
SNT TRC
FID C 3 877
FID C 3 878
# NET 538
NET IO_L20P_34 
SNT TOP T 70 0
FID H 0 107
FID C 6 3005
FID C 3 8375
FID C 8 6300
FID L 11 1507
FID L 12 1507
FID L 13 2284
FID L 14 2283
FID L 15 1507
FID L 16 1507
SNT TOP T 170 50
FID C 4 3872
FID C 5 1842
FID C 3 8376
SNT TRC
FID C 3 8377
# NET 539
NET IO_L20N_34 
SNT TOP T 62 0
FID H 0 108
FID C 6 3007
FID C 3 8382
FID C 8 6302
FID L 11 1509
FID L 12 1509
FID L 13 2286
FID L 14 2285
FID L 15 1509
FID L 16 1509
SNT TOP T 170 49
FID C 4 3874
FID C 5 1844
FID C 3 8383
SNT TRC
FID C 3 8384
# NET 540
NET IO_L21P_34 
SNT TOP T 77 0
FID H 0 109
FID C 6 739
FID C 3 3200
FID C 10 2171
FID C 8 2205
FID L 11 733
FID L 12 733
FID L 13 717
FID L 14 682
FID L 15 733
FID L 16 733
SNT TOP T 170 426
FID C 4 1226
FID C 5 740
FID C 3 3203
SNT VIA
FID H 0 2140
FID C 3 3201
FID C 10 2172
FID C 8 2206
FID L 11 734
FID L 12 734
FID L 13 718
FID L 14 683
FID L 15 734
FID L 16 734
SNT TRC
FID C 10 2164
FID C 10 2165
FID C 10 2166
FID C 10 2167
FID C 10 2168
FID C 10 2169
FID C 10 2170
SNT TRC
FID C 3 3202
# NET 541
NET IO_L21N_34 
SNT TOP T 75 0
FID H 0 110
FID C 6 3003
FID C 3 8367
FID C 10 3647
FID C 8 6297
FID L 11 1504
FID L 12 1504
FID L 13 2281
FID L 14 2280
FID L 15 1504
FID L 16 1504
SNT TOP T 170 425
FID C 4 3870
FID C 5 1840
FID C 3 8370
SNT VIA
FID H 0 2139
FID C 3 8368
FID C 10 3648
FID C 8 6298
FID L 11 1505
FID L 12 1505
FID L 13 2282
FID L 14 2281
FID L 15 1505
FID L 16 1505
SNT TRC
FID C 10 3638
FID C 10 3639
FID C 10 3640
FID C 10 3641
FID C 10 3642
FID C 10 3643
FID C 10 3644
FID C 10 3645
FID C 10 3646
SNT TRC
FID C 3 8369
# NET 542
NET IO_L22P_34 
SNT TOP T 76 0
FID H 0 111
FID C 6 2999
FID C 3 8345
FID C 8 6293
FID L 11 1500
FID L 12 1500
FID L 13 2277
FID L 14 2276
FID L 15 1500
FID L 16 1500
SNT TOP T 170 29
FID C 4 3866
FID C 5 1836
FID C 3 8349
SNT TRC
FID C 3 8346
FID C 3 8347
FID C 3 8348
# NET 543
NET IO_L22N_34 
SNT TOP T 74 0
FID H 0 112
FID C 6 737
FID C 3 3194
FID C 8 2202
FID L 11 730
FID L 12 730
FID L 13 714
FID L 14 679
FID L 15 730
FID L 16 730
SNT TOP T 170 51
FID C 4 1224
FID C 5 738
FID C 3 3195
SNT TRC
FID C 3 3191
FID C 3 3192
FID C 3 3193
# NET 544
NET IO_L23P_34 
SNT TOP T 61 0
FID H 0 113
FID C 6 733
FID C 3 3172
FID C 10 2162
FID C 8 2195
FID L 11 723
FID L 12 723
FID L 13 707
FID L 14 672
FID L 15 723
FID L 16 723
SNT TOP T 170 469
FID C 4 1220
FID C 5 734
FID C 3 3175
SNT VIA
FID H 0 2142
FID C 3 3173
FID C 10 2163
FID C 8 2196
FID L 11 724
FID L 12 724
FID L 13 708
FID L 14 673
FID L 15 724
FID L 16 724
SNT TRC
FID C 10 2153
FID C 10 2154
FID C 10 2155
FID C 10 2156
FID C 10 2157
FID C 10 2158
FID C 10 2159
FID C 10 2160
FID C 10 2161
SNT TRC
FID C 3 3174
# NET 545
NET IO_L23N_34 
SNT TOP T 60 0
FID H 0 114
FID C 6 2997
FID C 3 8334
FID C 10 3636
FID C 8 6290
FID L 11 1497
FID L 12 1497
FID L 13 2274
FID L 14 2273
FID L 15 1497
FID L 16 1497
SNT TOP T 170 468
FID C 4 3864
FID C 5 1834
FID C 3 8337
SNT VIA
FID H 0 2141
FID C 3 8335
FID C 10 3637
FID C 8 6291
FID L 11 1498
FID L 12 1498
FID L 13 2275
FID L 14 2274
FID L 15 1498
FID L 16 1498
SNT TRC
FID C 10 3630
FID C 10 3631
FID C 10 3632
FID C 10 3633
FID C 10 3634
FID C 10 3635
SNT TRC
FID C 3 8336
# NET 546
NET IO_L24P_34 
SNT TOP T 63 0
FID H 0 116
FID C 6 730
FID C 3 3161
FID C 8 2190
FID L 11 718
FID L 12 718
FID L 13 702
FID L 14 667
FID L 15 718
FID L 16 718
SNT TOP T 170 448
FID C 4 1217
FID C 5 731
FID C 3 3162
SNT TRC
FID C 3 3163
# NET 547
NET IO_L24N_34 
SNT TOP T 64 0
FID H 0 117
FID C 6 2994
FID C 3 8320
FID C 8 6287
FID L 11 1494
FID L 12 1494
FID L 13 2271
FID L 14 2270
FID L 15 1494
FID L 16 1494
SNT TOP T 170 470
FID C 4 3861
FID C 5 1831
FID C 3 8321
SNT TRC
FID C 3 8322
# NET 548
NET IO_L20N_16 
SNT TOP T 83 0
FID H 0 122
FID C 6 3008
FID C 3 8388
FID C 8 6303
FID L 11 1510
FID L 12 1510
FID L 13 2287
FID L 14 2286
FID L 15 1510
FID L 16 1510
SNT TOP T 170 87
FID C 4 3875
FID C 5 1845
FID C 3 8389
SNT TRC
FID C 3 8385
FID C 3 8386
FID C 3 8387
# NET 549
NET IO_L21P_16 
SNT TOP T 84 0
FID H 0 123
FID C 6 3002
FID C 3 8362
FID C 8 6296
FID L 11 1503
FID L 12 1503
FID L 13 2280
FID L 14 2279
FID L 15 1503
FID L 16 1503
SNT TOP T 170 86
FID C 4 3869
FID C 5 1839
FID C 3 8366
SNT TRC
FID C 3 8363
FID C 3 8364
FID C 3 8365
# NET 550
NET IO_L21N_16 
SNT TOP T 85 0
FID H 0 124
FID C 6 3004
FID C 3 8371
FID C 8 6299
FID L 11 1506
FID L 12 1506
FID L 13 2283
FID L 14 2282
FID L 15 1506
FID L 16 1506
SNT TOP T 170 20
FID C 4 3871
FID C 5 1841
FID C 3 8374
SNT TRC
FID C 3 8372
FID C 3 8373
# NET 551
NET IO_L22P_16 
SNT TOP T 86 0
FID H 0 125
FID C 6 3000
FID C 3 8353
FID C 8 6294
FID L 11 1501
FID L 12 1501
FID L 13 2278
FID L 14 2277
FID L 15 1501
FID L 16 1501
SNT TOP T 170 153
FID C 4 3867
FID C 5 1837
FID C 3 8354
SNT TRC
FID C 3 8350
FID C 3 8351
FID C 3 8352
# NET 552
NET IO_L22N_16 
SNT TOP T 87 0
FID H 0 126
FID C 6 3001
FID C 3 8360
FID C 8 6295
FID L 11 1502
FID L 12 1502
FID L 13 2279
FID L 14 2278
FID L 15 1502
FID L 16 1502
SNT TOP T 170 131
FID C 4 3868
FID C 5 1838
FID C 3 8361
SNT TRC
FID C 3 8355
FID C 3 8356
FID C 3 8357
FID C 3 8358
FID C 3 8359
# NET 553
NET IO_L23P_16 
SNT TOP T 88 0
FID H 0 127
FID C 6 2996
FID C 3 8332
FID C 8 6289
FID L 11 1496
FID L 12 1496
FID L 13 2273
FID L 14 2272
FID L 15 1496
FID L 16 1496
SNT TOP T 170 152
FID C 4 3863
FID C 5 1833
FID C 3 8333
SNT TRC
FID C 3 8327
FID C 3 8328
FID C 3 8329
FID C 3 8330
FID C 3 8331
# NET 554
NET IO_L23N_16 
SNT TOP T 89 0
FID H 0 128
FID C 6 2998
FID C 3 8338
FID C 8 6292
FID L 11 1499
FID L 12 1499
FID L 13 2276
FID L 14 2275
FID L 15 1499
FID L 16 1499
SNT TOP T 170 130
FID C 4 3865
FID C 5 1835
FID C 3 8344
SNT TRC
FID C 3 8339
FID C 3 8340
FID C 3 8341
FID C 3 8342
FID C 3 8343
# NET 555
NET IO_L24P_16 
SNT TOP T 90 0
FID H 0 129
FID C 6 2993
FID C 3 8318
FID C 8 6286
FID L 11 1493
FID L 12 1493
FID L 13 2270
FID L 14 2269
FID L 15 1493
FID L 16 1493
SNT TOP T 170 196
FID C 4 3860
FID C 5 1830
FID C 3 8319
SNT TRC
FID C 3 8315
FID C 3 8316
FID C 3 8317
# NET 556
NET IO_L24N_16 
SNT TOP T 91 0
FID H 0 130
FID C 6 2995
FID C 3 8325
FID C 8 6288
FID L 11 1495
FID L 12 1495
FID L 13 2272
FID L 14 2271
FID L 15 1495
FID L 16 1495
SNT TOP T 170 197
FID C 4 3862
FID C 5 1832
FID C 3 8326
SNT TRC
FID C 3 8323
FID C 3 8324
# NET 557
NET IO_L21P_35 
SNT TOP T 92 0
FID H 0 132
FID C 6 738
FID C 3 3196
FID C 9 1644
FID C 8 2203
FID L 11 731
FID L 12 731
FID L 13 715
FID L 14 680
FID L 15 731
FID L 16 731
SNT TOP T 170 334
FID C 4 1225
FID C 5 739
FID C 3 3198
SNT VIA
FID H 0 2376
FID C 3 3197
FID C 9 1645
FID C 8 2204
FID L 11 732
FID L 12 732
FID L 13 716
FID L 14 681
FID L 15 732
FID L 16 732
SNT TRC
FID C 9 1637
FID C 9 1638
FID C 9 1639
FID C 9 1640
FID C 9 1641
FID C 9 1642
FID C 9 1643
SNT TRC
FID C 3 3199
# NET 558
NET IO_L21N_35 
SNT TOP T 93 0
FID H 0 133
FID C 6 740
FID C 3 3204
FID C 9 1651
FID C 8 2207
FID L 11 735
FID L 12 735
FID L 13 719
FID L 14 684
FID L 15 735
FID L 16 735
SNT TOP T 170 333
FID C 4 1227
FID C 5 741
FID C 3 3206
SNT VIA
FID H 0 2375
FID C 3 3205
FID C 9 1652
FID C 8 2208
FID L 11 736
FID L 12 736
FID L 13 720
FID L 14 685
FID L 15 736
FID L 16 736
SNT TRC
FID C 9 1646
FID C 9 1647
FID C 9 1648
FID C 9 1649
FID C 9 1650
SNT TRC
FID C 3 3207
# NET 559
NET IO_L23P_35 
SNT TOP T 94 0
FID H 0 134
FID C 6 732
FID C 3 3168
FID C 9 1618
FID C 8 2193
FID L 11 721
FID L 12 721
FID L 13 705
FID L 14 670
FID L 15 721
FID L 16 721
SNT TOP T 170 291
FID C 4 1219
FID C 5 733
FID C 3 3171
SNT VIA
FID H 0 2379
FID C 3 3169
FID C 9 1619
FID C 8 2194
FID L 11 722
FID L 12 722
FID L 13 706
FID L 14 671
FID L 15 722
FID L 16 722
SNT TRC
FID C 9 1612
FID C 9 1613
FID C 9 1614
FID C 9 1615
FID C 9 1616
FID C 9 1617
SNT TRC
FID C 3 3170
# NET 560
NET IO_L23N_35 
SNT TOP T 95 0
FID H 0 135
FID C 6 734
FID C 3 3176
FID C 9 1626
FID C 8 2197
FID L 11 725
FID L 12 725
FID L 13 709
FID L 14 674
FID L 15 725
FID L 16 725
SNT TOP T 170 290
FID C 4 1221
FID C 5 735
FID C 3 3179
SNT VIA
FID H 0 2378
FID C 3 3177
FID C 9 1627
FID C 8 2198
FID L 11 726
FID L 12 726
FID L 13 710
FID L 14 675
FID L 15 726
FID L 16 726
SNT TRC
FID C 9 1620
FID C 9 1621
FID C 9 1622
FID C 9 1623
FID C 9 1624
FID C 9 1625
SNT TRC
FID C 3 3178
# NET 561
NET IO_L20P_35 
SNT TOP T 96 0
FID H 0 136
FID C 6 741
FID C 3 3212
FID C 8 2209
FID L 11 737
FID L 12 737
FID L 13 721
FID L 14 686
FID L 15 737
FID L 16 737
SNT TOP T 170 352
FID C 4 1228
FID C 5 742
FID C 3 3213
SNT TRC
FID C 3 3208
FID C 3 3209
FID C 3 3210
FID C 3 3211
# NET 562
NET IO_L20N_35 
SNT TOP T 97 0
FID H 0 139
FID C 6 742
FID C 3 3218
FID C 8 2210
FID L 11 738
FID L 12 738
FID L 13 722
FID L 14 687
FID L 15 738
FID L 16 738
SNT TOP T 170 330
FID C 4 1229
FID C 5 743
FID C 3 3219
SNT TRC
FID C 3 3214
FID C 3 3215
FID C 3 3216
FID C 3 3217
# NET 563
NET IO_L22P_35 
SNT TOP T 98 0
FID H 0 140
FID C 6 735
FID C 3 3185
FID C 8 2199
FID L 11 727
FID L 12 727
FID L 13 711
FID L 14 676
FID L 15 727
FID L 16 727
SNT TOP T 170 331
FID C 4 1222
FID C 5 736
FID C 3 3186
SNT TRC
FID C 3 3180
FID C 3 3181
FID C 3 3182
FID C 3 3183
FID C 3 3184
# NET 564
NET IO_L22N_35 
SNT TOP T 99 0
FID H 0 141
FID C 6 736
FID C 3 3187
FID C 9 1635
FID C 8 2200
FID L 11 728
FID L 12 728
FID L 13 712
FID L 14 677
FID L 15 728
FID L 16 728
SNT TOP T 170 309
FID C 4 1223
FID C 5 737
FID C 3 3189
SNT VIA
FID H 0 2377
FID C 3 3188
FID C 9 1636
FID C 8 2201
FID L 11 729
FID L 12 729
FID L 13 713
FID L 14 678
FID L 15 729
FID L 16 729
SNT TRC
FID C 9 1628
FID C 9 1629
FID C 9 1630
FID C 9 1631
FID C 9 1632
FID C 9 1633
FID C 9 1634
SNT TRC
FID C 3 3190
# NET 565
NET IO_L24P_35 
SNT TOP T 100 0
FID H 0 142
FID C 6 729
FID C 3 3157
FID C 9 1604
FID C 8 2188
FID L 11 716
FID L 12 716
FID L 13 700
FID L 14 665
FID L 15 716
FID L 16 716
SNT TOP T 170 335
FID C 4 1216
FID C 5 730
FID C 3 3159
SNT VIA
FID H 0 2381
FID C 3 3158
FID C 9 1605
FID C 8 2189
FID L 11 717
FID L 12 717
FID L 13 701
FID L 14 666
FID L 15 717
FID L 16 717
SNT TRC
FID C 9 1598
FID C 9 1599
FID C 9 1600
FID C 9 1601
FID C 9 1602
FID C 9 1603
SNT TRC
FID C 3 3160
# NET 566
NET IO_L24N_35 
SNT TOP T 101 0
FID H 0 143
FID C 6 731
FID C 3 3164
FID C 9 1610
FID C 8 2191
FID L 11 719
FID L 12 719
FID L 13 703
FID L 14 668
FID L 15 719
FID L 16 719
SNT TOP T 170 312
FID C 4 1218
FID C 5 732
FID C 3 3166
SNT VIA
FID H 0 2380
FID C 3 3165
FID C 9 1611
FID C 8 2192
FID L 11 720
FID L 12 720
FID L 13 704
FID L 14 669
FID L 15 720
FID L 16 720
SNT TRC
FID C 9 1606
FID C 9 1607
FID C 9 1608
FID C 9 1609
SNT TRC
FID C 3 3167
# NET 567
NET UNNAMED_524_FT4232HLREELQFP64_I 
SNT TOP T 13 23
FID C 4 370
FID C 5 259
FID C 3 867
SNT TOP T 66 0
FID H 0 175
FID C 6 183
FID C 3 866
FID C 8 443
FID L 11 266
FID L 12 266
FID L 13 250
FID L 14 215
FID L 15 266
FID L 16 266
SNT TRC
FID C 3 861
FID C 3 862
FID C 3 863
FID C 3 864
FID C 3 865
# NET 568
NET UNNAMED_524_FT4232HLREELQFP64_1 
SNT TOP T 13 28
FID C 4 379
FID C 5 266
FID C 3 902
SNT TOP T 78 0
FID H 0 186
FID C 6 192
FID C 3 901
FID C 8 456
FID L 11 273
FID L 12 273
FID L 13 257
FID L 14 222
FID L 15 273
FID L 16 273
SNT TRC
FID C 3 897
FID C 3 898
FID C 3 899
FID C 3 900
# NET 569
NET UNNAMED_9_BNO080LGA28_I29_HCS 
SNT TOP T 65 0
FID H 0 188
FID C 6 699
FID C 3 3027
FID C 8 2136
FID L 11 694
FID L 12 694
FID L 13 678
FID L 14 643
FID L 15 694
FID L 16 694
SNT TOP T 149 17
FID C 4 1165
FID C 5 697
FID C 3 3031
SNT TRC
FID C 3 3028
FID C 3 3029
FID C 3 3030
# NET 570
NET UNNAMED_524_FT4232HLREELQFP64_2 
SNT TOP T 13 29
FID C 4 378
FID C 5 265
FID C 3 896
SNT TOP T 68 0
FID H 0 190
FID C 6 191
FID C 3 895
FID C 8 455
FID L 11 272
FID L 12 272
FID L 13 256
FID L 14 221
FID L 15 272
FID L 16 272
SNT TRC
FID C 3 888
FID C 3 889
FID C 3 890
FID C 3 891
FID C 3 892
FID C 3 893
FID C 3 894
# NET 571
NET IO_L20P_16 
SNT TOP T 82 0
FID H 0 191
FID C 6 3006
FID C 3 8378
FID C 8 6301
FID L 11 1508
FID L 12 1508
FID L 13 2285
FID L 14 2284
FID L 15 1508
FID L 16 1508
SNT TOP T 170 109
FID C 4 3873
FID C 5 1843
FID C 3 8381
SNT TRC
FID C 3 8379
FID C 3 8380
# NET 572
NET UNNAMED_524_FT4232HLREELQFP64_3 
SNT TOP T 13 31
FID C 4 377
FID C 5 264
FID C 3 884
SNT TOP T 79 0
FID H 0 192
FID C 6 190
FID C 3 887
FID C 8 454
FID L 11 271
FID L 12 271
FID L 13 255
FID L 14 220
FID L 15 271
FID L 16 271
SNT TRC
FID C 3 885
FID C 3 886
# NET 573
NET UNNAMED_524_FT4232HLREELQFP64_4 
SNT TOP T 13 32
FID C 4 376
FID C 5 263
FID C 3 880
SNT TOP T 81 0
FID H 0 193
FID C 6 189
FID C 3 883
FID C 8 453
FID L 11 270
FID L 12 270
FID L 13 254
FID L 14 219
FID L 15 270
FID L 16 270
SNT TRC
FID C 3 881
FID C 3 882
# NET 574
NET FT4232_SPI_CLK 
SNT TOP T 5 2
FID C 4 518
FID C 5 341
FID C 3 1408
SNT TOP T 6 2
FID C 4 519
FID C 5 342
FID C 3 1409
SNT VIA
FID H 0 1177
FID C 4 517
FID C 6 302
FID C 3 1407
FID C 8 729
FID L 11 342
FID L 12 342
FID L 13 326
FID L 14 291
FID L 15 342
FID L 16 342
SNT TRC
FID C 3 1382
FID C 3 1383
FID C 3 1384
FID C 3 1385
FID C 3 1386
FID C 3 1387
FID C 3 1388
FID C 3 1389
FID C 3 1390
FID C 3 1391
FID C 3 1392
FID C 3 1393
FID C 3 1394
FID C 3 1395
FID C 3 1396
FID C 3 1397
FID C 3 1398
FID C 3 1399
FID C 3 1400
FID C 3 1401
FID C 3 1402
FID C 3 1403
FID C 3 1404
FID C 3 1405
SNT TRC
FID C 3 1406
# NET 575
NET FT4232_SPI_MOSI 
SNT TOP T 5 5
FID C 4 507
FID C 5 335
FID C 3 1361
SNT TOP T 6 5
FID C 4 508
FID C 5 336
FID C 3 1362
SNT VIA
FID H 0 301
FID C 4 505
FID C 6 296
FID C 3 1357
FID C 9 432
FID C 8 667
FID L 11 336
FID L 12 336
FID L 13 320
FID L 14 285
FID L 15 336
FID L 16 336
SNT VIA
FID H 0 1180
FID C 4 506
FID C 6 297
FID C 3 1360
FID C 9 433
FID C 8 668
FID L 11 337
FID L 12 337
FID L 13 321
FID L 14 286
FID L 15 337
FID L 16 337
SNT TRC
FID C 3 1353
FID C 3 1354
FID C 3 1355
FID C 3 1356
SNT TRC
FID C 9 419
FID C 9 420
FID C 9 421
FID C 9 422
FID C 9 423
FID C 9 424
FID C 9 425
FID C 9 426
FID C 9 427
FID C 9 428
FID C 9 429
FID C 9 430
FID C 9 431
SNT TRC
FID C 3 1358
FID C 3 1359
# NET 576
NET FT4232_SPI_MISO 
SNT TOP T 5 9
FID C 4 510
FID C 5 337
FID C 3 1369
SNT TOP T 6 9
FID C 4 512
FID C 5 338
FID C 3 1371
SNT VIA
FID H 0 300
FID C 4 509
FID C 6 298
FID C 3 1368
FID C 8 679
FID L 11 338
FID L 12 338
FID L 13 322
FID L 14 287
FID L 15 338
FID L 16 338
SNT VIA
FID H 0 1179
FID C 4 511
FID C 6 299
FID C 3 1370
FID C 8 680
FID L 11 339
FID L 12 339
FID L 13 323
FID L 14 288
FID L 15 339
FID L 16 339
SNT TRC
FID C 8 669
FID C 8 670
FID C 8 671
FID C 8 672
FID C 8 673
FID C 8 674
FID C 8 675
FID C 8 676
FID C 8 677
FID C 8 678
SNT TRC
FID C 3 1363
FID C 3 1364
FID C 3 1365
SNT TRC
FID C 3 1366
FID C 3 1367
# NET 577
NET FT4232_SPI_CS_N 
SNT TOP T 5 12
FID C 4 514
FID C 5 339
FID C 3 1376
SNT TOP T 6 12
FID C 4 516
FID C 5 340
FID C 3 1381
SNT VIA
FID H 0 299
FID C 4 513
FID C 6 300
FID C 3 1375
FID C 8 727
FID L 11 340
FID L 12 340
FID L 13 324
FID L 14 289
FID L 15 340
FID L 16 340
SNT VIA
FID H 0 1178
FID C 4 515
FID C 6 301
FID C 3 1380
FID C 8 728
FID L 11 341
FID L 12 341
FID L 13 325
FID L 14 290
FID L 15 341
FID L 16 341
SNT TRC
FID C 8 681
FID C 8 682
FID C 8 683
FID C 8 684
FID C 8 685
FID C 8 686
FID C 8 687
FID C 8 688
FID C 8 689
FID C 8 690
FID C 8 691
FID C 8 692
FID C 8 693
FID C 8 694
FID C 8 695
FID C 8 696
FID C 8 697
FID C 8 698
FID C 8 699
FID C 8 700
FID C 8 701
FID C 8 702
FID C 8 703
FID C 8 704
FID C 8 705
FID C 8 706
FID C 8 707
FID C 8 708
FID C 8 709
FID C 8 710
FID C 8 711
FID C 8 712
FID C 8 713
FID C 8 714
FID C 8 715
FID C 8 716
FID C 8 717
FID C 8 718
FID C 8 719
FID C 8 720
FID C 8 721
FID C 8 722
FID C 8 723
FID C 8 724
FID C 8 725
FID C 8 726
SNT TRC
FID C 3 1372
FID C 3 1373
FID C 3 1374
SNT TRC
FID C 3 1377
FID C 3 1378
FID C 3 1379
#
# PKG 0
PKG S_F_H_2X6_RA_P100 0.1 -0.31496 -0.17008 0.3149599 0.48239
RC -0.31496 -0.17008 0.62992 0.34016
PIN 1 S 0.25 0.2864099 0 U U
RC 0.222 0.2404099 0.056 0.092
PIN 2 S 0.25 0.43839 0 U U
RC 0.222 0.39439 0.056 0.088
PIN 3 S 0.15 0.2864099 0 U U
RC 0.122 0.2404099 0.056 0.092
PIN 4 S 0.15 0.43839 0 U U
RC 0.122 0.39439 0.056 0.088
PIN 5 S 0.05 0.2864099 0 U U
RC 0.022 0.2404099 0.056 0.092
PIN 6 S 0.05 0.43839 0 U U
RC 0.022 0.39439 0.056 0.088
PIN 7 S -0.05 0.2864099 0 U U
RC -0.078 0.2404099 0.056 0.092
PIN 8 S -0.05 0.43839 0 U U
RC -0.078 0.39439 0.056 0.088
PIN 9 S -0.15 0.2864099 0 U U
RC -0.178 0.2404099 0.056 0.092
PIN 10 S -0.15 0.43839 0 U U
RC -0.178 0.39439 0.056 0.088
PIN 11 S -0.25 0.2864099 0 U U
RC -0.278 0.2404099 0.056 0.092
PIN 12 S -0.25 0.43839 0 U U
RC -0.278 0.39439 0.056 0.088
#
# PKG 1
PKG P_F_USB_2X7_GH4_RA_P035_PIH 0.03544 -0.10176 -0.3208201 0.13245 0.2598799
RC -0.0626 -0.3208201 0.1559 0.5807
PIN A1 T 0 0 0 U U
CR 0 0 0.012
PIN A4 T 0 0.03544 0 U U
CR 0 0.03544 0.012
PIN A5 T 0 0.0708799 0 U U
CR 0 0.0708799 0.012
PIN A6 T 0 0.10632 0 U U
CR 0 0.10632 0.012
PIN A7 T 0 0.1417599 0 U U
CR 0 0.1417599 0.012
PIN A9 T 0 0.1772 0 U U
CR 0 0.1772 0.012
PIN A12 T 0 0.21264 0 U U
CR 0 0.21264 0.012
PIN B1 T 0.0307 0.19492 0 U U
CR 0.0307 0.19492 0.012
PIN B4 T 0.0307 0.1594799 0 U U
CR 0.0307 0.1594799 0.012
PIN B5 T 0.0307 0.12404 0 U U
CR 0.0307 0.12404 0.012
PIN B6 T 0.0307 0.0886 0 U U
CR 0.0307 0.0886 0.012
PIN B7 T 0.0307 0.0531599 0 U U
CR 0.0307 0.0531599 0.012
PIN B9 T 0.0307 0.01772 0 U U
CR 0.0307 0.01772 0.012
PIN B12 T 0.0307 -0.0177201 0 U U
CR 0.0307 -0.0177201 0.012
PIN GH1 T -0.08426 0.19099 0 U U
CT
OB -0.10176003937 0.17098996063 I
OS -0.10176003937 0.21098996063
OC -0.06676003937 0.21098996063 -0.08426003937 0.21098996063 Y
OS -0.06676003937 0.17098996063
OC -0.10176003937 0.17098996063 -0.08426003937 0.17098996063 Y
OE
CE
PIN GH2 T 0.11495 0.19099 0 U U
CT
OB 0.09745 0.17098996063 I
OS 0.09745 0.21098996063
OC 0.13245 0.21098996063 0.11495 0.21098996063 Y
OS 0.13245 0.17098996063
OC 0.09745 0.17098996063 0.11495 0.17098996063 Y
OE
CE
PIN GH3 T -0.04095 0.0020099 0 U U
CT
OB -0.05845 -0.017990059055 I
OS -0.05845 0.022009940945
OC -0.02345 0.022009940945 -0.04095 0.022009940945 Y
OS -0.02345 -0.017990059055
OC -0.05845 -0.017990059055 -0.04095 -0.017990059055 Y
OE
CE
PIN GH4 T 0.07165 0.0020099 0 U U
CT
OB 0.05415 -0.017990059055 I
OS 0.05415 0.022009940945
OC 0.08915 0.022009940945 0.07165 0.022009940945 Y
OS 0.08915 -0.017990059055
OC 0.05415 -0.017990059055 0.07165 -0.017990059055 Y
OE
CE
#
# PKG 2
PKG SOT363_V2 0.02559 -0.0494 -0.04331 0.0494 0.04331
RC -0.02657 -0.04331 0.05314 0.0866201
PIN 1 S -0.0374 0.02559 0 U U
RC -0.0494 0.01709 0.024 0.017
PIN 2 S -0.0374 0 0 U U
RC -0.0494 -0.0085 0.024 0.017
PIN 3 S -0.0374 -0.02559 0 U U
RC -0.0494 -0.03409 0.024 0.017
PIN 4 S 0.0374 -0.02559 0 U U
RC 0.0254 -0.03409 0.024 0.017
PIN 5 S 0.0374 0 0 U U
RC 0.0254 -0.0085 0.024 0.017
PIN 6 S 0.0374 0.02559 0 U U
RC 0.0254 0.01709 0.024 0.017
#
# PKG 3
PKG SOP16_173_P0256 0.02559 -0.1505 -0.0985 0.1505 0.0985
RC -0.0865 -0.0985 0.173 0.197
PIN 1 S -0.1195 0.08957 0 U U
RC -0.1505 0.08257 0.062 0.014
PIN 2 S -0.1195 0.06398 0 U U
RC -0.1505 0.05698 0.062 0.014
PIN 3 S -0.1195 0.03839 0 U U
RC -0.1505 0.03139 0.062 0.014
PIN 4 S -0.1195 0.0128 0 U U
RC -0.1505 0.0058 0.062 0.014
PIN 5 S -0.1195 -0.0128 0 U U
RC -0.1505 -0.0198 0.062 0.014
PIN 6 S -0.1195 -0.03839 0 U U
RC -0.1505 -0.04539 0.062 0.014
PIN 7 S -0.1195 -0.06398 0 U U
RC -0.1505 -0.07098 0.062 0.014
PIN 8 S -0.1195 -0.08957 0 U U
RC -0.1505 -0.09657 0.062 0.014
PIN 9 S 0.1195 -0.08957 0 U U
RC 0.0885 -0.09657 0.062 0.014
PIN 10 S 0.1195 -0.06398 0 U U
RC 0.0885 -0.07098 0.062 0.014
PIN 11 S 0.1195 -0.03839 0 U U
RC 0.0885 -0.04539 0.062 0.014
PIN 12 S 0.1195 -0.0128 0 U U
RC 0.0885 -0.0198 0.062 0.014
PIN 13 S 0.1195 0.0128 0 U U
RC 0.0885 0.0058 0.062 0.014
PIN 14 S 0.1195 0.03839 0 U U
RC 0.0885 0.03139 0.062 0.014
PIN 15 S 0.1195 0.06398 0 U U
RC 0.0885 0.05698 0.062 0.014
PIN 16 S 0.1195 0.08957 0 U U
RC 0.0885 0.08257 0.062 0.014
#
# PKG 4
PKG SOP8_173X118_P0256 0.02559 -0.1505 -0.061 0.1505 0.061
RC -0.0885 -0.061 0.177 0.122
PIN 1 S -0.1195 0.03839 0 U U
RC -0.1505 0.03139 0.062 0.014
PIN 2 S -0.1195 0.0128 0 U U
RC -0.1505 0.0058 0.062 0.014
PIN 3 S -0.1195 -0.01279 0 U U
RC -0.1505 -0.01979 0.062 0.014
PIN 4 S -0.1195 -0.03838 0 U U
RC -0.1505 -0.04538 0.062 0.014
PIN 5 S 0.1195 -0.03838 0 U U
RC 0.0885 -0.04538 0.062 0.014
PIN 6 S 0.1195 -0.01279 0 U U
RC 0.0885 -0.01979 0.062 0.014
PIN 7 S 0.1195 0.0128 0 U U
RC 0.0885 0.0058 0.062 0.014
PIN 8 S 0.1195 0.03839 0 U U
RC 0.0885 0.03139 0.062 0.014
#
# PKG 5
PKG SMC_CR_067X049_V1 0.0866201 -0.05331 -0.02657 0.05331 0.02657
RC -0.03543 -0.02657 0.07086 0.05314
PIN A S 0.04331 0 0 U U
RC 0.03331 -0.01 0.02 0.02
PIN C S -0.04331 0 0 U U
RC -0.05331 -0.01 0.02 0.02
#
# PKG 6
PKG SMC_0603R_H037 0.054 -0.042 -0.018 0.042 0.018
RC -0.032 -0.018 0.064 0.036
PIN 1 S -0.027 0 0 U U
RC -0.042 -0.017 0.03 0.034
PIN 2 S 0.027 0 0 U U
RC 0.012 -0.017 0.03 0.034
#
# PKG 7
PKG QFP64_394_P0197_V1 0.0196799 -0.261 -0.261 0.261 0.261
RC -0.197 -0.197 0.394 0.394
PIN 1 S -0.229 0.14764 0 U U
RC -0.261 0.14164 0.064 0.012
PIN 2 S -0.229 0.12795 0 U U
RC -0.261 0.12195 0.064 0.012
PIN 3 S -0.229 0.10827 0 U U
RC -0.261 0.10227 0.064 0.012
PIN 4 S -0.229 0.08858 0 U U
RC -0.261 0.08258 0.064 0.012
PIN 5 S -0.229 0.0689 0 U U
RC -0.261 0.0629 0.064 0.012
PIN 6 S -0.229 0.04921 0 U U
RC -0.261 0.04321 0.064 0.012
PIN 7 S -0.229 0.02953 0 U U
RC -0.261 0.02353 0.064 0.012
PIN 8 S -0.229 0.00984 0 U U
RC -0.261 0.00384 0.064 0.012
PIN 9 S -0.229 -0.00984 0 U U
RC -0.261 -0.01584 0.064 0.012
PIN 10 S -0.229 -0.02953 0 U U
RC -0.261 -0.03553 0.064 0.012
PIN 11 S -0.229 -0.04921 0 U U
RC -0.261 -0.05521 0.064 0.012
PIN 12 S -0.229 -0.0689 0 U U
RC -0.261 -0.0749 0.064 0.012
PIN 13 S -0.229 -0.08858 0 U U
RC -0.261 -0.09458 0.064 0.012
PIN 14 S -0.229 -0.10827 0 U U
RC -0.261 -0.11427 0.064 0.012
PIN 15 S -0.229 -0.12795 0 U U
RC -0.261 -0.13395 0.064 0.012
PIN 16 S -0.229 -0.14764 0 U U
RC -0.261 -0.15364 0.064 0.012
PIN 17 S -0.14764 -0.229 0 U U
RC -0.15364 -0.261 0.012 0.064
PIN 18 S -0.12795 -0.229 0 U U
RC -0.13395 -0.261 0.012 0.064
PIN 19 S -0.10827 -0.229 0 U U
RC -0.11427 -0.261 0.012 0.064
PIN 20 S -0.08858 -0.229 0 U U
RC -0.09458 -0.261 0.012 0.064
PIN 21 S -0.0689 -0.229 0 U U
RC -0.0749 -0.261 0.012 0.064
PIN 22 S -0.04921 -0.229 0 U U
RC -0.05521 -0.261 0.012 0.064
PIN 23 S -0.02953 -0.229 0 U U
RC -0.03553 -0.261 0.012 0.064
PIN 24 S -0.00984 -0.229 0 U U
RC -0.01584 -0.261 0.012 0.064
PIN 25 S 0.00984 -0.229 0 U U
RC 0.00384 -0.261 0.012 0.064
PIN 26 S 0.02953 -0.229 0 U U
RC 0.02353 -0.261 0.012 0.064
PIN 27 S 0.04921 -0.229 0 U U
RC 0.04321 -0.261 0.012 0.064
PIN 28 S 0.0689 -0.229 0 U U
RC 0.0629 -0.261 0.012 0.064
PIN 29 S 0.08858 -0.229 0 U U
RC 0.08258 -0.261 0.012 0.064
PIN 30 S 0.10827 -0.229 0 U U
RC 0.10227 -0.261 0.012 0.064
PIN 31 S 0.12795 -0.229 0 U U
RC 0.12195 -0.261 0.012 0.064
PIN 32 S 0.14764 -0.229 0 U U
RC 0.14164 -0.261 0.012 0.064
PIN 33 S 0.229 -0.14764 0 U U
RC 0.197 -0.15364 0.064 0.012
PIN 34 S 0.229 -0.12795 0 U U
RC 0.197 -0.13395 0.064 0.012
PIN 35 S 0.229 -0.10827 0 U U
RC 0.197 -0.11427 0.064 0.012
PIN 36 S 0.229 -0.08858 0 U U
RC 0.197 -0.09458 0.064 0.012
PIN 37 S 0.229 -0.0689 0 U U
RC 0.197 -0.0749 0.064 0.012
PIN 38 S 0.229 -0.04921 0 U U
RC 0.197 -0.05521 0.064 0.012
PIN 39 S 0.229 -0.02953 0 U U
RC 0.197 -0.03553 0.064 0.012
PIN 40 S 0.229 -0.00984 0 U U
RC 0.197 -0.01584 0.064 0.012
PIN 41 S 0.229 0.00984 0 U U
RC 0.197 0.00384 0.064 0.012
PIN 42 S 0.229 0.02953 0 U U
RC 0.197 0.02353 0.064 0.012
PIN 43 S 0.229 0.04921 0 U U
RC 0.197 0.04321 0.064 0.012
PIN 44 S 0.229 0.0689 0 U U
RC 0.197 0.0629 0.064 0.012
PIN 45 S 0.229 0.08858 0 U U
RC 0.197 0.08258 0.064 0.012
PIN 46 S 0.229 0.10827 0 U U
RC 0.197 0.10227 0.064 0.012
PIN 47 S 0.229 0.12795 0 U U
RC 0.197 0.12195 0.064 0.012
PIN 48 S 0.229 0.14764 0 U U
RC 0.197 0.14164 0.064 0.012
PIN 49 S 0.14764 0.229 0 U U
RC 0.14164 0.197 0.012 0.064
PIN 50 S 0.12795 0.229 0 U U
RC 0.12195 0.197 0.012 0.064
PIN 51 S 0.10827 0.229 0 U U
RC 0.10227 0.197 0.012 0.064
PIN 52 S 0.08858 0.229 0 U U
RC 0.08258 0.197 0.012 0.064
PIN 53 S 0.0689 0.229 0 U U
RC 0.0629 0.197 0.012 0.064
PIN 54 S 0.04921 0.229 0 U U
RC 0.04321 0.197 0.012 0.064
PIN 55 S 0.02953 0.229 0 U U
RC 0.02353 0.197 0.012 0.064
PIN 56 S 0.00984 0.229 0 U U
RC 0.00384 0.197 0.012 0.064
PIN 57 S -0.00984 0.229 0 U U
RC -0.01584 0.197 0.012 0.064
PIN 58 S -0.02953 0.229 0 U U
RC -0.03553 0.197 0.012 0.064
PIN 59 S -0.04921 0.229 0 U U
RC -0.05521 0.197 0.012 0.064
PIN 60 S -0.0689 0.229 0 U U
RC -0.0749 0.197 0.012 0.064
PIN 61 S -0.08858 0.229 0 U U
RC -0.09458 0.197 0.012 0.064
PIN 62 S -0.10827 0.229 0 U U
RC -0.11427 0.197 0.012 0.064
PIN 63 S -0.12795 0.229 0 U U
RC -0.13395 0.197 0.012 0.064
PIN 64 S -0.14764 0.229 0 U U
RC -0.15364 0.197 0.012 0.064
#
# PKG 8
PKG SMC_L_287X260_V1_H197 0.21457 -0.16529 -0.13583 0.16528 0.13583
RC -0.1496 -0.13583 0.2992 0.27166
PIN 1 S -0.10729 0 0 U U
RC -0.16529 -0.069 0.116 0.138
PIN 2 S 0.10728 0 0 U U
RC 0.04928 -0.069 0.116 0.138
#
# PKG 9
PKG SOT23_V1_H044 0.074 -0.057 -0.071 0.057 0.071
CT
OB -0.057 -0.026 I
OS -0.057 0.026
OS -0.009 0.026
OS -0.009 0.045
OS 0.009 0.045
OS 0.009 0.026
OS 0.057 0.026
OS 0.057 -0.026
OS 0.046 -0.026
OS 0.046 -0.045
OS 0.028 -0.045
OS 0.028 -0.026
OS -0.028 -0.026
OS -0.028 -0.045
OS -0.046 -0.045
OS -0.046 -0.026
OS -0.057 -0.026
OE
CE
PIN 1 S -0.037 -0.0435 0 U U
RC -0.0565 -0.071 0.039 0.055
PIN 2 S 0.037 -0.0435 0 U U
RC 0.0175 -0.071 0.039 0.055
PIN 3 S 0 0.0435 0 U U
RC -0.0195 0.016 0.039 0.055
#
# PKG 10
PKG SOT23_V1_H045 0.074 -0.057 -0.071 0.057 0.071
CT
OB -0.046 -0.045 I
OS -0.046 -0.026
OS -0.057 -0.026
OS -0.057 0.026
OS -0.009 0.026
OS -0.009 0.045
OS 0.009 0.045
OS 0.009 0.026
OS 0.057 0.026
OS 0.057 -0.026
OS 0.046 -0.026
OS 0.046 -0.045
OS 0.028 -0.045
OS 0.028 -0.026
OS -0.028 -0.026
OS -0.028 -0.045
OS -0.046 -0.045
OE
CE
PIN 1 S -0.037 -0.0435 0 U U
RC -0.0565 -0.071 0.039 0.055
PIN 2 S 0.037 -0.0435 0 U U
RC 0.0175 -0.071 0.039 0.055
PIN 3 S 0 0.0435 0 U U
RC -0.0195 0.016 0.039 0.055
#
# PKG 11
PKG TP010CT020B030_PTH 0 -0.035 -0.035 0.035 0.035
CR 0 0 0.035
PIN 1 T 0 0 0 U U
CR 0 0 0.01
#
# PKG 12
PKG S_M_H_2X2_S_P100_V3 0.1 -0.09193 -0.17256 0.09193 0.17256
RC -0.09193 -0.09606 0.18386 0.1921201
PIN 1 S -0.05 -0.10256 0 U U
RC -0.075 -0.17256 0.05 0.14
PIN 2 S -0.05 0.10256 0 U U
RC -0.075 0.03256 0.05 0.14
PIN 3 S 0.05 -0.10256 0 U U
RC 0.025 -0.17256 0.05 0.14
PIN 4 S 0.05 0.10256 0 U U
RC 0.025 0.03256 0.05 0.14
#
# PKG 13
PKG SMC_0402R_C_H016 0.03938 -0.03219 -0.0125 0.0321901 0.0125
RC -0.02 -0.012 0.04 0.024
PIN 1 S -0.01969 0 0 U U
CR -0.01969 0 0.0125
PIN 2 S 0.0196901 0 0 U U
CR 0.0196901 0 0.0125
#
# PKG 14
PKG P_F_JACK_1P_GH4_RA_P200 0.1414213 -0.53937 -0.145 0.145 0.145
RC -0.53937 -0.14173 0.6811 0.28346
PIN 1 T 0 0 0 U U
CR 0 0 0.043
PIN GH1 T -0.1 0.1 0 U U
CR -0.1 0.1 0.045
PIN GH2 T 0.1 0.1 0 U U
CR 0.1 0.1 0.045
PIN GH3 T -0.1 -0.1 0 U U
CR -0.1 -0.1 0.045
PIN GH4 T 0.1 -0.1 0 U U
CR 0.1 -0.1 0.045
#
# PKG 15
PKG SMC_DS4_098X039 0.03346 -0.06867 -0.0334599 0.06867 0.0226401
CT
OB -0.04428996063 0.022640059055 I
OS 0.044290059055 0.022640059055
OS 0.044290059055 0.00296003937
OS 0.052169980315 0.00296003937
OS 0.052169980315 -0.02262992126
OS -0.052169980315 -0.02262992126
OS -0.052169980315 0.00296003937
OS -0.04428996063 0.00296003937
OS -0.04428996063 0.022640059055
OE
CE
PIN 1 S -0.05217 -0.0096799 0 U U
RC -0.06867 -0.0271799 0.033 0.035
PIN 2 S -0.01673 -0.0234599 0 U U
RC -0.02573 -0.0334599 0.018 0.02
PIN 3 S 0.01673 -0.0234599 0 U U
RC 0.00773 -0.0334599 0.018 0.02
PIN 4 S 0.05217 -0.0096799 0 U U
RC 0.03567 -0.0271799 0.033 0.035
#
# PKG 16
PKG DFN11_118_P0197_TR057X071_VIA 0.01969 -0.08017 -0.06004 0.08017 0.06004
RC -0.06004 -0.06004 0.1200799 0.1200799
PIN 1 S -0.05967 0.03938 0 U U
CT
OB -0.05515 0.054380019685 I
OS -0.039169980315 0.054380019685
OS -0.039169980315 0.033380019685
OS -0.080169980315 0.033380019685
OS -0.080169980315 0.045380019685
OS -0.05515 0.045380019685
OS -0.05515 0.054380019685
OE
CE
PIN 2 S -0.05967 0.01969 0 U U
RC -0.08017 0.01369 0.041 0.012
PIN 3 S -0.05967 0 0 U U
RC -0.08017 -0.006 0.041 0.012
PIN 4 S -0.05967 -0.01969 0 U U
RC -0.08017 -0.02569 0.041 0.012
PIN 5 S -0.05967 -0.03938 0 U U
CT
OB -0.05515 -0.054380019685 I
OS -0.05515 -0.045380019685
OS -0.080169980315 -0.045380019685
OS -0.080169980315 -0.033380019685
OS -0.039169980315 -0.033380019685
OS -0.039169980315 -0.054380019685
OS -0.05515 -0.054380019685
OE
CE
PIN 6 S 0.05967 -0.03938 0 U U
CT
OB 0.05515 -0.054380019685 I
OS 0.039169980315 -0.054380019685
OS 0.039169980315 -0.033380019685
OS 0.080169980315 -0.033380019685
OS 0.080169980315 -0.045380019685
OS 0.05515 -0.045380019685
OS 0.05515 -0.054380019685
OE
CE
PIN 7 S 0.05967 -0.01969 0 U U
RC 0.03917 -0.02569 0.041 0.012
PIN 8 S 0.05967 0 0 U U
RC 0.03917 -0.006 0.041 0.012
PIN 9 S 0.05967 0.01969 0 U U
RC 0.03917 0.01369 0.041 0.012
PIN 10 S 0.05967 0.03938 0 U U
CT
OB 0.05515 0.054380019685 I
OS 0.05515 0.045380019685
OS 0.080169980315 0.045380019685
OS 0.080169980315 0.033380019685
OS 0.039169980315 0.033380019685
OS 0.039169980315 0.054380019685
OS 0.05515 0.054380019685
OE
CE
PIN 11 S 0 0 0 U U
RC -0.0285 -0.0355 0.057 0.071
#
# PKG 17
PKG DFN13_118_P0197_TR071X096_VIA 0.0196799 -0.08025 -0.05906 0.08025 0.06021
RC -0.05906 -0.05906 0.1181201 0.1181201
PIN 1 S -0.06375 0.05171 0 U U
RC -0.08025 0.04321 0.033 0.017
PIN 2 S -0.06375 0.02953 0 U U
RC -0.08025 0.02353 0.033 0.012
PIN 3 S -0.06375 0.00984 0 U U
RC -0.08025 0.00384 0.033 0.012
PIN 4 S -0.06375 -0.00984 0 U U
RC -0.08025 -0.01584 0.033 0.012
PIN 5 S -0.06375 -0.02953 0 U U
RC -0.08025 -0.03553 0.033 0.012
PIN 6 S -0.06375 -0.04921 0 U U
RC -0.08025 -0.05521 0.033 0.012
PIN 7 S 0.06375 -0.04921 0 U U
RC 0.04725 -0.05521 0.033 0.012
PIN 8 S 0.06375 -0.02953 0 U U
RC 0.04725 -0.03553 0.033 0.012
PIN 9 S 0.06375 -0.00984 0 U U
RC 0.04725 -0.01584 0.033 0.012
PIN 10 S 0.06375 0.00984 0 U U
RC 0.04725 0.00384 0.033 0.012
PIN 11 S 0.06375 0.02953 0 U U
RC 0.04725 0.02353 0.033 0.012
PIN 12 S 0.06375 0.04921 0 U U
RC 0.04725 0.04321 0.033 0.012
PIN 13 S 0 0 0 U U
RC -0.0355 -0.048 0.071 0.096
#
# PKG 18
PKG QFN29_197_P0197_TR115SQ_V1 0.01968 -0.1196 -0.1196 0.1196 0.1196
RC -0.09843 -0.09843 0.19686 0.19686
PIN 1 S -0.0966 0.05906 0 U U
RC -0.1196 0.05306 0.046 0.012
PIN 2 S -0.0951 0.03937 0 U U
RC -0.1196 0.03337 0.049 0.012
PIN 3 S -0.0951 0.01969 0 U U
RC -0.1196 0.01369 0.049 0.012
PIN 4 S -0.0951 0 0 U U
RC -0.1196 -0.006 0.049 0.012
PIN 5 S -0.0951 -0.01969 0 U U
RC -0.1196 -0.02569 0.049 0.012
PIN 6 S -0.0951 -0.03937 0 U U
RC -0.1196 -0.04537 0.049 0.012
PIN 7 S -0.0966 -0.05906 0 U U
RC -0.1196 -0.06506 0.046 0.012
PIN 8 S -0.05906 -0.0966 0 U U
RC -0.06506 -0.1196 0.012 0.046
PIN 9 S -0.03937 -0.0951 0 U U
RC -0.04537 -0.1196 0.012 0.049
PIN 10 S -0.01969 -0.0951 0 U U
RC -0.02569 -0.1196 0.012 0.049
PIN 11 S 0 -0.0951 0 U U
RC -0.006 -0.1196 0.012 0.049
PIN 12 S 0.01969 -0.0951 0 U U
RC 0.01369 -0.1196 0.012 0.049
PIN 13 S 0.03937 -0.0951 0 U U
RC 0.03337 -0.1196 0.012 0.049
PIN 14 S 0.05906 -0.0966 0 U U
RC 0.05306 -0.1196 0.012 0.046
PIN 15 S 0.0966 -0.05906 0 U U
RC 0.0736 -0.06506 0.046 0.012
PIN 16 S 0.0951 -0.03937 0 U U
RC 0.0706 -0.04537 0.049 0.012
PIN 17 S 0.0951 -0.01969 0 U U
RC 0.0706 -0.02569 0.049 0.012
PIN 18 S 0.0951 0 0 U U
RC 0.0706 -0.006 0.049 0.012
PIN 19 S 0.0951 0.01969 0 U U
RC 0.0706 0.01369 0.049 0.012
PIN 20 S 0.0951 0.03937 0 U U
RC 0.0706 0.03337 0.049 0.012
PIN 21 S 0.0966 0.05906 0 U U
RC 0.0736 0.05306 0.046 0.012
PIN 22 S 0.05906 0.0966 0 U U
RC 0.05306 0.0736 0.012 0.046
PIN 23 S 0.03937 0.0951 0 U U
RC 0.03337 0.0706 0.012 0.049
PIN 24 S 0.01969 0.0951 0 U U
RC 0.01369 0.0706 0.012 0.049
PIN 25 S 0 0.0951 0 U U
RC -0.006 0.0706 0.012 0.049
PIN 26 S -0.01969 0.0951 0 U U
RC -0.02569 0.0706 0.012 0.049
PIN 27 S -0.03937 0.0951 0 U U
RC -0.04537 0.0706 0.012 0.049
PIN 28 S -0.05906 0.0966 0 U U
RC -0.06506 0.0736 0.012 0.046
PIN 29 S 0 0 0 U U
RC -0.0575 -0.0575 0.115 0.115
#
# PKG 19
PKG SMC_0402R_C_H022 0.03938 -0.0321901 -0.0125 0.03219 0.0125
RC -0.02 -0.012 0.04 0.024
PIN 1 S -0.0196901 0 0 U U
CR -0.0196901 0 0.0125
PIN 2 S 0.01969 0 0 U U
CR 0.01969 0 0.0125
#
# PKG 20
PKG SMC_0402R_C_H026 0.03938 -0.0321901 -0.0125 0.03219 0.0125
RC -0.02 -0.012 0.04 0.024
PIN 1 S -0.01969 0 0 U U
CR -0.0196901 0 0.0125
PIN 2 S 0.0196901 0 0 U U
CR 0.01969 0 0.0125
#
# PKG 21
PKG MTH100C240N 0 -0.12 -0.12 0.12 0.12
CR 0 0 0.12
PIN un_1 T 0 0 0 U U
CR 0 0 0.045
#
# PKG 22
PKG SOP8_091_P0197_H035 0.01968 -0.08554 -0.04134 0.08554 0.0413402
RC -0.04724 -0.04134 0.0944799 0.0826801
PIN 1 S -0.06654 0.0295201 0 U U
RC -0.08554 0.0235201 0.038 0.012
PIN 2 S -0.06654 0.0098401 0 U U
RC -0.08554 0.0038401 0.038 0.012
PIN 3 S -0.06654 -0.00984 0 U U
RC -0.08554 -0.01584 0.038 0.012
PIN 4 S -0.06654 -0.02952 0 U U
RC -0.08554 -0.03552 0.038 0.012
PIN 5 S 0.0665401 -0.02952 0 U U
RC 0.04754 -0.03552 0.038 0.012
PIN 6 S 0.0665401 -0.00984 0 U U
RC 0.04754 -0.01584 0.038 0.012
PIN 7 S 0.0665401 0.0098401 0 U U
RC 0.04754 0.0038401 0.038 0.012
PIN 8 S 0.0665401 0.0295201 0 U U
RC 0.04754 0.0235201 0.038 0.012
#
# PKG 23
PKG MTH125C236N_V8 0.07386 -0.118 -0.118 0.118 0.118
CR 0 0 0.118
PIN 1 T 0 0.0965 0 U U
CR 0 0.0965 0.012
PIN 2 T 0.06824 0.06824 0 U U
CR 0.0682401 0.0682401 0.012
PIN 3 T 0.0965 0 0 U U
CR 0.0965 0 0.012
PIN 4 T 0.06824 -0.0682401 0 U U
CR 0.0682401 -0.06824 0.012
PIN 5 T 0 -0.0965 0 U U
CR 0 -0.0965 0.012
PIN 6 T -0.0682401 -0.0682401 0 U U
CR -0.06824 -0.06824 0.012
PIN 7 T -0.0965 0 0 U U
CR -0.0965 0 0.012
PIN 8 T -0.0682401 0.06824 0 U U
CR -0.06824 0.0682401 0.012
PIN un_1 T 0 0 0 U U
CR 0 0 0.0575
#
# PKG 24
PKG SOT23_5_H039 0.0374 -0.08 -0.05709 0.08 0.05709
CT
OB 0.0315 0.05708996063 I
OS 0.0315 0.04723996063
OS 0.05906003937 0.04723996063
OS 0.05906003937 0.02756003937
OS 0.0315 0.02756003937
OS 0.0315 -0.02756003937
OS 0.05906003937 -0.02756003937
OS 0.05906003937 -0.04723996063
OS 0.0315 -0.04723996063
OS 0.0315 -0.05708996063
OS -0.0315 -0.05708996063
OS -0.0315 -0.04723996063
OS -0.05906003937 -0.04723996063
OS -0.05906003937 -0.02756003937
OS -0.0315 -0.02756003937
OS -0.0315 -0.00983996063
OS -0.05906003937 -0.00983996063
OS -0.05906003937 0.00983996063
OS -0.0315 0.00983996063
OS -0.0315 0.02756003937
OS -0.05906003937 0.02756003937
OS -0.05906003937 0.04723996063
OS -0.0315 0.04723996063
OS -0.0315 0.05708996063
OS 0.0315 0.05708996063
OE
CE
PIN 1 S -0.0565 0.0374 0 U U
RC -0.08 0.0274 0.047 0.02
PIN 2 S -0.0565 0 0 U U
RC -0.08 -0.01 0.047 0.02
PIN 3 S -0.0565 -0.0374 0 U U
RC -0.08 -0.0474 0.047 0.02
PIN 4 S 0.0565 -0.0374 0 U U
RC 0.033 -0.0474 0.047 0.02
PIN 5 S 0.0565 0.0374 0 U U
RC 0.033 0.0274 0.047 0.02
#
# PKG 25
PKG P_NUT_079C100 0 -0.05 -0.05 0.05 0.05
CR 0 0 0.046
PIN 1 T 0 0 0 U U
CR 0 0 0.05
#
# PKG 26
PKG DFN9_098_P0197_TR039X071 0.0196799 -0.07032 -0.05118 0.07032 0.05118
RC -0.05118 -0.05118 0.10236 0.10236
PIN 1 S -0.04982 0.02953 0 U U
RC -0.07032 0.02353 0.041 0.012
PIN 2 S -0.04982 0.00984 0 U U
RC -0.07032 0.00384 0.041 0.012
PIN 3 S -0.04982 -0.00984 0 U U
RC -0.07032 -0.01584 0.041 0.012
PIN 4 S -0.04982 -0.02953 0 U U
RC -0.07032 -0.03553 0.041 0.012
PIN 5 S 0.04982 -0.02953 0 U U
RC 0.02932 -0.03553 0.041 0.012
PIN 6 S 0.04982 -0.00984 0 U U
RC 0.02932 -0.01584 0.041 0.012
PIN 7 S 0.04982 0.00984 0 U U
RC 0.02932 0.00384 0.041 0.012
PIN 8 S 0.04982 0.02953 0 U U
RC 0.02932 0.02353 0.041 0.012
PIN 9 S 0 0 0 U U
RC -0.0195 -0.0355 0.039 0.071
#
# PKG 27
PKG P_M_H_2X3_NP2_RA_P165_V1 0.16535 -0.27913 -0.50476 0.2791299 0.26732
RC -0.27913 -0.25157 0.5582599 0.51889
PIN 1 T -0.16535 -0.2874 0 U U
RC -0.21735 -0.3394 0.104 0.104
PIN 2 T 0 -0.2874 0 U U
CR 0 -0.2874 0.052
PIN 3 T 0.16535 -0.2874 0 U U
CR 0.16535 -0.2874 0.052
PIN 4 T -0.16535 -0.45276 0 U U
CR -0.16535 -0.45276 0.052
PIN 5 T 0 -0.45276 0 U U
CR 0 -0.45276 0.052
PIN 6 T 0.16535 -0.45276 0 U U
CR 0.16535 -0.45276 0.052
PIN un_1 T 0.16535 0 0 U U
CR 0.16535 0 0.054
PIN un_2 T -0.16535 0 0 U U
CR -0.16535 0 0.054
#
# PKG 28
PKG P_NUT_166CT244CB198_V1_H380 0 -0.122 -0.122 0.122 0.122
CR 0 0 0.112
PIN 1 T 0 0 0 U U
CR 0 0 0.122
#
# PKG 29
PKG LGA10_079_P0197 0.01968 -0.04134 -0.04134 0.0413401 0.04134
RC -0.04134 -0.04134 0.08268 0.0826799
PIN 1 S -0.00984 -0.03051 0 U U
RC -0.01534 -0.03751 0.011 0.014
PIN 2 S 0.0098401 -0.03051 0 U U
RC 0.0043401 -0.03751 0.011 0.014
PIN 3 S 0.03051 -0.01969 0 U U
RC 0.02351 -0.02519 0.014 0.011
PIN 4 S 0.03051 0 0 U U
RC 0.02351 -0.0055 0.014 0.011
PIN 5 S 0.03051 0.01969 0 U U
RC 0.02351 0.01419 0.014 0.011
PIN 6 S 0.0098401 0.03051 0 U U
RC 0.0043401 0.02351 0.011 0.014
PIN 7 S -0.00984 0.03051 0 U U
RC -0.01534 0.02351 0.011 0.014
PIN 8 S -0.0305099 0.01969 0 U U
RC -0.0375099 0.01419 0.014 0.011
PIN 9 S -0.0305099 0 0 U U
RC -0.0375099 -0.0055 0.014 0.011
PIN 10 S -0.0305099 -0.01969 0 U U
RC -0.0375099 -0.02519 0.014 0.011
#
# PKG 30
PKG LGA28_205X150_P0197 0.0196799 -0.07502 -0.10254 0.07502 0.10254
RC -0.0748 -0.10236 0.1496 0.2047201
PIN 1 S 0.06152 0.08858 0 U U
RC 0.04802 0.08358 0.027 0.01
PIN 2 S 0.02953 0.09104 0 U U
RC 0.02453 0.07954 0.01 0.023
PIN 3 S 0.00984 0.09104 0 U U
RC 0.00484 0.07954 0.01 0.023
PIN 4 S -0.00984 0.09104 0 U U
RC -0.01484 0.07954 0.01 0.023
PIN 5 S -0.02953 0.09104 0 U U
RC -0.03453 0.07954 0.01 0.023
PIN 6 S -0.06152 0.08858 0 U U
RC -0.07502 0.08358 0.027 0.01
PIN 7 S -0.06152 0.0689 0 U U
RC -0.07502 0.0639 0.027 0.01
PIN 8 S -0.06152 0.04921 0 U U
RC -0.07502 0.04421 0.027 0.01
PIN 9 S -0.06152 0.02953 0 U U
RC -0.07502 0.02453 0.027 0.01
PIN 10 S -0.06152 0.00984 0 U U
RC -0.07502 0.00484 0.027 0.01
PIN 11 S -0.06152 -0.00984 0 U U
RC -0.07502 -0.01484 0.027 0.01
PIN 12 S -0.06152 -0.02953 0 U U
RC -0.07502 -0.03453 0.027 0.01
PIN 13 S -0.06152 -0.04921 0 U U
RC -0.07502 -0.05421 0.027 0.01
PIN 14 S -0.06152 -0.0689 0 U U
RC -0.07502 -0.0739 0.027 0.01
PIN 15 S -0.06152 -0.08858 0 U U
RC -0.07502 -0.09358 0.027 0.01
PIN 16 S -0.02953 -0.09104 0 U U
RC -0.03453 -0.10254 0.01 0.023
PIN 17 S -0.00984 -0.09104 0 U U
RC -0.01484 -0.10254 0.01 0.023
PIN 18 S 0.00984 -0.09104 0 U U
RC 0.00484 -0.10254 0.01 0.023
PIN 19 S 0.02953 -0.09104 0 U U
RC 0.02453 -0.10254 0.01 0.023
PIN 20 S 0.06152 -0.08858 0 U U
RC 0.04802 -0.09358 0.027 0.01
PIN 21 S 0.06152 -0.0689 0 U U
RC 0.04802 -0.0739 0.027 0.01
PIN 22 S 0.06152 -0.04921 0 U U
RC 0.04802 -0.05421 0.027 0.01
PIN 23 S 0.06152 -0.02953 0 U U
RC 0.04802 -0.03453 0.027 0.01
PIN 24 S 0.06152 -0.00984 0 U U
RC 0.04802 -0.01484 0.027 0.01
PIN 25 S 0.06152 0.00984 0 U U
RC 0.04802 0.00484 0.027 0.01
PIN 26 S 0.06152 0.02953 0 U U
RC 0.04802 0.02453 0.027 0.01
PIN 27 S 0.06152 0.04921 0 U U
RC 0.04802 0.04421 0.027 0.01
PIN 28 S 0.06152 0.0689 0 U U
RC 0.04802 0.0639 0.027 0.01
#
# PKG 31
PKG SMC_0603R_H030 0.054 -0.042 -0.018 0.042 0.018
RC -0.032 -0.018 0.064 0.036
PIN 1 S -0.027 0 0 U U
RC -0.042 -0.017 0.03 0.034
PIN 2 S 0.027 0 0 U U
RC 0.012 -0.017 0.03 0.034
#
# PKG 32
PKG DPAK_3_V3 0.18 -0.1325 -0.264 0.1325 0.199
CT
OB 0.07750019685 0.1725 I
OS 0.1075 0.14250019685
OS 0.1075 0.1225
OS 0.1325 0.1225
OS 0.1325 -0.1225
OS 0.1075 -0.1225
OS 0.1075 -0.1625
OS 0.1125 -0.1625
OS 0.1125 -0.2075
OS 0.1075 -0.2075
OS 0.1075 -0.2375
OS 0.0725 -0.2375
OS 0.0725 -0.2075
OS 0.0675 -0.2075
OS 0.0675 -0.1625
OS 0.0725 -0.1625
OS 0.0725 -0.1225
OS 0.0175 -0.1225
OS 0.0175 -0.1625
OS -0.0175 -0.1625
OS -0.0175 -0.1225
OS -0.0725 -0.1225
OS -0.0725 -0.1625
OS -0.0675 -0.1625
OS -0.0675 -0.2075
OS -0.0725 -0.2075
OS -0.0725 -0.2375
OS -0.1075 -0.2375
OS -0.1075 -0.2075
OS -0.1125 -0.2075
OS -0.1125 -0.1625
OS -0.1075 -0.1625
OS -0.1075 -0.1225
OS -0.1325 -0.1225
OS -0.1325 0.1225
OS -0.1075 0.1225
OS -0.1075 0.14250019685
OS -0.07750019685 0.1725
OS 0.07750019685 0.1725
OE
CE
PIN 1 S -0.09 -0.205 0 U U
RC -0.1215 -0.264 0.063 0.118
PIN 2 S 0.09 -0.205 0 U U
RC 0.0585 -0.264 0.063 0.118
PIN 3 S 0 0.077 0 U U
RC -0.114 -0.045 0.228 0.244
#
# PKG 33
PKG SMC_Y6_197X276 0.1 -0.10039 -0.13976 0.10039 0.13976
RC -0.10039 -0.13976 0.2007799 0.2795201
PIN 1 S -0.07283 0.1 0 U U
RC -0.09233 0.0725 0.039 0.055
PIN 2 S -0.07283 0 0 U U
RC -0.09233 -0.0275 0.039 0.055
PIN 3 S -0.07283 -0.1 0 U U
RC -0.09233 -0.1275 0.039 0.055
PIN 4 S 0.07283 -0.1 0 U U
RC 0.05333 -0.1275 0.039 0.055
PIN 5 S 0.07283 0 0 U U
RC 0.05333 -0.0275 0.039 0.055
PIN 6 S 0.07283 0.1 0 U U
RC 0.05333 0.0725 0.039 0.055
#
# PKG 34
PKG SMC_Y6_126X197 0.05 -0.06496 -0.10039 0.06496 0.10039
RC -0.06496 -0.10039 0.1299201 0.2007799
PIN 1 S -0.04134 0.05 0 U U
RC -0.05884 0.0375 0.035 0.025
PIN 2 S -0.04134 0 0 U U
RC -0.05884 -0.0125 0.035 0.025
PIN 3 S -0.04134 -0.05 0 U U
RC -0.05884 -0.0625 0.035 0.025
PIN 4 S 0.04134 -0.05 0 U U
RC 0.02384 -0.0625 0.035 0.025
PIN 5 S 0.04134 0 0 U U
RC 0.02384 -0.0125 0.035 0.025
PIN 6 S 0.04134 0.05 0 U U
RC 0.02384 0.0375 0.035 0.025
#
# PKG 35
PKG S_F_H_2X4_S_P0787_V1 0.07874 -0.16825 -0.10847 0.16825 0.1084599
RC -0.16825 -0.0813 0.3365 0.1626
PIN 1 S 0.1181099 -0.06447 0 U U
RC 0.0981099 -0.10847 0.04 0.088
PIN 2 S 0.1181099 0.0644599 0 U U
RC 0.0981099 0.0204599 0.04 0.088
PIN 3 S 0.03937 -0.06447 0 U U
RC 0.01937 -0.10847 0.04 0.088
PIN 4 S 0.03937 0.0644599 0 U U
RC 0.01937 0.0204599 0.04 0.088
PIN 5 S -0.0393701 -0.06447 0 U U
RC -0.0593701 -0.10847 0.04 0.088
PIN 6 S -0.0393701 0.0644599 0 U U
RC -0.0593701 0.0204599 0.04 0.088
PIN 7 S -0.11811 -0.06447 0 U U
RC -0.13811 -0.10847 0.04 0.088
PIN 8 S -0.11811 0.0644599 0 U U
RC -0.13811 0.0204599 0.04 0.088
#
# PKG 36
PKG SOP8_208_P050_V2 0.05 -0.18 -0.10807 0.18 0.10807
RC -0.10807 -0.10807 0.21614 0.21614
PIN 1 S -0.144 0.075 0 U U
RC -0.18 0.065 0.072 0.02
PIN 2 S -0.144 0.025 0 U U
RC -0.18 0.015 0.072 0.02
PIN 3 S -0.144 -0.025 0 U U
RC -0.18 -0.035 0.072 0.02
PIN 4 S -0.144 -0.075 0 U U
RC -0.18 -0.085 0.072 0.02
PIN 5 S 0.144 -0.075 0 U U
RC 0.108 -0.085 0.072 0.02
PIN 6 S 0.144 -0.025 0 U U
RC 0.108 -0.035 0.072 0.02
PIN 7 S 0.144 0.025 0 U U
RC 0.108 0.015 0.072 0.02
PIN 8 S 0.144 0.075 0 U U
RC 0.108 0.065 0.072 0.02
#
# PKG 37
PKG S_M_H_2X10_S_P0197 0.0196799 -0.17717 -0.11424 0.17717 0.11424
CT
OB -0.177169980315 0.11023996063 I
OS 0.177169980315 0.11023996063
OS 0.177169980315 -0.11023996063
OS -0.158049901575 -0.11023996063
OS -0.177169980315 -0.09112992126
OS -0.177169980315 0.11023996063
OE
CE
PIN 1 S -0.08858 -0.07874 0 U U
RC -0.09358 -0.11424 0.01 0.071
PIN 2 S -0.08858 0.07874 0 U U
RC -0.09358 0.04324 0.01 0.071
PIN 3 S -0.0689 -0.07874 0 U U
RC -0.0739 -0.11424 0.01 0.071
PIN 4 S -0.0689 0.07874 0 U U
RC -0.0739 0.04324 0.01 0.071
PIN 5 S -0.04921 -0.07874 0 U U
RC -0.05421 -0.11424 0.01 0.071
PIN 6 S -0.04921 0.07874 0 U U
RC -0.05421 0.04324 0.01 0.071
PIN 7 S -0.02953 -0.07874 0 U U
RC -0.03453 -0.11424 0.01 0.071
PIN 8 S -0.02953 0.07874 0 U U
RC -0.03453 0.04324 0.01 0.071
PIN 9 S -0.0098401 -0.07874 0 U U
RC -0.0148401 -0.11424 0.01 0.071
PIN 10 S -0.0098401 0.07874 0 U U
RC -0.0148401 0.04324 0.01 0.071
PIN 11 S 0.00984 -0.07874 0 U U
RC 0.00484 -0.11424 0.01 0.071
PIN 12 S 0.00984 0.07874 0 U U
RC 0.00484 0.04324 0.01 0.071
PIN 13 S 0.02953 -0.07874 0 U U
RC 0.02453 -0.11424 0.01 0.071
PIN 14 S 0.02953 0.07874 0 U U
RC 0.02453 0.04324 0.01 0.071
PIN 15 S 0.0492099 -0.07874 0 U U
RC 0.0442099 -0.11424 0.01 0.071
PIN 16 S 0.0492099 0.07874 0 U U
RC 0.0442099 0.04324 0.01 0.071
PIN 17 S 0.0689 -0.07874 0 U U
RC 0.0639 -0.11424 0.01 0.071
PIN 18 S 0.0689 0.07874 0 U U
RC 0.0639 0.04324 0.01 0.071
PIN 19 S 0.08858 -0.07874 0 U U
RC 0.08358 -0.11424 0.01 0.071
PIN 20 S 0.08858 0.07874 0 U U
RC 0.08358 0.04324 0.01 0.071
#
# PKG 38
PKG BGA484_906_P0394_V3 0.03937 -0.45276 -0.45276 0.45276 0.45276
RC -0.45276 -0.45276 0.9055201 0.9055201
PIN A1 S -0.41339 0.41339 0 U U
CR -0.41339 0.41339 0.00985
PIN A2 S -0.37402 0.41339 0 U U
CR -0.37402 0.41339 0.00985
PIN A3 S -0.33465 0.41339 0 U U
CR -0.33465 0.41339 0.00985
PIN A4 S -0.29527 0.41339 0 U U
CR -0.29527 0.41339 0.00985
PIN A5 S -0.2559 0.41339 0 U U
CR -0.2559 0.41339 0.00985
PIN A6 S -0.21653 0.41339 0 U U
CR -0.21653 0.41339 0.00985
PIN A7 S -0.17716 0.41339 0 U U
CR -0.17716 0.41339 0.00985
PIN A8 S -0.13779 0.41339 0 U U
CR -0.13779 0.41339 0.00985
PIN A9 S -0.09842 0.41339 0 U U
CR -0.09842 0.41339 0.00985
PIN A10 S -0.05905 0.41339 0 U U
CR -0.05905 0.41339 0.00985
PIN A11 S -0.01968 0.41339 0 U U
CR -0.01968 0.41339 0.00985
PIN A12 S 0.01969 0.41339 0 U U
CR 0.01969 0.41339 0.00985
PIN A13 S 0.05906 0.41339 0 U U
CR 0.05906 0.41339 0.00985
PIN A14 S 0.09843 0.41339 0 U U
CR 0.09843 0.41339 0.00985
PIN A15 S 0.1378 0.41339 0 U U
CR 0.1378 0.41339 0.00985
PIN A16 S 0.17717 0.41339 0 U U
CR 0.17717 0.41339 0.00985
PIN A17 S 0.21654 0.41339 0 U U
CR 0.21654 0.41339 0.00985
PIN A18 S 0.25591 0.41339 0 U U
CR 0.25591 0.41339 0.00985
PIN A19 S 0.29528 0.41339 0 U U
CR 0.29528 0.41339 0.00985
PIN A20 S 0.33465 0.41339 0 U U
CR 0.33465 0.41339 0.00985
PIN A21 S 0.37402 0.41339 0 U U
CR 0.37402 0.41339 0.00985
PIN A22 S 0.41339 0.41339 0 U U
CR 0.41339 0.41339 0.00985
PIN AA1 S -0.41339 -0.37402 0 U U
CR -0.41339 -0.37402 0.00985
PIN AA2 S -0.37402 -0.37402 0 U U
CR -0.37402 -0.37402 0.00985
PIN AA3 S -0.33465 -0.37402 0 U U
CR -0.33465 -0.37402 0.00985
PIN AA4 S -0.29527 -0.37402 0 U U
CR -0.29527 -0.37402 0.00985
PIN AA5 S -0.2559 -0.37402 0 U U
CR -0.2559 -0.37402 0.00985
PIN AA6 S -0.21653 -0.37402 0 U U
CR -0.21653 -0.37402 0.00985
PIN AA7 S -0.17716 -0.37402 0 U U
CR -0.17716 -0.37402 0.00985
PIN AA8 S -0.13779 -0.37402 0 U U
CR -0.13779 -0.37402 0.00985
PIN AA9 S -0.09842 -0.37402 0 U U
CR -0.09842 -0.37402 0.00985
PIN AA10 S -0.05905 -0.37402 0 U U
CR -0.05905 -0.37402 0.00985
PIN AA11 S -0.01968 -0.37402 0 U U
CR -0.01968 -0.37402 0.00985
PIN AA12 S 0.01969 -0.37402 0 U U
CR 0.01969 -0.37402 0.00985
PIN AA13 S 0.05906 -0.37402 0 U U
CR 0.05906 -0.37402 0.00985
PIN AA14 S 0.09843 -0.37402 0 U U
CR 0.09843 -0.37402 0.00985
PIN AA15 S 0.1378 -0.37402 0 U U
CR 0.1378 -0.37402 0.00985
PIN AA16 S 0.17717 -0.37402 0 U U
CR 0.17717 -0.37402 0.00985
PIN AA17 S 0.21654 -0.37402 0 U U
CR 0.21654 -0.37402 0.00985
PIN AA18 S 0.25591 -0.37402 0 U U
CR 0.25591 -0.37402 0.00985
PIN AA19 S 0.29528 -0.37402 0 U U
CR 0.29528 -0.37402 0.00985
PIN AA20 S 0.33465 -0.37402 0 U U
CR 0.33465 -0.37402 0.00985
PIN AA21 S 0.37402 -0.37402 0 U U
CR 0.37402 -0.37402 0.00985
PIN AA22 S 0.41339 -0.37402 0 U U
CR 0.41339 -0.37402 0.00985
PIN AB1 S -0.41339 -0.41339 0 U U
CR -0.41339 -0.41339 0.00985
PIN AB2 S -0.37402 -0.41339 0 U U
CR -0.37402 -0.41339 0.00985
PIN AB3 S -0.33465 -0.41339 0 U U
CR -0.33465 -0.41339 0.00985
PIN AB4 S -0.29527 -0.41339 0 U U
CR -0.29527 -0.41339 0.00985
PIN AB5 S -0.2559 -0.41339 0 U U
CR -0.2559 -0.41339 0.00985
PIN AB6 S -0.21653 -0.41339 0 U U
CR -0.21653 -0.41339 0.00985
PIN AB7 S -0.17716 -0.41339 0 U U
CR -0.17716 -0.41339 0.00985
PIN AB8 S -0.13779 -0.41339 0 U U
CR -0.13779 -0.41339 0.00985
PIN AB9 S -0.09842 -0.41339 0 U U
CR -0.09842 -0.41339 0.00985
PIN AB10 S -0.05905 -0.41339 0 U U
CR -0.05905 -0.41339 0.00985
PIN AB11 S -0.01968 -0.41339 0 U U
CR -0.01968 -0.41339 0.00985
PIN AB12 S 0.01969 -0.41339 0 U U
CR 0.01969 -0.41339 0.00985
PIN AB13 S 0.05906 -0.41339 0 U U
CR 0.05906 -0.41339 0.00985
PIN AB14 S 0.09843 -0.41339 0 U U
CR 0.09843 -0.41339 0.00985
PIN AB15 S 0.1378 -0.41339 0 U U
CR 0.1378 -0.41339 0.00985
PIN AB16 S 0.17717 -0.41339 0 U U
CR 0.17717 -0.41339 0.00985
PIN AB17 S 0.21654 -0.41339 0 U U
CR 0.21654 -0.41339 0.00985
PIN AB18 S 0.25591 -0.41339 0 U U
CR 0.25591 -0.41339 0.00985
PIN AB19 S 0.29528 -0.41339 0 U U
CR 0.29528 -0.41339 0.00985
PIN AB20 S 0.33465 -0.41339 0 U U
CR 0.33465 -0.41339 0.00985
PIN AB21 S 0.37402 -0.41339 0 U U
CR 0.37402 -0.41339 0.00985
PIN AB22 S 0.41339 -0.41339 0 U U
CR 0.41339 -0.41339 0.00985
PIN B1 S -0.41339 0.37402 0 U U
CR -0.41339 0.37402 0.00985
PIN B2 S -0.37402 0.37402 0 U U
CR -0.37402 0.37402 0.00985
PIN B3 S -0.33465 0.37402 0 U U
CR -0.33465 0.37402 0.00985
PIN B4 S -0.29527 0.37402 0 U U
CR -0.29527 0.37402 0.00985
PIN B5 S -0.2559 0.37402 0 U U
CR -0.2559 0.37402 0.00985
PIN B6 S -0.21653 0.37402 0 U U
CR -0.21653 0.37402 0.00985
PIN B7 S -0.17716 0.37402 0 U U
CR -0.17716 0.37402 0.00985
PIN B8 S -0.13779 0.37402 0 U U
CR -0.13779 0.37402 0.00985
PIN B9 S -0.09842 0.37402 0 U U
CR -0.09842 0.37402 0.00985
PIN B10 S -0.05905 0.37402 0 U U
CR -0.05905 0.37402 0.00985
PIN B11 S -0.01968 0.37402 0 U U
CR -0.01968 0.37402 0.00985
PIN B12 S 0.01969 0.37402 0 U U
CR 0.01969 0.37402 0.00985
PIN B13 S 0.05906 0.37402 0 U U
CR 0.05906 0.37402 0.00985
PIN B14 S 0.09843 0.37402 0 U U
CR 0.09843 0.37402 0.00985
PIN B15 S 0.1378 0.37402 0 U U
CR 0.1378 0.37402 0.00985
PIN B16 S 0.17717 0.37402 0 U U
CR 0.17717 0.37402 0.00985
PIN B17 S 0.21654 0.37402 0 U U
CR 0.21654 0.37402 0.00985
PIN B18 S 0.25591 0.37402 0 U U
CR 0.25591 0.37402 0.00985
PIN B19 S 0.29528 0.37402 0 U U
CR 0.29528 0.37402 0.00985
PIN B20 S 0.33465 0.37402 0 U U
CR 0.33465 0.37402 0.00985
PIN B21 S 0.37402 0.37402 0 U U
CR 0.37402 0.37402 0.00985
PIN B22 S 0.41339 0.37402 0 U U
CR 0.41339 0.37402 0.00985
PIN C1 S -0.41339 0.33465 0 U U
CR -0.41339 0.33465 0.00985
PIN C2 S -0.37402 0.33465 0 U U
CR -0.37402 0.33465 0.00985
PIN C3 S -0.33465 0.33465 0 U U
CR -0.33465 0.33465 0.00985
PIN C4 S -0.29527 0.33465 0 U U
CR -0.29527 0.33465 0.00985
PIN C5 S -0.2559 0.33465 0 U U
CR -0.2559 0.33465 0.00985
PIN C6 S -0.21653 0.33465 0 U U
CR -0.21653 0.33465 0.00985
PIN C7 S -0.17716 0.33465 0 U U
CR -0.17716 0.33465 0.00985
PIN C8 S -0.13779 0.33465 0 U U
CR -0.13779 0.33465 0.00985
PIN C9 S -0.09842 0.33465 0 U U
CR -0.09842 0.33465 0.00985
PIN C10 S -0.05905 0.33465 0 U U
CR -0.05905 0.33465 0.00985
PIN C11 S -0.01968 0.33465 0 U U
CR -0.01968 0.33465 0.00985
PIN C12 S 0.01969 0.33465 0 U U
CR 0.01969 0.33465 0.00985
PIN C13 S 0.05906 0.33465 0 U U
CR 0.05906 0.33465 0.00985
PIN C14 S 0.09843 0.33465 0 U U
CR 0.09843 0.33465 0.00985
PIN C15 S 0.1378 0.33465 0 U U
CR 0.1378 0.33465 0.00985
PIN C16 S 0.17717 0.33465 0 U U
CR 0.17717 0.33465 0.00985
PIN C17 S 0.21654 0.33465 0 U U
CR 0.21654 0.33465 0.00985
PIN C18 S 0.25591 0.33465 0 U U
CR 0.25591 0.33465 0.00985
PIN C19 S 0.29528 0.33465 0 U U
CR 0.29528 0.33465 0.00985
PIN C20 S 0.33465 0.33465 0 U U
CR 0.33465 0.33465 0.00985
PIN C21 S 0.37402 0.33465 0 U U
CR 0.37402 0.33465 0.00985
PIN C22 S 0.41339 0.33465 0 U U
CR 0.41339 0.33465 0.00985
PIN D1 S -0.41339 0.29527 0 U U
CR -0.41339 0.29527 0.00985
PIN D2 S -0.37402 0.29527 0 U U
CR -0.37402 0.29527 0.00985
PIN D3 S -0.33465 0.29527 0 U U
CR -0.33465 0.29527 0.00985
PIN D4 S -0.29527 0.29527 0 U U
CR -0.29527 0.29527 0.00985
PIN D5 S -0.2559 0.29527 0 U U
CR -0.2559 0.29527 0.00985
PIN D6 S -0.21653 0.29527 0 U U
CR -0.21653 0.29527 0.00985
PIN D7 S -0.17716 0.29527 0 U U
CR -0.17716 0.29527 0.00985
PIN D8 S -0.13779 0.29527 0 U U
CR -0.13779 0.29527 0.00985
PIN D9 S -0.09842 0.29527 0 U U
CR -0.09842 0.29527 0.00985
PIN D10 S -0.05905 0.29527 0 U U
CR -0.05905 0.29527 0.00985
PIN D11 S -0.01968 0.29527 0 U U
CR -0.01968 0.29527 0.00985
PIN D12 S 0.01969 0.29527 0 U U
CR 0.01969 0.29527 0.00985
PIN D13 S 0.05906 0.29527 0 U U
CR 0.05906 0.29527 0.00985
PIN D14 S 0.09843 0.29527 0 U U
CR 0.09843 0.29527 0.00985
PIN D15 S 0.1378 0.29527 0 U U
CR 0.1378 0.29527 0.00985
PIN D16 S 0.17717 0.29527 0 U U
CR 0.17717 0.29527 0.00985
PIN D17 S 0.21654 0.29527 0 U U
CR 0.21654 0.29527 0.00985
PIN D18 S 0.25591 0.29527 0 U U
CR 0.25591 0.29527 0.00985
PIN D19 S 0.29528 0.29527 0 U U
CR 0.29528 0.29527 0.00985
PIN D20 S 0.33465 0.29527 0 U U
CR 0.33465 0.29527 0.00985
PIN D21 S 0.37402 0.29527 0 U U
CR 0.37402 0.29527 0.00985
PIN D22 S 0.41339 0.29527 0 U U
CR 0.41339 0.29527 0.00985
PIN E1 S -0.41339 0.2559 0 U U
CR -0.41339 0.2559 0.00985
PIN E2 S -0.37402 0.2559 0 U U
CR -0.37402 0.2559 0.00985
PIN E3 S -0.33465 0.2559 0 U U
CR -0.33465 0.2559 0.00985
PIN E4 S -0.29527 0.2559 0 U U
CR -0.29527 0.2559 0.00985
PIN E5 S -0.2559 0.2559 0 U U
CR -0.2559 0.2559 0.00985
PIN E6 S -0.21653 0.2559 0 U U
CR -0.21653 0.2559 0.00985
PIN E7 S -0.17716 0.2559 0 U U
CR -0.17716 0.2559 0.00985
PIN E8 S -0.13779 0.2559 0 U U
CR -0.13779 0.2559 0.00985
PIN E9 S -0.09842 0.2559 0 U U
CR -0.09842 0.2559 0.00985
PIN E10 S -0.05905 0.2559 0 U U
CR -0.05905 0.2559 0.00985
PIN E11 S -0.01968 0.2559 0 U U
CR -0.01968 0.2559 0.00985
PIN E12 S 0.01969 0.2559 0 U U
CR 0.01969 0.2559 0.00985
PIN E13 S 0.05906 0.2559 0 U U
CR 0.05906 0.2559 0.00985
PIN E14 S 0.09843 0.2559 0 U U
CR 0.09843 0.2559 0.00985
PIN E15 S 0.1378 0.2559 0 U U
CR 0.1378 0.2559 0.00985
PIN E16 S 0.17717 0.2559 0 U U
CR 0.17717 0.2559 0.00985
PIN E17 S 0.21654 0.2559 0 U U
CR 0.21654 0.2559 0.00985
PIN E18 S 0.25591 0.2559 0 U U
CR 0.25591 0.2559 0.00985
PIN E19 S 0.29528 0.2559 0 U U
CR 0.29528 0.2559 0.00985
PIN E20 S 0.33465 0.2559 0 U U
CR 0.33465 0.2559 0.00985
PIN E21 S 0.37402 0.2559 0 U U
CR 0.37402 0.2559 0.00985
PIN E22 S 0.41339 0.2559 0 U U
CR 0.41339 0.2559 0.00985
PIN F1 S -0.41339 0.21653 0 U U
CR -0.41339 0.21653 0.00985
PIN F2 S -0.37402 0.21653 0 U U
CR -0.37402 0.21653 0.00985
PIN F3 S -0.33465 0.21653 0 U U
CR -0.33465 0.21653 0.00985
PIN F4 S -0.29527 0.21653 0 U U
CR -0.29527 0.21653 0.00985
PIN F5 S -0.2559 0.21653 0 U U
CR -0.2559 0.21653 0.00985
PIN F6 S -0.21653 0.21653 0 U U
CR -0.21653 0.21653 0.00985
PIN F7 S -0.17716 0.21653 0 U U
CR -0.17716 0.21653 0.00985
PIN F8 S -0.13779 0.21653 0 U U
CR -0.13779 0.21653 0.00985
PIN F9 S -0.09842 0.21653 0 U U
CR -0.09842 0.21653 0.00985
PIN F10 S -0.05905 0.21653 0 U U
CR -0.05905 0.21653 0.00985
PIN F11 S -0.01968 0.21653 0 U U
CR -0.01968 0.21653 0.00985
PIN F12 S 0.01969 0.21653 0 U U
CR 0.01969 0.21653 0.00985
PIN F13 S 0.05906 0.21653 0 U U
CR 0.05906 0.21653 0.00985
PIN F14 S 0.09843 0.21653 0 U U
CR 0.09843 0.21653 0.00985
PIN F15 S 0.1378 0.21653 0 U U
CR 0.1378 0.21653 0.00985
PIN F16 S 0.17717 0.21653 0 U U
CR 0.17717 0.21653 0.00985
PIN F17 S 0.21654 0.21653 0 U U
CR 0.21654 0.21653 0.00985
PIN F18 S 0.25591 0.21653 0 U U
CR 0.25591 0.21653 0.00985
PIN F19 S 0.29528 0.21653 0 U U
CR 0.29528 0.21653 0.00985
PIN F20 S 0.33465 0.21653 0 U U
CR 0.33465 0.21653 0.00985
PIN F21 S 0.37402 0.21653 0 U U
CR 0.37402 0.21653 0.00985
PIN F22 S 0.41339 0.21653 0 U U
CR 0.41339 0.21653 0.00985
PIN G1 S -0.41339 0.17716 0 U U
CR -0.41339 0.17716 0.00985
PIN G2 S -0.37402 0.17716 0 U U
CR -0.37402 0.17716 0.00985
PIN G3 S -0.33465 0.17716 0 U U
CR -0.33465 0.17716 0.00985
PIN G4 S -0.29527 0.17716 0 U U
CR -0.29527 0.17716 0.00985
PIN G5 S -0.2559 0.17716 0 U U
CR -0.2559 0.17716 0.00985
PIN G6 S -0.21653 0.17716 0 U U
CR -0.21653 0.17716 0.00985
PIN G7 S -0.17716 0.17716 0 U U
CR -0.17716 0.17716 0.00985
PIN G8 S -0.13779 0.17716 0 U U
CR -0.13779 0.17716 0.00985
PIN G9 S -0.09842 0.17716 0 U U
CR -0.09842 0.17716 0.00985
PIN G10 S -0.05905 0.17716 0 U U
CR -0.05905 0.17716 0.00985
PIN G11 S -0.01968 0.17716 0 U U
CR -0.01968 0.17716 0.00985
PIN G12 S 0.01969 0.17716 0 U U
CR 0.01969 0.17716 0.00985
PIN G13 S 0.05906 0.17716 0 U U
CR 0.05906 0.17716 0.00985
PIN G14 S 0.09843 0.17716 0 U U
CR 0.09843 0.17716 0.00985
PIN G15 S 0.1378 0.17716 0 U U
CR 0.1378 0.17716 0.00985
PIN G16 S 0.17717 0.17716 0 U U
CR 0.17717 0.17716 0.00985
PIN G17 S 0.21654 0.17716 0 U U
CR 0.21654 0.17716 0.00985
PIN G18 S 0.25591 0.17716 0 U U
CR 0.25591 0.17716 0.00985
PIN G19 S 0.29528 0.17716 0 U U
CR 0.29528 0.17716 0.00985
PIN G20 S 0.33465 0.17716 0 U U
CR 0.33465 0.17716 0.00985
PIN G21 S 0.37402 0.17716 0 U U
CR 0.37402 0.17716 0.00985
PIN G22 S 0.41339 0.17716 0 U U
CR 0.41339 0.17716 0.00985
PIN H1 S -0.41339 0.13779 0 U U
CR -0.41339 0.13779 0.00985
PIN H2 S -0.37402 0.13779 0 U U
CR -0.37402 0.13779 0.00985
PIN H3 S -0.33465 0.13779 0 U U
CR -0.33465 0.13779 0.00985
PIN H4 S -0.29527 0.13779 0 U U
CR -0.29527 0.13779 0.00985
PIN H5 S -0.2559 0.13779 0 U U
CR -0.2559 0.13779 0.00985
PIN H6 S -0.21653 0.13779 0 U U
CR -0.21653 0.13779 0.00985
PIN H7 S -0.17716 0.13779 0 U U
CR -0.17716 0.13779 0.00985
PIN H8 S -0.13779 0.13779 0 U U
CR -0.13779 0.13779 0.00985
PIN H9 S -0.09842 0.13779 0 U U
CR -0.09842 0.13779 0.00985
PIN H10 S -0.05905 0.13779 0 U U
CR -0.05905 0.13779 0.00985
PIN H11 S -0.01968 0.13779 0 U U
CR -0.01968 0.13779 0.00985
PIN H12 S 0.01969 0.13779 0 U U
CR 0.01969 0.13779 0.00985
PIN H13 S 0.05906 0.13779 0 U U
CR 0.05906 0.13779 0.00985
PIN H14 S 0.09843 0.13779 0 U U
CR 0.09843 0.13779 0.00985
PIN H15 S 0.1378 0.13779 0 U U
CR 0.1378 0.13779 0.00985
PIN H16 S 0.17717 0.13779 0 U U
CR 0.17717 0.13779 0.00985
PIN H17 S 0.21654 0.13779 0 U U
CR 0.21654 0.13779 0.00985
PIN H18 S 0.25591 0.13779 0 U U
CR 0.25591 0.13779 0.00985
PIN H19 S 0.29528 0.13779 0 U U
CR 0.29528 0.13779 0.00985
PIN H20 S 0.33465 0.13779 0 U U
CR 0.33465 0.13779 0.00985
PIN H21 S 0.37402 0.13779 0 U U
CR 0.37402 0.13779 0.00985
PIN H22 S 0.41339 0.13779 0 U U
CR 0.41339 0.13779 0.00985
PIN J1 S -0.41339 0.09842 0 U U
CR -0.41339 0.09842 0.00985
PIN J2 S -0.37402 0.09842 0 U U
CR -0.37402 0.09842 0.00985
PIN J3 S -0.33465 0.09842 0 U U
CR -0.33465 0.09842 0.00985
PIN J4 S -0.29527 0.09842 0 U U
CR -0.29527 0.09842 0.00985
PIN J5 S -0.2559 0.09842 0 U U
CR -0.2559 0.09842 0.00985
PIN J6 S -0.21653 0.09842 0 U U
CR -0.21653 0.09842 0.00985
PIN J7 S -0.17716 0.09842 0 U U
CR -0.17716 0.09842 0.00985
PIN J8 S -0.13779 0.09842 0 U U
CR -0.13779 0.09842 0.00985
PIN J9 S -0.09842 0.09842 0 U U
CR -0.09842 0.09842 0.00985
PIN J10 S -0.05905 0.09842 0 U U
CR -0.05905 0.09842 0.00985
PIN J11 S -0.01968 0.09842 0 U U
CR -0.01968 0.09842 0.00985
PIN J12 S 0.01969 0.09842 0 U U
CR 0.01969 0.09842 0.00985
PIN J13 S 0.05906 0.09842 0 U U
CR 0.05906 0.09842 0.00985
PIN J14 S 0.09843 0.09842 0 U U
CR 0.09843 0.09842 0.00985
PIN J15 S 0.1378 0.09842 0 U U
CR 0.1378 0.09842 0.00985
PIN J16 S 0.17717 0.09842 0 U U
CR 0.17717 0.09842 0.00985
PIN J17 S 0.21654 0.09842 0 U U
CR 0.21654 0.09842 0.00985
PIN J18 S 0.25591 0.09842 0 U U
CR 0.25591 0.09842 0.00985
PIN J19 S 0.29528 0.09842 0 U U
CR 0.29528 0.09842 0.00985
PIN J20 S 0.33465 0.09842 0 U U
CR 0.33465 0.09842 0.00985
PIN J21 S 0.37402 0.09842 0 U U
CR 0.37402 0.09842 0.00985
PIN J22 S 0.41339 0.09842 0 U U
CR 0.41339 0.09842 0.00985
PIN K1 S -0.41339 0.05905 0 U U
CR -0.41339 0.05905 0.00985
PIN K2 S -0.37402 0.05905 0 U U
CR -0.37402 0.05905 0.00985
PIN K3 S -0.33465 0.05905 0 U U
CR -0.33465 0.05905 0.00985
PIN K4 S -0.29527 0.05905 0 U U
CR -0.29527 0.05905 0.00985
PIN K5 S -0.2559 0.05905 0 U U
CR -0.2559 0.05905 0.00985
PIN K6 S -0.21653 0.05905 0 U U
CR -0.21653 0.05905 0.00985
PIN K7 S -0.17716 0.05905 0 U U
CR -0.17716 0.05905 0.00985
PIN K8 S -0.13779 0.05905 0 U U
CR -0.13779 0.05905 0.00985
PIN K9 S -0.09842 0.05905 0 U U
CR -0.09842 0.05905 0.00985
PIN K10 S -0.05905 0.05905 0 U U
CR -0.05905 0.05905 0.00985
PIN K11 S -0.01968 0.05905 0 U U
CR -0.01968 0.05905 0.00985
PIN K12 S 0.01969 0.05905 0 U U
CR 0.01969 0.05905 0.00985
PIN K13 S 0.05906 0.05905 0 U U
CR 0.05906 0.05905 0.00985
PIN K14 S 0.09843 0.05905 0 U U
CR 0.09843 0.05905 0.00985
PIN K15 S 0.1378 0.05905 0 U U
CR 0.1378 0.05905 0.00985
PIN K16 S 0.17717 0.05905 0 U U
CR 0.17717 0.05905 0.00985
PIN K17 S 0.21654 0.05905 0 U U
CR 0.21654 0.05905 0.00985
PIN K18 S 0.25591 0.05905 0 U U
CR 0.25591 0.05905 0.00985
PIN K19 S 0.29528 0.05905 0 U U
CR 0.29528 0.05905 0.00985
PIN K20 S 0.33465 0.05905 0 U U
CR 0.33465 0.05905 0.00985
PIN K21 S 0.37402 0.05905 0 U U
CR 0.37402 0.05905 0.00985
PIN K22 S 0.41339 0.05905 0 U U
CR 0.41339 0.05905 0.00985
PIN L1 S -0.41339 0.01968 0 U U
CR -0.41339 0.01968 0.00985
PIN L2 S -0.37402 0.01968 0 U U
CR -0.37402 0.01968 0.00985
PIN L3 S -0.33465 0.01968 0 U U
CR -0.33465 0.01968 0.00985
PIN L4 S -0.29527 0.01968 0 U U
CR -0.29527 0.01968 0.00985
PIN L5 S -0.2559 0.01968 0 U U
CR -0.2559 0.01968 0.00985
PIN L6 S -0.21653 0.01968 0 U U
CR -0.21653 0.01968 0.00985
PIN L7 S -0.17716 0.01968 0 U U
CR -0.17716 0.01968 0.00985
PIN L8 S -0.13779 0.01968 0 U U
CR -0.13779 0.01968 0.00985
PIN L9 S -0.09842 0.01968 0 U U
CR -0.09842 0.01968 0.00985
PIN L10 S -0.05905 0.01968 0 U U
CR -0.05905 0.01968 0.00985
PIN L11 S -0.01968 0.01968 0 U U
CR -0.01968 0.01968 0.00985
PIN L12 S 0.01969 0.01968 0 U U
CR 0.01969 0.01968 0.00985
PIN L13 S 0.05906 0.01968 0 U U
CR 0.05906 0.01968 0.00985
PIN L14 S 0.09843 0.01968 0 U U
CR 0.09843 0.01968 0.00985
PIN L15 S 0.1378 0.01968 0 U U
CR 0.1378 0.01968 0.00985
PIN L16 S 0.17717 0.01968 0 U U
CR 0.17717 0.01968 0.00985
PIN L17 S 0.21654 0.01968 0 U U
CR 0.21654 0.01968 0.00985
PIN L18 S 0.25591 0.01968 0 U U
CR 0.25591 0.01968 0.00985
PIN L19 S 0.29528 0.01968 0 U U
CR 0.29528 0.01968 0.00985
PIN L20 S 0.33465 0.01968 0 U U
CR 0.33465 0.01968 0.00985
PIN L21 S 0.37402 0.01968 0 U U
CR 0.37402 0.01968 0.00985
PIN L22 S 0.41339 0.01968 0 U U
CR 0.41339 0.01968 0.00985
PIN M1 S -0.41339 -0.01969 0 U U
CR -0.41339 -0.01969 0.00985
PIN M2 S -0.37402 -0.01969 0 U U
CR -0.37402 -0.01969 0.00985
PIN M3 S -0.33465 -0.01969 0 U U
CR -0.33465 -0.01969 0.00985
PIN M4 S -0.29527 -0.01969 0 U U
CR -0.29527 -0.01969 0.00985
PIN M5 S -0.2559 -0.01969 0 U U
CR -0.2559 -0.01969 0.00985
PIN M6 S -0.21653 -0.01969 0 U U
CR -0.21653 -0.01969 0.00985
PIN M7 S -0.17716 -0.01969 0 U U
CR -0.17716 -0.01969 0.00985
PIN M8 S -0.13779 -0.01969 0 U U
CR -0.13779 -0.01969 0.00985
PIN M9 S -0.09842 -0.01969 0 U U
CR -0.09842 -0.01969 0.00985
PIN M10 S -0.05905 -0.01969 0 U U
CR -0.05905 -0.01969 0.00985
PIN M11 S -0.01968 -0.01969 0 U U
CR -0.01968 -0.01969 0.00985
PIN M12 S 0.01969 -0.01969 0 U U
CR 0.01969 -0.01969 0.00985
PIN M13 S 0.05906 -0.01969 0 U U
CR 0.05906 -0.01969 0.00985
PIN M14 S 0.09843 -0.01969 0 U U
CR 0.09843 -0.01969 0.00985
PIN M15 S 0.1378 -0.01969 0 U U
CR 0.1378 -0.01969 0.00985
PIN M16 S 0.17717 -0.01969 0 U U
CR 0.17717 -0.01969 0.00985
PIN M17 S 0.21654 -0.01969 0 U U
CR 0.21654 -0.01969 0.00985
PIN M18 S 0.25591 -0.01969 0 U U
CR 0.25591 -0.01969 0.00985
PIN M19 S 0.29528 -0.01969 0 U U
CR 0.29528 -0.01969 0.00985
PIN M20 S 0.33465 -0.01969 0 U U
CR 0.33465 -0.01969 0.00985
PIN M21 S 0.37402 -0.01969 0 U U
CR 0.37402 -0.01969 0.00985
PIN M22 S 0.41339 -0.01969 0 U U
CR 0.41339 -0.01969 0.00985
PIN N1 S -0.41339 -0.05906 0 U U
CR -0.41339 -0.05906 0.00985
PIN N2 S -0.37402 -0.05906 0 U U
CR -0.37402 -0.05906 0.00985
PIN N3 S -0.33465 -0.05906 0 U U
CR -0.33465 -0.05906 0.00985
PIN N4 S -0.29527 -0.05906 0 U U
CR -0.29527 -0.05906 0.00985
PIN N5 S -0.2559 -0.05906 0 U U
CR -0.2559 -0.05906 0.00985
PIN N6 S -0.21653 -0.05906 0 U U
CR -0.21653 -0.05906 0.00985
PIN N7 S -0.17716 -0.05906 0 U U
CR -0.17716 -0.05906 0.00985
PIN N8 S -0.13779 -0.05906 0 U U
CR -0.13779 -0.05906 0.00985
PIN N9 S -0.09842 -0.05906 0 U U
CR -0.09842 -0.05906 0.00985
PIN N10 S -0.05905 -0.05906 0 U U
CR -0.05905 -0.05906 0.00985
PIN N11 S -0.01968 -0.05906 0 U U
CR -0.01968 -0.05906 0.00985
PIN N12 S 0.01969 -0.05906 0 U U
CR 0.01969 -0.05906 0.00985
PIN N13 S 0.05906 -0.05906 0 U U
CR 0.05906 -0.05906 0.00985
PIN N14 S 0.09843 -0.05906 0 U U
CR 0.09843 -0.05906 0.00985
PIN N15 S 0.1378 -0.05906 0 U U
CR 0.1378 -0.05906 0.00985
PIN N16 S 0.17717 -0.05906 0 U U
CR 0.17717 -0.05906 0.00985
PIN N17 S 0.21654 -0.05906 0 U U
CR 0.21654 -0.05906 0.00985
PIN N18 S 0.25591 -0.05906 0 U U
CR 0.25591 -0.05906 0.00985
PIN N19 S 0.29528 -0.05906 0 U U
CR 0.29528 -0.05906 0.00985
PIN N20 S 0.33465 -0.05906 0 U U
CR 0.33465 -0.05906 0.00985
PIN N21 S 0.37402 -0.05906 0 U U
CR 0.37402 -0.05906 0.00985
PIN N22 S 0.41339 -0.05906 0 U U
CR 0.41339 -0.05906 0.00985
PIN P1 S -0.41339 -0.09843 0 U U
CR -0.41339 -0.09843 0.00985
PIN P2 S -0.37402 -0.09843 0 U U
CR -0.37402 -0.09843 0.00985
PIN P3 S -0.33465 -0.09843 0 U U
CR -0.33465 -0.09843 0.00985
PIN P4 S -0.29527 -0.09843 0 U U
CR -0.29527 -0.09843 0.00985
PIN P5 S -0.2559 -0.09843 0 U U
CR -0.2559 -0.09843 0.00985
PIN P6 S -0.21653 -0.09843 0 U U
CR -0.21653 -0.09843 0.00985
PIN P7 S -0.17716 -0.09843 0 U U
CR -0.17716 -0.09843 0.00985
PIN P8 S -0.13779 -0.09843 0 U U
CR -0.13779 -0.09843 0.00985
PIN P9 S -0.09842 -0.09843 0 U U
CR -0.09842 -0.09843 0.00985
PIN P10 S -0.05905 -0.09843 0 U U
CR -0.05905 -0.09843 0.00985
PIN P11 S -0.01968 -0.09843 0 U U
CR -0.01968 -0.09843 0.00985
PIN P12 S 0.01969 -0.09843 0 U U
CR 0.01969 -0.09843 0.00985
PIN P13 S 0.05906 -0.09843 0 U U
CR 0.05906 -0.09843 0.00985
PIN P14 S 0.09843 -0.09843 0 U U
CR 0.09843 -0.09843 0.00985
PIN P15 S 0.1378 -0.09843 0 U U
CR 0.1378 -0.09843 0.00985
PIN P16 S 0.17717 -0.09843 0 U U
CR 0.17717 -0.09843 0.00985
PIN P17 S 0.21654 -0.09843 0 U U
CR 0.21654 -0.09843 0.00985
PIN P18 S 0.25591 -0.09843 0 U U
CR 0.25591 -0.09843 0.00985
PIN P19 S 0.29528 -0.09843 0 U U
CR 0.29528 -0.09843 0.00985
PIN P20 S 0.33465 -0.09843 0 U U
CR 0.33465 -0.09843 0.00985
PIN P21 S 0.37402 -0.09843 0 U U
CR 0.37402 -0.09843 0.00985
PIN P22 S 0.41339 -0.09843 0 U U
CR 0.41339 -0.09843 0.00985
PIN R1 S -0.41339 -0.1378 0 U U
CR -0.41339 -0.1378 0.00985
PIN R2 S -0.37402 -0.1378 0 U U
CR -0.37402 -0.1378 0.00985
PIN R3 S -0.33465 -0.1378 0 U U
CR -0.33465 -0.1378 0.00985
PIN R4 S -0.29527 -0.1378 0 U U
CR -0.29527 -0.1378 0.00985
PIN R5 S -0.2559 -0.1378 0 U U
CR -0.2559 -0.1378 0.00985
PIN R6 S -0.21653 -0.1378 0 U U
CR -0.21653 -0.1378 0.00985
PIN R7 S -0.17716 -0.1378 0 U U
CR -0.17716 -0.1378 0.00985
PIN R8 S -0.13779 -0.1378 0 U U
CR -0.13779 -0.1378 0.00985
PIN R9 S -0.09842 -0.1378 0 U U
CR -0.09842 -0.1378 0.00985
PIN R10 S -0.05905 -0.1378 0 U U
CR -0.05905 -0.1378 0.00985
PIN R11 S -0.01968 -0.1378 0 U U
CR -0.01968 -0.1378 0.00985
PIN R12 S 0.01969 -0.1378 0 U U
CR 0.01969 -0.1378 0.00985
PIN R13 S 0.05906 -0.1378 0 U U
CR 0.05906 -0.1378 0.00985
PIN R14 S 0.09843 -0.1378 0 U U
CR 0.09843 -0.1378 0.00985
PIN R15 S 0.1378 -0.1378 0 U U
CR 0.1378 -0.1378 0.00985
PIN R16 S 0.17717 -0.1378 0 U U
CR 0.17717 -0.1378 0.00985
PIN R17 S 0.21654 -0.1378 0 U U
CR 0.21654 -0.1378 0.00985
PIN R18 S 0.25591 -0.1378 0 U U
CR 0.25591 -0.1378 0.00985
PIN R19 S 0.29528 -0.1378 0 U U
CR 0.29528 -0.1378 0.00985
PIN R20 S 0.33465 -0.1378 0 U U
CR 0.33465 -0.1378 0.00985
PIN R21 S 0.37402 -0.1378 0 U U
CR 0.37402 -0.1378 0.00985
PIN R22 S 0.41339 -0.1378 0 U U
CR 0.41339 -0.1378 0.00985
PIN T1 S -0.41339 -0.17717 0 U U
CR -0.41339 -0.17717 0.00985
PIN T2 S -0.37402 -0.17717 0 U U
CR -0.37402 -0.17717 0.00985
PIN T3 S -0.33465 -0.17717 0 U U
CR -0.33465 -0.17717 0.00985
PIN T4 S -0.29527 -0.17717 0 U U
CR -0.29527 -0.17717 0.00985
PIN T5 S -0.2559 -0.17717 0 U U
CR -0.2559 -0.17717 0.00985
PIN T6 S -0.21653 -0.17717 0 U U
CR -0.21653 -0.17717 0.00985
PIN T7 S -0.17716 -0.17717 0 U U
CR -0.17716 -0.17717 0.00985
PIN T8 S -0.13779 -0.17717 0 U U
CR -0.13779 -0.17717 0.00985
PIN T9 S -0.09842 -0.17717 0 U U
CR -0.09842 -0.17717 0.00985
PIN T10 S -0.05905 -0.17717 0 U U
CR -0.05905 -0.17717 0.00985
PIN T11 S -0.01968 -0.17717 0 U U
CR -0.01968 -0.17717 0.00985
PIN T12 S 0.01969 -0.17717 0 U U
CR 0.01969 -0.17717 0.00985
PIN T13 S 0.05906 -0.17717 0 U U
CR 0.05906 -0.17717 0.00985
PIN T14 S 0.09843 -0.17717 0 U U
CR 0.09843 -0.17717 0.00985
PIN T15 S 0.1378 -0.17717 0 U U
CR 0.1378 -0.17717 0.00985
PIN T16 S 0.17717 -0.17717 0 U U
CR 0.17717 -0.17717 0.00985
PIN T17 S 0.21654 -0.17717 0 U U
CR 0.21654 -0.17717 0.00985
PIN T18 S 0.25591 -0.17717 0 U U
CR 0.25591 -0.17717 0.00985
PIN T19 S 0.29528 -0.17717 0 U U
CR 0.29528 -0.17717 0.00985
PIN T20 S 0.33465 -0.17717 0 U U
CR 0.33465 -0.17717 0.00985
PIN T21 S 0.37402 -0.17717 0 U U
CR 0.37402 -0.17717 0.00985
PIN T22 S 0.41339 -0.17717 0 U U
CR 0.41339 -0.17717 0.00985
PIN U1 S -0.41339 -0.21654 0 U U
CR -0.41339 -0.21654 0.00985
PIN U2 S -0.37402 -0.21654 0 U U
CR -0.37402 -0.21654 0.00985
PIN U3 S -0.33465 -0.21654 0 U U
CR -0.33465 -0.21654 0.00985
PIN U4 S -0.29527 -0.21654 0 U U
CR -0.29527 -0.21654 0.00985
PIN U5 S -0.2559 -0.21654 0 U U
CR -0.2559 -0.21654 0.00985
PIN U6 S -0.21653 -0.21654 0 U U
CR -0.21653 -0.21654 0.00985
PIN U7 S -0.17716 -0.21654 0 U U
CR -0.17716 -0.21654 0.00985
PIN U8 S -0.13779 -0.21654 0 U U
CR -0.13779 -0.21654 0.00985
PIN U9 S -0.09842 -0.21654 0 U U
CR -0.09842 -0.21654 0.00985
PIN U10 S -0.05905 -0.21654 0 U U
CR -0.05905 -0.21654 0.00985
PIN U11 S -0.01968 -0.21654 0 U U
CR -0.01968 -0.21654 0.00985
PIN U12 S 0.01969 -0.21654 0 U U
CR 0.01969 -0.21654 0.00985
PIN U13 S 0.05906 -0.21654 0 U U
CR 0.05906 -0.21654 0.00985
PIN U14 S 0.09843 -0.21654 0 U U
CR 0.09843 -0.21654 0.00985
PIN U15 S 0.1378 -0.21654 0 U U
CR 0.1378 -0.21654 0.00985
PIN U16 S 0.17717 -0.21654 0 U U
CR 0.17717 -0.21654 0.00985
PIN U17 S 0.21654 -0.21654 0 U U
CR 0.21654 -0.21654 0.00985
PIN U18 S 0.25591 -0.21654 0 U U
CR 0.25591 -0.21654 0.00985
PIN U19 S 0.29528 -0.21654 0 U U
CR 0.29528 -0.21654 0.00985
PIN U20 S 0.33465 -0.21654 0 U U
CR 0.33465 -0.21654 0.00985
PIN U21 S 0.37402 -0.21654 0 U U
CR 0.37402 -0.21654 0.00985
PIN U22 S 0.41339 -0.21654 0 U U
CR 0.41339 -0.21654 0.00985
PIN V1 S -0.41339 -0.25591 0 U U
CR -0.41339 -0.25591 0.00985
PIN V2 S -0.37402 -0.25591 0 U U
CR -0.37402 -0.25591 0.00985
PIN V3 S -0.33465 -0.25591 0 U U
CR -0.33465 -0.25591 0.00985
PIN V4 S -0.29527 -0.25591 0 U U
CR -0.29527 -0.25591 0.00985
PIN V5 S -0.2559 -0.25591 0 U U
CR -0.2559 -0.25591 0.00985
PIN V6 S -0.21653 -0.25591 0 U U
CR -0.21653 -0.25591 0.00985
PIN V7 S -0.17716 -0.25591 0 U U
CR -0.17716 -0.25591 0.00985
PIN V8 S -0.13779 -0.25591 0 U U
CR -0.13779 -0.25591 0.00985
PIN V9 S -0.09842 -0.25591 0 U U
CR -0.09842 -0.25591 0.00985
PIN V10 S -0.05905 -0.25591 0 U U
CR -0.05905 -0.25591 0.00985
PIN V11 S -0.01968 -0.25591 0 U U
CR -0.01968 -0.25591 0.00985
PIN V12 S 0.01969 -0.25591 0 U U
CR 0.01969 -0.25591 0.00985
PIN V13 S 0.05906 -0.25591 0 U U
CR 0.05906 -0.25591 0.00985
PIN V14 S 0.09843 -0.25591 0 U U
CR 0.09843 -0.25591 0.00985
PIN V15 S 0.1378 -0.25591 0 U U
CR 0.1378 -0.25591 0.00985
PIN V16 S 0.17717 -0.25591 0 U U
CR 0.17717 -0.25591 0.00985
PIN V17 S 0.21654 -0.25591 0 U U
CR 0.21654 -0.25591 0.00985
PIN V18 S 0.25591 -0.25591 0 U U
CR 0.25591 -0.25591 0.00985
PIN V19 S 0.29528 -0.25591 0 U U
CR 0.29528 -0.25591 0.00985
PIN V20 S 0.33465 -0.25591 0 U U
CR 0.33465 -0.25591 0.00985
PIN V21 S 0.37402 -0.25591 0 U U
CR 0.37402 -0.25591 0.00985
PIN V22 S 0.41339 -0.25591 0 U U
CR 0.41339 -0.25591 0.00985
PIN W1 S -0.41339 -0.29528 0 U U
CR -0.41339 -0.29528 0.00985
PIN W2 S -0.37402 -0.29528 0 U U
CR -0.37402 -0.29528 0.00985
PIN W3 S -0.33465 -0.29528 0 U U
CR -0.33465 -0.29528 0.00985
PIN W4 S -0.29527 -0.29528 0 U U
CR -0.29527 -0.29528 0.00985
PIN W5 S -0.2559 -0.29528 0 U U
CR -0.2559 -0.29528 0.00985
PIN W6 S -0.21653 -0.29528 0 U U
CR -0.21653 -0.29528 0.00985
PIN W7 S -0.17716 -0.29528 0 U U
CR -0.17716 -0.29528 0.00985
PIN W8 S -0.13779 -0.29528 0 U U
CR -0.13779 -0.29528 0.00985
PIN W9 S -0.09842 -0.29528 0 U U
CR -0.09842 -0.29528 0.00985
PIN W10 S -0.05905 -0.29528 0 U U
CR -0.05905 -0.29528 0.00985
PIN W11 S -0.01968 -0.29528 0 U U
CR -0.01968 -0.29528 0.00985
PIN W12 S 0.01969 -0.29528 0 U U
CR 0.01969 -0.29528 0.00985
PIN W13 S 0.05906 -0.29528 0 U U
CR 0.05906 -0.29528 0.00985
PIN W14 S 0.09843 -0.29528 0 U U
CR 0.09843 -0.29528 0.00985
PIN W15 S 0.1378 -0.29528 0 U U
CR 0.1378 -0.29528 0.00985
PIN W16 S 0.17717 -0.29528 0 U U
CR 0.17717 -0.29528 0.00985
PIN W17 S 0.21654 -0.29528 0 U U
CR 0.21654 -0.29528 0.00985
PIN W18 S 0.25591 -0.29528 0 U U
CR 0.25591 -0.29528 0.00985
PIN W19 S 0.29528 -0.29528 0 U U
CR 0.29528 -0.29528 0.00985
PIN W20 S 0.33465 -0.29528 0 U U
CR 0.33465 -0.29528 0.00985
PIN W21 S 0.37402 -0.29528 0 U U
CR 0.37402 -0.29528 0.00985
PIN W22 S 0.41339 -0.29528 0 U U
CR 0.41339 -0.29528 0.00985
PIN Y1 S -0.41339 -0.33465 0 U U
CR -0.41339 -0.33465 0.00985
PIN Y2 S -0.37402 -0.33465 0 U U
CR -0.37402 -0.33465 0.00985
PIN Y3 S -0.33465 -0.33465 0 U U
CR -0.33465 -0.33465 0.00985
PIN Y4 S -0.29527 -0.33465 0 U U
CR -0.29527 -0.33465 0.00985
PIN Y5 S -0.2559 -0.33465 0 U U
CR -0.2559 -0.33465 0.00985
PIN Y6 S -0.21653 -0.33465 0 U U
CR -0.21653 -0.33465 0.00985
PIN Y7 S -0.17716 -0.33465 0 U U
CR -0.17716 -0.33465 0.00985
PIN Y8 S -0.13779 -0.33465 0 U U
CR -0.13779 -0.33465 0.00985
PIN Y9 S -0.09842 -0.33465 0 U U
CR -0.09842 -0.33465 0.00985
PIN Y10 S -0.05905 -0.33465 0 U U
CR -0.05905 -0.33465 0.00985
PIN Y11 S -0.01968 -0.33465 0 U U
CR -0.01968 -0.33465 0.00985
PIN Y12 S 0.01969 -0.33465 0 U U
CR 0.01969 -0.33465 0.00985
PIN Y13 S 0.05906 -0.33465 0 U U
CR 0.05906 -0.33465 0.00985
PIN Y14 S 0.09843 -0.33465 0 U U
CR 0.09843 -0.33465 0.00985
PIN Y15 S 0.1378 -0.33465 0 U U
CR 0.1378 -0.33465 0.00985
PIN Y16 S 0.17717 -0.33465 0 U U
CR 0.17717 -0.33465 0.00985
PIN Y17 S 0.21654 -0.33465 0 U U
CR 0.21654 -0.33465 0.00985
PIN Y18 S 0.25591 -0.33465 0 U U
CR 0.25591 -0.33465 0.00985
PIN Y19 S 0.29528 -0.33465 0 U U
CR 0.29528 -0.33465 0.00985
PIN Y20 S 0.33465 -0.33465 0 U U
CR 0.33465 -0.33465 0.00985
PIN Y21 S 0.37402 -0.33465 0 U U
CR 0.37402 -0.33465 0.00985
PIN Y22 S 0.41339 -0.33465 0 U U
CR 0.41339 -0.33465 0.00985
#
# PKG 39
PKG SMC_1210R_H110 0.105 -0.075 -0.052 0.075 0.052
RC -0.063 -0.049 0.126 0.098
PIN 1 S -0.0525 0 0 U U
RC -0.075 -0.052 0.045 0.104
PIN 2 S 0.0525 0 0 U U
RC 0.03 -0.052 0.045 0.104
#
# PKG 40
PKG SMC_0402R_H026 0.042 -0.035 -0.012 0.035 0.012
RC -0.02 -0.012 0.04 0.024
PIN 1 S -0.021 0 0 U U
RC -0.035 -0.012 0.028 0.024
PIN 2 S 0.021 0 0 U U
RC 0.007 -0.012 0.028 0.024
#
# PKG 41
PKG 0201_SOLDER_PREFORM_4MIL 0.009 -0.007 -0.012 0.007 0.012
RC -0.0055 -0.0095 0.011 0.019
PIN 1 S -0.0045 0 0 U U
RC -0.007 -0.012 0.005 0.024
PIN 2 S 0.0045 0 0 U U
RC 0.002 -0.012 0.005 0.024
#
# PKG 42
PKG SMC_0603R_H022 0.054 -0.042 -0.018 0.042 0.018
RC -0.032 -0.018 0.064 0.036
PIN 1 S -0.027 0 0 U U
RC -0.042 -0.017 0.03 0.034
PIN 2 S 0.027 0 0 U U
RC 0.012 -0.017 0.03 0.034
#
# PKG 43
PKG SMC_CR_270X232_V1 0.25984 -0.17692 -0.12244 0.17692 0.12244
RC -0.13996 -0.12244 0.2799201 0.2448799
PIN A S -0.12992 0 0 U U
RC -0.17692 -0.065 0.094 0.13
PIN C S 0.12992 0 0 U U
RC 0.08292 -0.065 0.094 0.13
#
# PKG 44
PKG SMC_CR_170X143_V2 0.1740201 -0.12951 -0.07776 0.12951 0.07776
RC -0.09055 -0.07776 0.1811 0.1555201
PIN A S -0.08701 0 0 U U
RC -0.12951 -0.054 0.085 0.108
PIN C S 0.08701 0 0 U U
RC 0.04451 -0.054 0.085 0.108
#
# PKG 45
PKG SOT23_5 0.0374 -0.08 -0.05709 0.08 0.05709
CT
OB 0.05906003937 -0.02756003937 I
OS 0.05906003937 -0.04723996063
OS 0.0315 -0.04723996063
OS 0.0315 -0.05708996063
OS -0.0315 -0.05708996063
OS -0.0315 -0.04723996063
OS -0.05906003937 -0.04723996063
OS -0.05906003937 -0.02756003937
OS -0.0315 -0.02756003937
OS -0.0315 -0.00983996063
OS -0.05906003937 -0.00983996063
OS -0.05906003937 0.00983996063
OS -0.0315 0.00983996063
OS -0.0315 0.02756003937
OS -0.05906003937 0.02756003937
OS -0.05906003937 0.04723996063
OS -0.0315 0.04723996063
OS -0.0315 0.05708996063
OS 0.0315 0.05708996063
OS 0.0315 0.04723996063
OS 0.05906003937 0.04723996063
OS 0.05906003937 0.02756003937
OS 0.0315 0.02756003937
OS 0.0315 -0.02756003937
OS 0.05906003937 -0.02756003937
OE
CE
PIN 1 S -0.0565 0.0374 0 U U
RC -0.08 0.0274 0.047 0.02
PIN 2 S -0.0565 0 0 U U
RC -0.08 -0.01 0.047 0.02
PIN 3 S -0.0565 -0.0374 0 U U
RC -0.08 -0.0474 0.047 0.02
PIN 4 S 0.0565 -0.0374 0 U U
RC 0.033 -0.0474 0.047 0.02
PIN 5 S 0.0565 0.0374 0 U U
RC 0.033 0.0274 0.047 0.02
#
# PKG 46
PKG QFN12_071_P0157 0.0157401 -0.0565599 -0.0565599 0.05656 0.05656
RC -0.0374 -0.0374 0.0748 0.0748
PIN 1 S -0.0300599 0.0078701 0 U U
RC -0.0565599 0.0038701 0.053 0.008
PIN 2 S -0.0300599 -0.0078799 0 U U
RC -0.0565599 -0.0118799 0.053 0.008
PIN 3 S -0.02362 -0.0380599 0 U U
RC -0.02762 -0.0565599 0.008 0.037
PIN 4 S -0.00787 -0.0380599 0 U U
RC -0.01187 -0.0565599 0.008 0.037
PIN 5 S 0.0078701 -0.0380599 0 U U
RC 0.0038701 -0.0565599 0.008 0.037
PIN 6 S 0.0236201 -0.0380599 0 U U
RC 0.0196201 -0.0565599 0.008 0.037
PIN 7 S 0.03006 -0.0078799 0 U U
RC 0.00356 -0.0118799 0.053 0.008
PIN 8 S 0.03006 0.0078701 0 U U
RC 0.00356 0.0038701 0.053 0.008
PIN 9 S 0.0236201 0.03806 0 U U
RC 0.0196201 0.01956 0.008 0.037
PIN 10 S 0.0078701 0.03806 0 U U
RC 0.0038701 0.01956 0.008 0.037
PIN 11 S -0.00787 0.03806 0 U U
RC -0.01187 0.01956 0.008 0.037
PIN 12 S -0.02362 0.03806 0 U U
RC -0.02762 0.01956 0.008 0.037
#
# PKG 47
PKG QFN18_138_P0197_V1 0.0196799 -0.07696 -0.07662 0.07696 0.07696
RC -0.07087 -0.07087 0.14174 0.14174
PIN 1 S -0.06496 0.0374 0 U U
RC -0.07696 0.0314 0.024 0.012
PIN 2 S -0.05413 0.01378 0 U U
RC -0.07663 0.00578 0.045 0.016
PIN 3 S -0.05413 -0.01181 0 U U
RC -0.07663 -0.01781 0.045 0.012
PIN 4 S -0.05413 -0.03346 0 U U
RC -0.07663 -0.03946 0.045 0.012
PIN 5 S -0.05413 -0.05512 0 U U
RC -0.07663 -0.06112 0.045 0.012
PIN 6 S -0.0128 -0.02362 0 U U
RC -0.0168 -0.07662 0.008 0.106
PIN 7 S 0.0128 -0.02362 0 U U
RC 0.0088 -0.07662 0.008 0.106
PIN 8 S 0.05413 -0.05512 0 U U
RC 0.03163 -0.06112 0.045 0.012
PIN 9 S 0.05413 -0.03346 0 U U
RC 0.03163 -0.03946 0.045 0.012
PIN 10 S 0.05413 -0.01181 0 U U
RC 0.03163 -0.01781 0.045 0.012
PIN 11 S 0.05413 0.01378 0 U U
RC 0.03163 0.00578 0.045 0.016
PIN 12 S 0.06496 0.0374 0 U U
RC 0.05296 0.0314 0.024 0.012
PIN 13 S 0.05413 0.06496 0 U U
RC 0.04413 0.05296 0.02 0.024
PIN 14 S 0.02953 0.06496 0 U U
RC 0.02453 0.05296 0.01 0.024
PIN 15 S 0.00984 0.06496 0 U U
RC 0.00484 0.05296 0.01 0.024
PIN 16 S -0.00984 0.06496 0 U U
RC -0.01484 0.05296 0.01 0.024
PIN 17 S -0.02953 0.06496 0 U U
RC -0.03453 0.05296 0.01 0.024
PIN 18 S -0.05413 0.06496 0 U U
RC -0.06413 0.05296 0.02 0.024
#
# PKG 48
PKG SOP8_154_P050_V1 0.05 -0.143 -0.0965 0.143 0.0965
CT
OB -0.077 0.0965 I
OS 0.077 0.0965
OS 0.077 0.083
OS 0.118 0.083
OS 0.118 0.067
OS 0.077 0.067
OS 0.077 0.033
OS 0.118 0.033
OS 0.118 0.017
OS 0.077 0.017
OS 0.077 -0.017
OS 0.118 -0.017
OS 0.118 -0.033
OS 0.077 -0.033
OS 0.077 -0.067
OS 0.118 -0.067
OS 0.118 -0.083
OS 0.077 -0.083
OS 0.077 -0.0965
OS -0.077 -0.0965
OS -0.077 -0.083
OS -0.118 -0.083
OS -0.118 -0.067
OS -0.077 -0.067
OS -0.077 -0.033
OS -0.118 -0.033
OS -0.118 -0.017
OS -0.077 -0.017
OS -0.077 0.017
OS -0.118 0.017
OS -0.118 0.033
OS -0.077 0.033
OS -0.077 0.067
OS -0.118 0.067
OS -0.118 0.083
OS -0.077 0.083
OS -0.077 0.0965
OE
CE
PIN 1 S -0.1105 0.075 0 U U
RC -0.143 0.065 0.065 0.02
PIN 2 S -0.1105 0.025 0 U U
RC -0.143 0.015 0.065 0.02
PIN 3 S -0.1105 -0.025 0 U U
RC -0.143 -0.035 0.065 0.02
PIN 4 S -0.1105 -0.075 0 U U
RC -0.143 -0.085 0.065 0.02
PIN 5 S 0.1105 -0.075 0 U U
RC 0.078 -0.085 0.065 0.02
PIN 6 S 0.1105 -0.025 0 U U
RC 0.078 -0.035 0.065 0.02
PIN 7 S 0.1105 0.025 0 U U
RC 0.078 0.015 0.065 0.02
PIN 8 S 0.1105 0.075 0 U U
RC 0.078 0.065 0.065 0.02
#
# PKG 49
PKG SMC_L_287X268_V3 0.23426 -0.16513 -0.13976 0.16513 0.13976
RC -0.14961 -0.13976 0.2992201 0.2795201
PIN 1 S -0.11713 0 0 U U
RC -0.16513 -0.073 0.096 0.146
PIN 2 S 0.11713 0 0 U U
RC 0.06913 -0.073 0.096 0.146
#
# PKG 50
PKG SOP8_118_P0256_V2 0.0256 -0.1205 -0.06 0.1205 0.06
RC -0.06 -0.06 0.12 0.12
PIN 1 S -0.0905 0.0384 0 U U
RC -0.1205 0.0294 0.06 0.018
PIN 2 S -0.0905 0.0128 0 U U
RC -0.1205 0.0038 0.06 0.018
PIN 3 S -0.0905 -0.0128 0 U U
RC -0.1205 -0.0218 0.06 0.018
PIN 4 S -0.0905 -0.0384 0 U U
RC -0.1205 -0.0474 0.06 0.018
PIN 5 S 0.0905 -0.0384 0 U U
RC 0.0605 -0.0474 0.06 0.018
PIN 6 S 0.0905 -0.0128 0 U U
RC 0.0605 -0.0218 0.06 0.018
PIN 7 S 0.0905 0.0128 0 U U
RC 0.0605 0.0038 0.06 0.018
PIN 8 S 0.0905 0.0384 0 U U
RC 0.0605 0.0294 0.06 0.018
#
# PKG 51
PKG QFN26_118X197_P197_TR049X010 0.0196799 -0.08021 -0.11956 0.08021 0.11956
RC -0.06102 -0.10039 0.12204 0.2007799
PIN 1 S -0.05671 0.07874 0 U U
RC -0.08021 0.07274 0.047 0.012
PIN 2 S -0.05671 0.05906 0 U U
RC -0.08021 0.05306 0.047 0.012
PIN 3 S -0.05671 0.03937 0 U U
RC -0.08021 0.03337 0.047 0.012
PIN 4 S -0.05671 0.01969 0 U U
RC -0.08021 0.01369 0.047 0.012
PIN 5 S -0.05671 0 0 U U
RC -0.08021 -0.006 0.047 0.012
PIN 6 S -0.05671 -0.01969 0 U U
RC -0.08021 -0.02569 0.047 0.012
PIN 7 S -0.05671 -0.03937 0 U U
RC -0.08021 -0.04537 0.047 0.012
PIN 8 S -0.05671 -0.05906 0 U U
RC -0.08021 -0.06506 0.047 0.012
PIN 9 S -0.05671 -0.07874 0 U U
RC -0.08021 -0.08474 0.047 0.012
PIN 10 S -0.01969 -0.09756 0 U U
RC -0.02619 -0.11956 0.013 0.044
PIN 11 S 0.01969 -0.09756 0 U U
RC 0.01319 -0.11956 0.013 0.044
PIN 12 S 0.05671 -0.07874 0 U U
RC 0.03321 -0.08474 0.047 0.012
PIN 13 S 0.05671 -0.05906 0 U U
RC 0.03321 -0.06506 0.047 0.012
PIN 14 S 0.05671 -0.03937 0 U U
RC 0.03321 -0.04537 0.047 0.012
PIN 15 S 0.05671 -0.01969 0 U U
RC 0.03321 -0.02569 0.047 0.012
PIN 16 S 0.05671 0 0 U U
RC 0.03321 -0.006 0.047 0.012
PIN 17 S 0.05671 0.01969 0 U U
RC 0.03321 0.01369 0.047 0.012
PIN 18 S 0.05671 0.03937 0 U U
RC 0.03321 0.03337 0.047 0.012
PIN 19 S 0.05671 0.05906 0 U U
RC 0.03321 0.05306 0.047 0.012
PIN 20 S 0.05671 0.07874 0 U U
RC 0.03321 0.07274 0.047 0.012
PIN 21 S 0 0.07887 0 U U
CT
OB -0.02618996063 0.07393996063 I
OS -0.02618996063 0.11956003937
OS -0.01318996063 0.11956003937
OS -0.01318996063 0.0838
OS 0.01318996063 0.0838
OS 0.01318996063 0.11956003937
OS 0.02618996063 0.11956003937
OS 0.02618996063 0.07393996063
OS -0.02618996063 0.07393996063
OE
CE
PIN 22 S -0.02007 0.10395 0 U U
RC -0.02057 0.10345 0.001 0.001
PIN 23 S 0 0.04331 0 U U
RC -0.0245 0.03831 0.049 0.01
PIN 24 S 0 0.00787 0 U U
RC -0.0245 0.00287 0.049 0.01
PIN 25 S 0 -0.02756 0 U U
RC -0.0245 -0.03256 0.049 0.01
PIN 26 S 0 -0.06299 0 U U
RC -0.0245 -0.06799 0.049 0.01
#
# PKG 52
PKG SMC_0402R_H014 0.042 -0.035 -0.012 0.035 0.012
RC -0.02 -0.012 0.04 0.024
PIN 1 S -0.021 0 0 U U
RC -0.035 -0.012 0.028 0.024
PIN 2 S 0.021 0 0 U U
RC 0.007 -0.012 0.028 0.024
#
# PKG 53
PKG SMC_0603R_H024 0.054 -0.042 -0.018 0.042 0.018
RC -0.032 -0.018 0.064 0.036
PIN 1 S -0.027 0 0 U U
RC -0.042 -0.017 0.03 0.034
PIN 2 S 0.027 0 0 U U
RC 0.012 -0.017 0.03 0.034
#
# PKG 54
PKG SMC_0805R_H026 0.066 -0.052 -0.027 0.052 0.027
RC -0.04 -0.025 0.08 0.05
PIN 1 S -0.033 0 0 U U
RC -0.052 -0.027 0.038 0.054
PIN 2 S 0.033 0 0 U U
RC 0.014 -0.027 0.038 0.054
#
# PKG 55
PKG SMC_Y2_079X047 0.05314 -0.04307 -0.0275 0.04307 0.0275
RC -0.04134 -0.02559 0.0826799 0.0511799
PIN 1 S -0.02657 0 0 U U
RC -0.04307 -0.0275 0.033 0.055
PIN 2 S 0.02657 0 0 U U
RC 0.01007 -0.0275 0.033 0.055
#
# PKG 56
PKG SMC_0402R_H016 0.042 -0.035 -0.012 0.035 0.012
RC -0.02 -0.012 0.04 0.024
PIN 1 S -0.021 0 0 U U
RC -0.035 -0.012 0.028 0.024
PIN 2 S 0.021 0 0 U U
RC 0.007 -0.012 0.028 0.024
#
# PKG 57
PKG SMC_0402R 0.042 -0.035 -0.012 0.035 0.012
RC -0.02 -0.012 0.04 0.024
PIN 1 S -0.021 0 0 U U
RC -0.035 -0.012 0.028 0.024
PIN 2 S 0.021 0 0 U U
RC 0.007 -0.012 0.028 0.024
#
# PKG 58
PKG SMC_DS_063X031_V4 0.05904 -0.04502 -0.01772 0.04502 0.01772
RC -0.03347 -0.01772 0.06694 0.03544
PIN A S -0.02952 0 0 U U
RC -0.04502 -0.0155 0.031 0.031
PIN C S 0.0295201 0 0 U U
RC 0.01402 -0.0155 0.031 0.031
#
# PKG 59
PKG SMC_0201R 0.02086 -0.01643 -0.0075 0.01643 0.0075
RC -0.0124 -0.0065 0.0248 0.013
PIN 1 S -0.01043 0 0 U U
RC -0.01643 -0.0075 0.012 0.015
PIN 2 S 0.01043 0 0 U U
RC 0.00443 -0.0075 0.012 0.015
#
# PKG 60
PKG SMC_0805R_H057 0.066 -0.052 -0.027 0.052 0.027
RC -0.04 -0.025 0.08 0.05
PIN 1 S -0.033 0 0 U U
RC -0.052 -0.027 0.038 0.054
PIN 2 S 0.033 0 0 U U
RC 0.014 -0.027 0.038 0.054
#
# PKG 61
PKG SMC_0402R_H022 0.042 -0.035 -0.012 0.035 0.012
RC -0.02 -0.012 0.04 0.024
PIN 1 S -0.021 0 0 U U
RC -0.035 -0.012 0.028 0.024
PIN 2 S 0.021 0 0 U U
RC 0.007 -0.012 0.028 0.024
#
# PKG 62
PKG S_M_H_3P_S_P058 0.083528 -0.07857 -0.08054 0.07857 0.0561
CT
OB -0.01476003937 -0.06593996063 I
OS -0.01476003937 -0.0561
OS -0.0561 -0.0561
OS -0.0561 0.0561
OS 0.0561 0.0561
OS 0.0561 -0.0561
OS 0.01476003937 -0.0561
OS 0.01476003937 -0.06593996063
OS -0.01476003937 -0.06593996063
OE
CE
PIN 1 S -0.05807 0 0 U U
RC -0.07857 -0.0435 0.041 0.087
PIN 2 S 0 -0.06004 0 U U
RC -0.0195 -0.08054 0.039 0.041
PIN 3 S 0.05807 0 0 U U
RC 0.03757 -0.0435 0.041 0.087
#
# PKG 63
PKG SOT143 0.067 -0.072 -0.057 0.072 0.057
CT
OB 0.045 0.0285 I
OS 0.0255 0.0285
OS 0.0255 -0.0285
OS 0.045 -0.0285
OS 0.045 -0.0465
OS 0.0255 -0.0465
OS 0.0255 -0.05625
OS -0.0255 -0.05625
OS -0.0255 -0.0465
OS -0.045 -0.0465
OS -0.045 -0.0285
OS -0.0255 -0.0285
OS -0.0255 0.0125
OS -0.045 0.0125
OS -0.045 0.0465
OS -0.0255 0.0465
OS -0.0255 0.05625
OS 0.0255 0.05625
OS 0.0255 0.0465
OS 0.045 0.0465
OS 0.045 0.0285
OE
CE
PIN 1 S -0.0435 0.0295 0 U U
RC -0.072 0.008 0.057 0.043
PIN 2 S -0.0435 -0.0375 0 U U
RC -0.072 -0.057 0.057 0.039
PIN 3 S 0.0435 -0.0375 0 U U
RC 0.015 -0.057 0.057 0.039
PIN 4 S 0.0435 0.0375 0 U U
RC 0.015 0.018 0.057 0.039
#
# PKG 64
PKG SMC_Y4_126X098_V5_H032 0.0669201 -0.07081 -0.05696 0.07081 0.05696
RC -0.06496 -0.05118 0.1299201 0.10236
PIN 1 S -0.04331 -0.03346 0 U U
RC -0.07081 -0.05696 0.055 0.047
PIN 2 S 0.04331 -0.03346 0 U U
RC 0.01581 -0.05696 0.055 0.047
PIN 3 S 0.04331 0.03346 0 U U
RC 0.01581 0.00996 0.055 0.047
PIN 4 S -0.04331 0.03346 0 U U
RC -0.07081 0.00996 0.055 0.047
#
# PKG 65
PKG SC70_5V1 0.02559 -0.066 -0.0423 0.066 0.0423
CT
OB -0.04718996063 -0.03051003937 I
OS -0.04718996063 -0.020669980315
OS -0.02751003937 -0.020669980315
OS -0.02751003937 -0.004919980315
OS -0.04718996063 -0.004919980315
OS -0.04718996063 0.004919980315
OS -0.02751003937 0.004919980315
OS -0.02751003937 0.020669980315
OS -0.04718996063 0.020669980315
OS -0.04718996063 0.03051003937
OS -0.02751003937 0.03051003937
OS -0.02751003937 0.0423
OS 0.02751003937 0.0423
OS 0.02751003937 0.03051003937
OS 0.04718996063 0.03051003937
OS 0.04718996063 0.020669980315
OS 0.02751003937 0.020669980315
OS 0.02751003937 -0.020669980315
OS 0.04718996063 -0.020669980315
OS 0.04718996063 -0.03051003937
OS 0.02751003937 -0.03051003937
OS 0.02751003937 -0.0423
OS -0.02751003937 -0.0423
OS -0.02751003937 -0.03051003937
OS -0.04718996063 -0.03051003937
OE
CE
PIN 1 S -0.047 0.02559 0 U U
RC -0.066 0.01909 0.038 0.013
PIN 2 S -0.047 0 0 U U
RC -0.066 -0.0065 0.038 0.013
PIN 3 S -0.047 -0.02559 0 U U
RC -0.066 -0.03209 0.038 0.013
PIN 4 S 0.047 -0.02559 0 U U
RC 0.028 -0.03209 0.038 0.013
PIN 5 S 0.047 0.02559 0 U U
RC 0.028 0.01909 0.038 0.013
#
# PKG 66
PKG SOT23_6 0.0374 -0.08 -0.05709 0.08 0.05709
CT
OB -0.05906003937 0.00983996063 I
OS -0.0315 0.00983996063
OS -0.0315 0.02756003937
OS -0.05906003937 0.02756003937
OS -0.05906003937 0.04723996063
OS -0.0315 0.04723996063
OS -0.0315 0.05708996063
OS 0.0315 0.05708996063
OS 0.0315 0.04723996063
OS 0.05906003937 0.04723996063
OS 0.05906003937 0.02756003937
OS 0.0315 0.02756003937
OS 0.0315 0.00983996063
OS 0.05906003937 0.00983996063
OS 0.05906003937 -0.00983996063
OS 0.0315 -0.00983996063
OS 0.0315 -0.02756003937
OS 0.05906003937 -0.02756003937
OS 0.05906003937 -0.04723996063
OS 0.0315 -0.04723996063
OS 0.0315 -0.05708996063
OS -0.0315 -0.05708996063
OS -0.0315 -0.04723996063
OS -0.05906003937 -0.04723996063
OS -0.05906003937 -0.02756003937
OS -0.0315 -0.02756003937
OS -0.0315 -0.00983996063
OS -0.05906003937 -0.00983996063
OS -0.05906003937 0.00983996063
OE
CE
PIN 1 S -0.0565 0.0374 0 U U
RC -0.08 0.0274 0.047 0.02
PIN 2 S -0.0565 0 0 U U
RC -0.08 -0.01 0.047 0.02
PIN 3 S -0.0565 -0.0374 0 U U
RC -0.08 -0.0474 0.047 0.02
PIN 4 S 0.0565 -0.0374 0 U U
RC 0.033 -0.0474 0.047 0.02
PIN 5 S 0.0565 0 0 U U
RC 0.033 -0.01 0.047 0.02
PIN 6 S 0.0565 0.0374 0 U U
RC 0.033 0.0274 0.047 0.02
#
# PKG 67
PKG S_M_DIL_2X5_P100_V1 0.1 -0.24193 -0.17256 0.24193 0.17256
CT
OB 0.241930019685 -0.096 I
OS 0.212080019685 -0.096
OS 0.212080019685 -0.14606003937
OS 0.186880019685 -0.14606003937
OS 0.186880019685 -0.096
OS 0.112080019685 -0.096
OS 0.112080019685 -0.14606003937
OS 0.086880019685 -0.14606003937
OS 0.086880019685 -0.096
OS 0.012080019685 -0.096
OS 0.012080019685 -0.14606003937
OS -0.013119980315 -0.14606003937
OS -0.013119980315 -0.096
OS -0.087919980315 -0.096
OS -0.087919980315 -0.14606003937
OS -0.113119980315 -0.14606003937
OS -0.113119980315 -0.096
OS -0.186919980315 -0.096
OS -0.186919980315 -0.14606003937
OS -0.212119980315 -0.14606003937
OS -0.212119980315 -0.096
OS -0.241930019685 -0.096
OS -0.241930019685 0.096
OS -0.213119980315 0.096
OS -0.213119980315 0.146
OS -0.187919980315 0.146
OS -0.187919980315 0.096
OS -0.113119980315 0.096
OS -0.113119980315 0.146
OS -0.087919980315 0.146
OS -0.087919980315 0.096
OS -0.013119980315 0.096
OS -0.013119980315 0.146
OS 0.012080019685 0.146
OS 0.012080019685 0.096
OS 0.087880019685 0.096
OS 0.087880019685 0.146
OS 0.113080019685 0.146
OS 0.113080019685 0.096
OS 0.186880019685 0.096
OS 0.186880019685 0.146
OS 0.212080019685 0.146
OS 0.212080019685 0.096
OS 0.241930019685 0.096
OS 0.241930019685 -0.096
OE
CE
PIN 1 S -0.2 -0.10256 0 U U
RC -0.225 -0.17256 0.05 0.14
PIN 2 S -0.2 0.10256 0 U U
RC -0.225 0.03256 0.05 0.14
PIN 3 S -0.1 -0.10256 0 U U
RC -0.125 -0.17256 0.05 0.14
PIN 4 S -0.1 0.10256 0 U U
RC -0.125 0.03256 0.05 0.14
PIN 5 S 0 -0.10256 0 U U
RC -0.025 -0.17256 0.05 0.14
PIN 6 S 0 0.10256 0 U U
RC -0.025 0.03256 0.05 0.14
PIN 7 S 0.1 -0.10256 0 U U
RC 0.075 -0.17256 0.05 0.14
PIN 8 S 0.1 0.10256 0 U U
RC 0.075 0.03256 0.05 0.14
PIN 9 S 0.2 -0.10256 0 U U
RC 0.175 -0.17256 0.05 0.14
PIN 10 S 0.2 0.10256 0 U U
RC 0.175 0.03256 0.05 0.14
#
# PKG 68
PKG S_F_USB_1X5_G2_GH4_RA_P0256 0.02559 -0.16142 -0.1525599 0.1614201 0.0727901
RC -0.15157 -0.1525599 0.3031401 0.20866
PIN 1 S -0.0511799 0.04331 0 U U
RC -0.0591799 0.01681 0.016 0.053
PIN 2 S -0.02559 0.04331 0 U U
RC -0.03359 0.01681 0.016 0.053
PIN 3 S 0 0.04331 0 U U
RC -0.008 0.01681 0.016 0.053
PIN 4 S 0.0255901 0.04331 0 U U
RC 0.0175901 0.01681 0.016 0.053
PIN 5 S 0.05118 0.04331 0 U U
RC 0.04318 0.01681 0.016 0.053
PIN G1 S -0.03937 -0.0620099 0 U U
RC -0.06887 -0.0995099 0.059 0.075
PIN G2 S 0.0393701 -0.0620099 0 U U
RC 0.0098701 -0.0995099 0.059 0.075
PIN GH1 T -0.0984299 0.0442901 0 U U
CR -0.0984299 0.0442901 0.0285
PIN GH2 T 0.09843 0.0442901 0 U U
CR 0.09843 0.0442901 0.0285
PIN GH3 T -0.1378 -0.0620099 0 U U
CT
OB -0.161419980315 -0.07972992126 I
OS -0.161419980315 -0.04428996063
OC -0.14173996063 -0.024609940945 -0.14173996063 -0.04428996063 Y
OS -0.09056003937 -0.02461003937
OS -0.09056003937 -0.09940984252
OS -0.110177755906 -0.09940984252
OS -0.11023996063 -0.099409940945
OS -0.14173996063 -0.099409940945
OC -0.161419980315 -0.07972992126 -0.14173996063 -0.07972992126 Y
OE
CE
PIN GH4 T 0.1378 -0.0620099 0 U U
CT
OB 0.09056003937 -0.07972992126 I
OS 0.090560137795 -0.02461003937
OS 0.141740059055 -0.024609940945
OC 0.16142007874 -0.04428996063 0.141740059055 -0.04428996063 Y
OS 0.16142007874 -0.07972992126
OC 0.141740059055 -0.099409940945 0.141740059055 -0.07972992126 Y
OS 0.090560137795 -0.09940984252
OS 0.09056003937 -0.07972992126
OE
CE
#
# PKG 69
PKG SOP16_173_P0256_H043 0.02559 -0.1505 -0.0985 0.1505 0.0985
RC -0.0865 -0.0985 0.173 0.197
PIN 1 S -0.1195 0.08957 0 U U
RC -0.1505 0.08257 0.062 0.014
PIN 2 S -0.1195 0.06398 0 U U
RC -0.1505 0.05698 0.062 0.014
PIN 3 S -0.1195 0.03839 0 U U
RC -0.1505 0.03139 0.062 0.014
PIN 4 S -0.1195 0.0128 0 U U
RC -0.1505 0.0058 0.062 0.014
PIN 5 S -0.1195 -0.0128 0 U U
RC -0.1505 -0.0198 0.062 0.014
PIN 6 S -0.1195 -0.03839 0 U U
RC -0.1505 -0.04539 0.062 0.014
PIN 7 S -0.1195 -0.06398 0 U U
RC -0.1505 -0.07098 0.062 0.014
PIN 8 S -0.1195 -0.08957 0 U U
RC -0.1505 -0.09657 0.062 0.014
PIN 9 S 0.1195 -0.08957 0 U U
RC 0.0885 -0.09657 0.062 0.014
PIN 10 S 0.1195 -0.06398 0 U U
RC 0.0885 -0.07098 0.062 0.014
PIN 11 S 0.1195 -0.03839 0 U U
RC 0.0885 -0.04539 0.062 0.014
PIN 12 S 0.1195 -0.0128 0 U U
RC 0.0885 -0.0198 0.062 0.014
PIN 13 S 0.1195 0.0128 0 U U
RC 0.0885 0.0058 0.062 0.014
PIN 14 S 0.1195 0.03839 0 U U
RC 0.0885 0.03139 0.062 0.014
PIN 15 S 0.1195 0.06398 0 U U
RC 0.0885 0.05698 0.062 0.014
PIN 16 S 0.1195 0.08957 0 U U
RC 0.0885 0.08257 0.062 0.014
#
# PKG 70
PKG S_M_EF64_PCIE_P0394_V1 0.0195 -0.014 -0.0825 1.31321 0.0825
RC -0.01 -0.01 0.02 0.02
PIN A1 S 0 0.0195 0 U U
RC -0.014 -0.0435 0.028 0.126
PIN A2 S 0.0393701 0 0 U U
RC 0.0253701 -0.0825 0.028 0.165
PIN A3 S 0.0787401 0 0 U U
RC 0.0647401 -0.0825 0.028 0.165
PIN A4 S 0.11811 0 0 U U
RC 0.10411 -0.0825 0.028 0.165
PIN A5 S 0.15748 0 0 U U
RC 0.14348 -0.0825 0.028 0.165
PIN A6 S 0.19685 0 0 U U
RC 0.18285 -0.0825 0.028 0.165
PIN A7 S 0.2362201 0 0 U U
RC 0.2222201 -0.0825 0.028 0.165
PIN A8 S 0.2755901 0 0 U U
RC 0.2615901 -0.0825 0.028 0.165
PIN A9 S 0.31496 0 0 U U
RC 0.30096 -0.0825 0.028 0.165
PIN A10 S 0.35433 0 0 U U
RC 0.34033 -0.0825 0.028 0.165
PIN A11 S 0.3937 0 0 U U
RC 0.3797 -0.0825 0.028 0.165
PIN A12 S 0.51181 0 0 U U
RC 0.49781 -0.0825 0.028 0.165
PIN A13 S 0.55118 0 0 U U
RC 0.53718 -0.0825 0.028 0.165
PIN A14 S 0.59055 0 0 U U
RC 0.57655 -0.0825 0.028 0.165
PIN A15 S 0.6299201 0 0 U U
RC 0.6159201 -0.0825 0.028 0.165
PIN A16 S 0.6692901 0 0 U U
RC 0.6552901 -0.0825 0.028 0.165
PIN A17 S 0.70866 0 0 U U
RC 0.69466 -0.0825 0.028 0.165
PIN A18 S 0.74803 0 0 U U
RC 0.73403 -0.0825 0.028 0.165
PIN A19 S 0.7874 0 0 U U
RC 0.7734 -0.0825 0.028 0.165
PIN A20 S 0.8267701 0 0 U U
RC 0.8127701 -0.0825 0.028 0.165
PIN A21 S 0.8661401 0 0 U U
RC 0.8521401 -0.0825 0.028 0.165
PIN A22 S 0.90551 0 0 U U
RC 0.89151 -0.0825 0.028 0.165
PIN A23 S 0.94488 0 0 U U
RC 0.93088 -0.0825 0.028 0.165
PIN A24 S 0.98425 0 0 U U
RC 0.97025 -0.0825 0.028 0.165
PIN A25 S 1.0236201 0 0 U U
RC 1.0096201 -0.0825 0.028 0.165
PIN A26 S 1.0629901 0 0 U U
RC 1.0489901 -0.0825 0.028 0.165
PIN A27 S 1.10236 0 0 U U
RC 1.08836 -0.0825 0.028 0.165
PIN A28 S 1.14173 0 0 U U
RC 1.12773 -0.0825 0.028 0.165
PIN A29 S 1.1811 0 0 U U
RC 1.1671 -0.0825 0.028 0.165
PIN A30 S 1.2204701 0 0 U U
RC 1.2064701 -0.0825 0.028 0.165
PIN A31 S 1.2598401 0 0 U U
RC 1.2458401 -0.0825 0.028 0.165
PIN A32 S 1.29921 0 0 U U
RC 1.28521 -0.0825 0.028 0.165
PIN B1 S 0 0 0 U U
RC -0.014 -0.0825 0.028 0.165
PIN B2 S 0.0393701 0 0 U U
RC 0.0253701 -0.0825 0.028 0.165
PIN B3 S 0.0787401 0 0 U U
RC 0.0647401 -0.0825 0.028 0.165
PIN B4 S 0.11811 0 0 U U
RC 0.10411 -0.0825 0.028 0.165
PIN B5 S 0.15748 0 0 U U
RC 0.14348 -0.0825 0.028 0.165
PIN B6 S 0.19685 0 0 U U
RC 0.18285 -0.0825 0.028 0.165
PIN B7 S 0.2362201 0 0 U U
RC 0.2222201 -0.0825 0.028 0.165
PIN B8 S 0.2755901 0 0 U U
RC 0.2615901 -0.0825 0.028 0.165
PIN B9 S 0.31496 0 0 U U
RC 0.30096 -0.0825 0.028 0.165
PIN B10 S 0.35433 0 0 U U
RC 0.34033 -0.0825 0.028 0.165
PIN B11 S 0.3937 0 0 U U
RC 0.3797 -0.0825 0.028 0.165
PIN B12 S 0.51181 0 0 U U
RC 0.49781 -0.0825 0.028 0.165
PIN B13 S 0.55118 0 0 U U
RC 0.53718 -0.0825 0.028 0.165
PIN B14 S 0.59055 0 0 U U
RC 0.57655 -0.0825 0.028 0.165
PIN B15 S 0.6299201 0 0 U U
RC 0.6159201 -0.0825 0.028 0.165
PIN B16 S 0.6692901 0 0 U U
RC 0.6552901 -0.0825 0.028 0.165
PIN B17 S 0.70866 0 0 U U
RC 0.69466 -0.0825 0.028 0.165
PIN B18 S 0.74803 0 0 U U
RC 0.73403 -0.0825 0.028 0.165
PIN B19 S 0.7874 0 0 U U
RC 0.7734 -0.0825 0.028 0.165
PIN B20 S 0.8267701 0 0 U U
RC 0.8127701 -0.0825 0.028 0.165
PIN B21 S 0.8661401 0 0 U U
RC 0.8521401 -0.0825 0.028 0.165
PIN B22 S 0.90551 0 0 U U
RC 0.89151 -0.0825 0.028 0.165
PIN B23 S 0.94488 0 0 U U
RC 0.93088 -0.0825 0.028 0.165
PIN B24 S 0.98425 0 0 U U
RC 0.97025 -0.0825 0.028 0.165
PIN B25 S 1.0236201 0 0 U U
RC 1.0096201 -0.0825 0.028 0.165
PIN B26 S 1.0629901 0 0 U U
RC 1.0489901 -0.0825 0.028 0.165
PIN B27 S 1.10236 0 0 U U
RC 1.08836 -0.0825 0.028 0.165
PIN B28 S 1.14173 0 0 U U
RC 1.12773 -0.0825 0.028 0.165
PIN B29 S 1.1811 0 0 U U
RC 1.1671 -0.0825 0.028 0.165
PIN B30 S 1.2204701 0 0 U U
RC 1.2064701 -0.0825 0.028 0.165
PIN B31 S 1.2598401 0.0195 0 U U
RC 1.2458401 -0.0435 0.028 0.126
PIN B32 S 1.29921 0 0 U U
RC 1.28521 -0.0825 0.028 0.165
#
# PKG 71
PKG NO_BODY+1 0 -0.02 -0.02 0.02 0.02
RC -0.02 -0.02 0.04 0.04
PIN 1 S 0 0 0 U U
CR 0 0 0.02
#

### steps/pcb/netlists/cadnet/netlist
H optimize n staggered n
$0 $NONE$
$1 XP3R3V_FPGA
$2 SG
$3 XP12R0V
$4 XP3R3V_VPLL
$5 XP3R3V_VPHY
$6 FPGA_MGTAVTT
$7 XP1R0V_FPGA_MGTAVCC
$8 XP1R8V_FPGA_VCCAUX
$9 XP2R5V_FPGA
$10 XP1R0V_FPGA_VCCINT
$11 UNNAMED_516_CAPACITOR_I29_1
$12 XP5R0V_FB_R_TO_AGND
$13 XP5R0V
$14 XP1R2V_FPGA
$15 XP1R0V_FPGA
$16 XP1R8V_FPGA
$17 UNNAMED_517_CAPACITOR_I30_1
$18 XP3R3V_FB_R_TO_AGND
$19 XP3R3V
$20 XP1R2V_EN_R
$21 XP1R2V_VIN
$22 XP1R8V_VIN
$23 XP1R8V_EN_R
$24 C_PCIEREFCLKP
$25 PCIE_REFCLKP
$26 XP1R2V_SS
$27 XP1R8V_SS
$28 XP1R2V_PG_R
$29 XP1R8V_PG_R
$30 XP12R0V_IN
$31 UNNAMED_515_CAPACITOR_I128_1
$32 UNNAMED_515_CAPACITOR_I130_1
$33 XP3R3V_FPGA_EN_R
$34 C_PCIEREFCLKN
$35 PCIE_REFCLKN
$36 UNNAMED_515_CAPACITOR_I132_1
$37 UNNAMED_515_CAPACITOR_I138_1
$38 XP3R3V_FPGA_SR
$39 C_CPU_RX_PCIE_MGT0_TXP
$40 CPU_RX_PCIE_MGT0_TXP
$41 VDD3V3_OSC_200M
$42 VDD3V3_OSC_125M
$43 C_CPU_RX_PCIE_MGT0_TXN
$44 CPU_RX_PCIE_MGT0_TXN
$45 UNNAMED_3_RESISTOR_I151_2
$46 OSC_200M_CLKP
$47 MHZ200CLKP_CLKIN
$48 OSC_200M_CLKN
$49 MHZ200CLKN_CLKIN
$50 OSC_125M_CLKP
$51 MHZ125CLKP_CLKIN
$52 OSC_125M_CLKN
$53 MHZ125CLKN_CLKIN
$54 UNNAMED_523_CAPACITOR_I7_1
$55 VIN_XP1R0V
$56 XP1R0V_PG
$57 XP1R0V_SS
$58 XP1R0V_AGND
$59 C_CPU_RX_PCIE_MGT1_TXP
$60 CPU_RX_PCIE_MGT1_TXP
$61 UNNAMED_523_CAPACITOR_I9_1
$62 XP1R0V_COMP
$63 UNNAMED_523_CAPACITOR_I24_1
$64 XP1R0V_SW
$65 UNNAMED_523_CAPACITOR_I31_2
$66 UNNAMED_523_CAPACITOR_I28_1
$67 XP1R0V_FB_R_TO_AGND
$68 C_CPU_RX_PCIE_MGT1_TXN
$69 CPU_RX_PCIE_MGT1_TXN
$70 XP3R3V_GPS
$71 VDD3V3_SHT31A
$72 XP1R8V_ICP10100
$73 C_CPU_RX_PCIE_MGT2_TXP
$74 CPU_RX_PCIE_MGT2_TXP
$75 VDD_BNO085
$76 XP5R0V_MAC
$77 UNNAMED_525_CAPACITOR_I7_1
$78 UNNAMED_9_BNO080LGA28_I29_CAP
$79 XP3R3V_EN
$80 XP3R3V_AUX_PCIE
$81 XP3R3V_PCIE
$82 R_XP5R0V_EN
$83 XP12R0V_A_EN
$84 VIN_XP5R0V
$85 UNNAMED_525_CAPACITOR_I16_1
$86 UNNAMED_525_CAPACITOR_I14_1
$87 UNNAMED_525_CAPACITOR_I18_1
$88 XP3R3V_FT4232
$89 XP5R0V_SS
$90 XP5R0V_AGND
$91 UNNAMED_12_CAPACITOR_I318_2
$92 UNNAMED_12_CAPACITOR_I321_2
$93 RGB_LED_SHUTDOWN_N
$94 UNNAMED_12_CAPACITOR_I328_2
$95 UNNAMED_12_CAPACITOR_I332_2
$96 C_CPU_RX_PCIE_MGT2_TXN
$97 CPU_RX_PCIE_MGT2_TXN
$98 C_CPU_RX_PCIE_MGT3_TXP
$99 CPU_RX_PCIE_MGT3_TXP
$100 C_CPU_RX_PCIE_MGT3_TXN
$101 CPU_RX_PCIE_MGT3_TXN
$102 VDD_PCA9546A
$103 XP12R0V_A_TIMER
$104 UNNAMED_516_CAPACITOR_I13_1
$105 XP5R0V_COMP
$106 UNNAMED_516_CAPACITOR_I27_1
$107 XP5R0V_SW
$108 UNNAMED_516_CAPACITOR_I37_2
$109 UNNAMED_9_BNO080LGA28_I29_XOUT3
$110 VIN_XP3R3
$111 XP3R3V_SS
$112 XP3R3V_AGND
$113 XP12R0V_A_SS
$114 UNNAMED_9_CAPACITOR_I17_1
$115 UNNAMED_517_CAPACITOR_I17_1
$116 XP3R3V_COMP
$117 UNNAMED_517_CAPACITOR_I27_1
$118 XP3R3V_SW
$119 UNNAMED_517_CAPACITOR_I29_2
$120 XP12R0V_A_AVIN
$121 XP5R0V_USB_CONN
$122 XP5R0V_MAC_USB
$123 USB_PWR_EN
$124 XP12R0V_A_IMON
$125 XP5R0V_VCC_ANT
$126 XP5R0V_PG
$127 R_XP3R3V_PG
$128 XP12R0V_A_OV
$129 UNNAMED_524_CAPACITOR_I7_2
$130 UNNAMED_524_CAPACITOR_I10_2
$131 FT4232_VREGOUT
$132 XP5R0V_FT4232
$133 XP12R0V_PCIE
$134 XP12R0V_EXT
$135 SMA2_SIG_IO_CONN
$136 SMA1_SIG_IO_CONN
$137 SMA4_SIG_IO_CONN
$138 SMA3_SIG_IO_CONN
$139 FT4232_FPGA_TMS
$140 FT4232_FPGA_TDI
$141 FT4232_FPGA_TCK
$142 FT4232_FPGA_TDO
$143 UNNAMED_14_OPTICAL_I12_A
$144 LED_DATOUT3
$145 UNNAMED_14_OPTICAL_I138_A
$146 FPGA_USR_LED1
$147 UNNAMED_14_OPTICAL_I139_A
$148 FPGA_USR_LED0
$149 UNNAMED_14_OPTICAL_I289_A
$150 UNNAMED_14_LED4PV14_I265_1
$151 UNNAMED_14_LED4PV14_I265_3
$152 UNNAMED_14_LED4PV14_I265_4
$153 UNNAMED_14_LED4PV14_I266_1
$154 UNNAMED_14_LED4PV14_I266_3
$155 UNNAMED_14_LED4PV14_I266_4
$156 UNNAMED_14_LED4PV14_I267_1
$157 UNNAMED_14_LED4PV14_I267_3
$158 UNNAMED_14_LED4PV14_I267_4
$159 UNNAMED_14_LED4PV14_I268_1
$160 UNNAMED_14_LED4PV14_I268_3
$161 UNNAMED_14_LED4PV14_I268_4
$162 UNNAMED_14_LED4PV14_I269_1
$163 UNNAMED_14_LED4PV14_I269_3
$164 UNNAMED_14_LED4PV14_I269_4
$165 UNNAMED_14_OPTICAL_I191_A
$166 UNNAMED_14_OPTICAL_I11_A
$167 LED_DATOUT2
$168 UNNAMED_14_OPTICAL_I194_A
$169 UNNAMED_14_OPTICAL_I136_A
$170 LED_DATOUT1
$171 UNNAMED_14_OPTICAL_I137_A
$172 LED_DATOUT0
$173 UNNAMED_14_OPTICAL_I143_A
$174 UNNAMED_14_OPTICAL_I140_A
$175 UNNAMED_14_OPTICAL_I141_A
$176 UNNAMED_14_OPTICAL_I142_A
$177 UNNAMED_14_OPTICAL_I292_A
$178 UNNAMED_527_FUSE_I244_1
$179 CARD_PRESENT
$180 PCIE_CONN_TCK
$181 PCIE_CONN_TDI
$182 PCIE_CONN_TDO
$183 PCIE_CONN_TMS
$184 PCIE_CONN_PERST_N
$185 PCIE_CONN_SMCLK
$186 PCIE_CONN_SMDAT
$187 CPU_TX_PCIE_MGT_0_RXP
$188 CPU_TX_PCIE_MGT_0_RXN
$189 UNNAMED_3_CONN64PGF_I61_PRSNT21
$190 CPU_TX_PCIE_MGT_1_RXP
$191 CPU_TX_PCIE_MGT_1_RXN
$192 CPU_TX_PCIE_MGT_2_RXP
$193 CPU_TX_PCIE_MGT_2_RXN
$194 CPU_TX_PCIE_MGT_3_RXP
$195 CPU_TX_PCIE_MGT_3_RXN
$196 UNNAMED_3_CONN64PGF_I61_PRSNT22
$197 FT4232_CHD_TX
$198 DBG_UART_MAC_RX
$199 DBG_UART_GPS_RXD
$200 FT4232_CHD_RX
$201 DBG_UART_MAC_TX
$202 DBG_UART_GPS_TXD
$203 FPGA_CFG_INIT_N
$204 CONN_MICRO_USB_DM
$205 CONN_MICRO_USB_DP
$206 UNNAMED_524_CONNUSB14PGH4FRATH_
$207 FT_USB_DP
$208 FT_USB_DM
$209 UNNAMED_524_CONNUSB14PGH4FRAT_1
$210 UNNAMED_127_G2001028301_I427_4
$211 SN_EEPROM_WP
$212 SEC_EEPROM_WP
$213 SMA_ANALOG_TUNING_IN
$214 UNNAMED_16_CONNHDR2X6FSSMT_I161
$215 UNNAMED_16_CONNHDR2X6FSSMT_I1_1
$216 UNNAMED_16_CONNHDR2X6FSSMT_I1_2
$217 UNNAMED_16_CONNHDR2X6FSSMT_I1_3
$218 UNNAMED_16_CONNHDR2X6FSSMT_I1_6
$219 UNNAMED_16_CONNHDR2X6FSSMT_I1_7
$220 UNNAMED_16_CONNHDR2X6FSSMT_I1_4
$221 UNNAMED_16_CONNHDR2X6FSSMT_I1_5
$222 UNNAMED_5_CONNHDR2X2MSSMT_I126_
$223 EEPROM_SDA
$224 UNNAMED_5_CONNHDR2X2MSSMT_I12_1
$225 EEPROM_SCL
$226 ANALOG_TUNING_IN
$227 R_MAC_10MHZ_RF_OUT
$228 R_MAC_BITEOUT
$229 R_MAC_UART_TX_FPGA_RX
$230 R_MAC_UART_RX_FPGA_TX
$231 R_MAC_PPS_IN1P
$232 R_MAC_USB_DP
$233 R_MAC_PPS_IN1N
$234 R_MAC_USB_DM
$235 R_MAC_PPS_IN0P
$236 R_MAC_PPS_IN0N
$237 R_MAC_PPS_OUTP
$238 R_MAC_PPS_OUTN
$239 MAC_ALARM
$240 GPS_UART_TXD
$241 GPS_RST_N
$242 GPS_UART_RXD
$243 GPSTP1_OUT
$244 GPSTP2_OUT
$245 FT_USB_DETECT
$246 UNNAMED_524_POWERMOS3PNCHV1_I44
$247 UNNAMED_527_POWERMOS3PNCHV1_I23
$248 FPGA_OUT_SN_EEPROM_WP
$249 FPGA_OUT_MACUSBPOWER_EN
$250 XP5R0V_USB_CONN_DET
$251 UNNAMED_527_RESISTOR_I201_2
$252 UNNAMED_527_RESISTOR_I126_1
$253 MUX_USB_DM
$254 MAC_USB_DM
$255 MUX_USB_DP
$256 MAC_USB_DP
$257 FPGA_IN_MAC_USB_OC_N
$258 UNNAMED_14_RESISTOR_I58_2
$259 UART_GPS_TX_FPGA_RX
$260 UART_GPS_RX_FPGA_TX
$261 FPGA_IN_GPSTP2_OUT
$262 FPGA_OUT_GPS_RST_N
$263 FPGA_IN_GPSTP1_OUT
$264 ANT1_OUT
$265 UNNAMED_12_74HCT2G125DPTSSOP8_6
$266 ANT2_OUT
$267 UNNAMED_12_74HCT2G125DPTSSOP8_9
$268 BF_SMA3_SIG_IO_CONN
$269 BF_SMA4_SIG_IO_CONN
$270 FPGA_OUT_SMA1_LED_BLUE_N
$271 FPGA_OUT_SMA1_LED_GREEN_N
$272 BF_SMA2_SIG_IO_CONN
$273 BF_SMA1_SIG_IO_CONN
$274 R_FT_USB_DM
$275 R_FT_USB_DP
$276 XP12R0V_A_PG
$277 R_FT4232_CHD_TX
$278 R_FT4232_CHD_RX
$279 FPGA_TCK
$280 FPGA_TDO
$281 FPGA_TMS
$282 FPGA_TDI
$283 XP1R0V_FPGA_PG
$284 XP1R2V_FPGA_PG
$285 XP1R8V_FPGA_PG
$286 UNNAMED_515_NCP45560IMNTWGHDFN1
$287 PCA9546_I2C_SDA
$288 R_PCA9546_I2C_SDA
$289 PCA9546_I2C_SCL
$290 R_PCA9546_I2C_SCL
$291 PCA9546_RST_N
$292 UNNAMED_5_PCA9546APWTSSOP16_I33
$293 XP12R0V_A_FLTB
$294 UNNAMED_5_PCA9546APWTSSOP16_I_1
$295 UNNAMED_5_PCA9546APWTSSOP16_I_2
$296 ANT3_OUT
$297 UNNAMED_12_74HCT2G125DPTSSOP8_I
$298 ANT4_OUT
$299 UNNAMED_12_74HCT2G125DPTSSOP8_3
$300 UNNAMED_5_24LC16BTISTTSSOP8_I15
$301 UNNAMED_5_24LC16BTISTTSSOP8_I_1
$302 UNNAMED_5_24LC16BTISTTSSOP8_I_2
$303 FPGA_IN_RST_DLY_N
$304 FPGA_IO_0
$305 FPGA_IO_1
$306 PCIE_SMDAT
$307 PCIE_SMCLK
$308 EEPROM_I2C_SDA
$309 EEPROM_I2C_SCL
$310 XP1R2V_FB
$311 XP1R8V_FB
$312 FLASH_CS_N
$313 FLASH_CLK
$314 FPGA_PROGRAM_N
$315 CFGBVS
$316 R_FPGA_TDO
$317 FPGA_MGTRREF
$318 UNNAMED_127_MT25QL128ABA1ESESOP
$319 FPGA_OUT_SEC_EEPROM_WP
$320 LM75B_I2C_SDA
$321 UNNAMED_127_MT25QL128ABA1ESES_1
$322 UNNAMED_127_MT25QL128ABA1ESES_3
$323 UNNAMED_127_MT25QL128ABA1ESES_2
$324 FLASH_DQ0_MOSI
$325 FLASH_DQ1_MISO
$326 FLASH_DQ2
$327 FLASH_DQ3
$328 CCLK_0
$329 FPGA_FLASH_CLK
$330 FPGA_DONE
$331 LM75B_I2C_SCL
$332 FPGA_M0
$333 FPGA_BRD_REV2
$334 FPGA_BRD_REV1
$335 FPGA_M1
$336 FPGA_BRD_REV0
$337 FPGA_M2
$338 PUDC
$339 UNNAMED_515_ISL80101IRAJZDFN10_
$340 FPGA_D00_MOSI
$341 FPGA_FLASH_DQ0_MOSI
$342 CLK_200M_OE
$343 CLK_125M_OE
$344 FPGA_D01
$345 FPGA_FLASH_DQ1_MISO
$346 XP3R3V_PG
$347 XP1R0V_RT
$348 UNNAMED_3_G2201019801_I100_EN
$349 XP1R0V_BT
$350 UNNAMED_14_RESISTOR_I65_2
$351 UART_MAC_TX_FPGA_RX
$352 RSVD_DBG_USB_MUX_SEL
$353 UNNAMED_527_RESISTOR_I206_1
$354 FPGA_OUT_SMA1_LED_RED_N
$355 FPGA_OUT_SMA2_LED_BLUE_N
$356 FPGA_OUT_SMA2_LED_GREEN_N
$357 FPGA_IN_MAC_PPS_OUTP
$358 FPGA_IN_MAC_PPS_OUTN
$359 FPGA_OUT_MAC_PPS_IN0P
$360 FPGA_OUT_MAC_PPS_IN0N
$361 FPGA_OUT_MAC_PPS_IN1P
$362 FPGA_OUT_MAC_PPS_IN1N
$363 ICP10100_I2C_SDA
$364 ICP10100_I2C_SCL
$365 FPGA_IO_2
$366 FPGA_IO_3
$367 FPGA_IN_MAC_ALARM_OUT_N
$368 FPGA_IN_MAC_BITEOUT
$369 FPGA_IN_BNO080_INT_N
$370 XP5R0V_RT
$371 BNO080_SA0
$372 R_BNO080_RST_N
$373 FPGA_IO_4
$374 R_SHT3X_RST_N
$375 FPGA_OUT_SHT3X_RST_N
$376 R_SHT3X_ALERT_N
$377 FPGA_IN_SHT3X_ALERT_N
$378 UNNAMED_9_BNO080LGA28_I29_PS1
$379 R_BNO080_BOOT_N
$380 UNNAMED_9_BNO080LGA28_I29_PS0
$381 UNNAMED_9_BNO080LGA28_I29_CLKSE
$382 FPGA_IO_5
$383 XP5R0V_BT
$384 RGB_LED_I2C_SDA
$385 RGB_LED_I2C_SCL
$386 UNNAMED_8_PCA9508DPTSSOP8_I51_E
$387 BF_ICP10100_I2C_SCL
$388 BF_ICP10100_I2C_SDA
$389 R_RGB_LED_I2C_SDA
$390 R_RGB_LED_I2C_SCL
$391 FPGA_OUT_RGB_LED_SHUTDOWN_N
$392 FPGA_M_RGB_LED_I2C_SDA
$393 FPGA_M_RGB_LED_I2C_SCL
$394 UNNAMED_14_IS32FL3207QWLA3TRQ_1
$395 UNNAMED_14_IS32FL3207QWLA3TRQFN
$396 FPGA_IO_6
$397 FPGA_IO_7
$398 R_BNO080_EVN_SDA
$399 BNO080_EVN_SDA
$400 SMA2_SIG_OUT_BF_EN_N
$401 R_LM75B_1_I2C_SDA
$402 UNNAMED_6_LM75BDPTSSOP8_I34_A2
$403 UNNAMED_6_LM75BDPTSSOP8_I34_A1
$404 UNNAMED_6_LM75BDPTSSOP8_I34_A0
$405 FPGA_D02
$406 FPGA_FLASH_DQ2
$407 FPGA_IN_LM75B_INT1_N
$408 BNO080_EVN_SCL
$409 UNNAMED_8_ICP10100LGA10_I24_RES
$410 PRI_EEPROM_SDA
$411 UNNAMED_8_ICP10100LGA10_I24_R_1
$412 UNNAMED_8_ICP10100LGA10_I24_R_2
$413 FPGA_D03
$414 FPGA_FLASH_DQ3
$415 XP3R3V_RT
$416 UNNAMED_8_ICP10100LGA10_I24_R_3
$417 UNNAMED_8_ICP10100LGA10_I24_R_4
$418 R_FT4232_CHC_RX
$419 UART_FT4232_RX_FPGA_TX
$420 R_FT4232_CHC_TX
$421 UART_FT4232_TX_FPGA_RX
$422 FPGA_OUT_I2C_BUFFER_EN
$423 BF_PCIE_PERST_N
$424 SMA1_SIG_OUT_BF_EN_N
$425 FPGA_FCS_B
$426 FPGA_FLASH_CS_N
$427 R_BNO080_EVN_SCL
$428 SMA3_SIG_OUT_BF_EN_N
$429 BF_ANT3_IN
$430 ANT3_IN
$431 SMA4_SIG_OUT_BF_EN_N
$432 XP3R3V_BT
$433 BF_ANT4_IN
$434 ANT4_IN
$435 BF_ANT1_IN
$436 ANT1_IN
$437 BF_ANT2_IN
$438 ANT2_IN
$439 FPGA_OUT_SMA2_LED_RED_N
$440 FPGA_OUT_SMA3_LED_BLUE_N
$441 FPGA_OUT_SMA3_LED_GREEN_N
$442 FPGA_OUT_SMA3_LED_RED_N
$443 SMA3_SIG_IN_BF_EN_N
$444 SMA4_SIG_IN_BF_EN_N
$445 SMA1_SIG_IN_BF_EN_N
$446 SMA2_SIG_IN_BF_EN_N
$447 SMA1_LED_BLUE_N
$448 SMA1_LED_GREEN_N
$449 SMA1_LED_RED_N
$450 SMA2_LED_BLUE_N
$451 SMA2_LED_GREEN_N
$452 SMA2_LED_RED_N
$453 SMA3_LED_BLUE_N
$454 SMA3_LED_GREEN_N
$455 SMA3_LED_RED_N
$456 SMA4_LED_BLUE_N
$457 SMA4_LED_GREEN_N
$458 SMA4_LED_RED_N
$459 GPS_SMA_LED_BLUE_N
$460 GPS_SMA_LED_GREEN_N
$461 GPS_SMA_LED_RED_N
$462 FPGA_OUT_SMA4_LED_BLUE_N
$463 FPGA_OUT_SMA4_LED_GREEN_N
$464 R_LM75B_2_I2C_SDA
$465 R_LM75B_3_I2C_SDA
$466 UNNAMED_6_LM75BDPTSSOP8_I59_A2
$467 UNNAMED_6_LM75BDPTSSOP8_I81_A2
$468 UNNAMED_6_LM75BDPTSSOP8_I59_A1
$469 UNNAMED_6_LM75BDPTSSOP8_I81_A1
$470 UNNAMED_6_LM75BDPTSSOP8_I59_A0
$471 UNNAMED_6_LM75BDPTSSOP8_I81_A0
$472 FPGA_IN_LM75B_INT2_N
$473 FPGA_IN_LM75B_INT3_N
$474 FPGA_OUT_SMA4_LED_RED_N
$475 FPGA_OUT_GPS_LED_BLUE_N
$476 FPGA_OUT_GPS_LED_GREEN_N
$477 FPGA_OUT_GPS_LED_RED_N
$478 FPGA_IO_FT_USBDET_RST_N
$479 FTDI_EE_DO
$480 FTDI_EE_CS
$481 FTDI_EE_CLK
$482 MUX1_SEL
$483 FPGA_OUT_MUX1_SEL
$484 FT4232_MUX1_SEL
$485 SEC_EEPROM_SDA
$486 FTDI_EE_DAT
$487 XP3R3V_FT_PG
$488 MUX2_SEL
$489 UNNAMED_524_RESISTOR_I432_2
$490 XP12R0V_A_ISET
$491 UNNAMED_524_FT4232HLREELQFP64_7
$492 FPGA_OUT_MUX2_SEL
$493 FT4232_MUX2_SEL
$494 UNNAMED_524_FT4232HLREELQFP64_6
$495 R_FT4232_TDO
$496 R_FT4232_TCK
$497 FT4232_TCK_SCLK
$498 R_FT4232_TDI
$499 FT4232_TDI_MOSI
$500 FT4232_TDO_MISO
$501 R_FT4232_TMS
$502 FT4232_TMS_SPICS_N
$503 R_FT4232_I2C_SCL
$504 FT4232_I2C_SCL
$505 R_FT4232_I2C_SDA_OUT
$506 FT4232_I2C_SDA
$507 R_FT4232_I2C_SDA_IN
$508 FPGA_PCA9546_I2C_SDA
$509 FPGA_PCA9546_I2C_SCL
$510 FPGA_EEPROM_I2C_SDA
$511 FPGA_EEPROM_I2C_SCL
$512 MUX3_SEL
$513 UNNAMED_524_RESISTOR_I463_2
$514 FPGA_OUT_MUX3_SEL
$515 FT4232_MUX3_SEL
$516 UNNAMED_525_ISL80101IRAJZDFN10_
$517 FPGA_IN_MAC_10MHZ_OUT
$518 PCIE_PERST_N
$519 FPGA_OUT_PCA9546_RST_N
$520 SHT3X_I2C_SDA
$521 SHT3X_I2C_SCL
$522 R_SHT3X_I2C_SDA
$523 R_SHT3X_I2C_SCL
$524 SHT3X_ADDR
$525 UNNAMED_15_MP5022CGQVZQFN22_I_2
$526 R_ICP10100_I2C_SDA
$527 R_ICP10100_I2C_SCL
$528 BNO080_I2C_SDA
$529 BNO080_I2C_SCL
$530 R_BNO080_I2C_SDA
$531 R_BNO080_I2C_SCL
$532 FPGA_OUT_BNO080_RST_N
$533 R_BNO080_INT_N
$534 UNNAMED_15_MP5022CGQVZQFN22_I21
$535 FPGA_OUT_BNO080_BOOT_N
$536 UART_MAC_RX_FPGA_TX
$537 UNNAMED_524_FT4232HLREELQFP64_5
$538 IO_L20P_34
$539 IO_L20N_34
$540 IO_L21P_34
$541 IO_L21N_34
$542 IO_L22P_34
$543 IO_L22N_34
$544 IO_L23P_34
$545 IO_L23N_34
$546 IO_L24P_34
$547 IO_L24N_34
$548 IO_L20N_16
$549 IO_L21P_16
$550 IO_L21N_16
$551 IO_L22P_16
$552 IO_L22N_16
$553 IO_L23P_16
$554 IO_L23N_16
$555 IO_L24P_16
$556 IO_L24N_16
$557 IO_L21P_35
$558 IO_L21N_35
$559 IO_L23P_35
$560 IO_L23N_35
$561 IO_L20P_35
$562 IO_L20N_35
$563 IO_L22P_35
$564 IO_L22N_35
$565 IO_L24P_35
$566 IO_L24N_35
$567 UNNAMED_524_FT4232HLREELQFP64_I
$568 UNNAMED_524_FT4232HLREELQFP64_1
$569 UNNAMED_9_BNO080LGA28_I29_HCS
$570 UNNAMED_524_FT4232HLREELQFP64_2
$571 IO_L20P_16
$572 UNNAMED_524_FT4232HLREELQFP64_3
$573 UNNAMED_524_FT4232HLREELQFP64_4
$574 FT4232_SPI_CLK
$575 FT4232_SPI_MOSI
$576 FT4232_SPI_MISO
$577 FT4232_SPI_CS_N
#
#Netlist points
#
0 0 4.00559 3.4804 T 0.017 0.024 e e staggered 0 0 0 
0 0 4.20059 3.4824 T 0.017 0.024 e e staggered 0 0 0 
0 0 1.03442 3.12 T 0.012 0.064 e e staggered 0 0 0 
0 0 1.11316 3.12 T 0.012 0.064 e e staggered 0 0 0 
0 0 1.13284 3.12 T 0.012 0.064 e e staggered 0 0 0 
0 0 1.17221 3.12 T 0.012 0.064 e e staggered 0 0 0 
0 0 1.1919 3.12 T 0.012 0.064 e e staggered 0 0 0 
0 0 1.21158 3.12 T 0.012 0.064 e e staggered 0 0 0 
0 0 1.23127 3.12 T 0.012 0.064 e e staggered 0 0 0 
0 0 1.352 3.2801 T 0.064 0.012 e e staggered 0 0 0 
0 0 1.352 3.29979 T 0.064 0.012 e e staggered 0 0 0 
0 0 1.352 3.31947 T 0.064 0.012 e e staggered 0 0 0 
0 0 1.352 3.35884 T 0.064 0.012 e e staggered 0 0 0 
0 0 1.352 3.37853 T 0.064 0.012 e e staggered 0 0 0 
0 0 1.352 3.39821 T 0.064 0.012 e e staggered 0 0 0 
0 0 1.352 3.4179 T 0.064 0.012 e e staggered 0 0 0 
0 0 1.73967 3.015 T 0.041 0.012 e e staggered 0 0 0 
0 0 5.04833 2.707 T 0.041 0.012 e e staggered 0 0 0 
0 0 5.68467 0.679 T 0.041 0.012 e e staggered 0 0 0 
0 0 3.912 3.00467 T 0.012 0.041 e e staggered 0 0 0 
0 0 4.16369 3.8969 T 0.012 0.049 e e staggered 0 0 0 
0 0 4.18337 3.8969 T 0.012 0.049 e e staggered 0 0 0 
0 0 4.20306 3.8954 T 0.012 0.046 e e staggered 0 0 0 
0 0.05 2.68567 1.12143 B e e staggered 0 0 0 
0 0.05 2.68567 2.55943 B e e staggered 0 0 0 
0 0.05 1.46067 2.68043 B e e staggered 0 0 0 
0 0.05 1.43567 1.06043 B e e staggered 0 0 0 
0 0.0625 6.40039 0.65354 B e e staggered 0 0 0 
0 0.0625 0.29528 3.73031 B e e staggered 0 0 0 
0 0.0625 0.29528 0.36811 B e e staggered 0 0 0 
0 0.0625 6.40039 4.17835 B e e staggered 0 0 0 
0 0.059 6.34055 3.34449 B e e staggered 0 0 0 
0 0.059 6.34055 3.67519 B e e staggered 0 0 0 
0 0 3.45152 2.40258 T 0.027 0.01 e e staggered 0 0 0 
0 0 3.32848 2.3829 T 0.027 0.01 e e staggered 0 0 0 
0 0 3.32848 2.36321 T 0.027 0.01 e e staggered 0 0 0 
0 0 3.32848 2.28447 T 0.027 0.01 e e staggered 0 0 0 
0 0 3.32848 2.26479 T 0.027 0.01 e e staggered 0 0 0 
0 0 3.45152 2.2451 T 0.027 0.01 e e staggered 0 0 0 
0 0 3.45152 2.26479 T 0.027 0.01 e e staggered 0 0 0 
0 0 3.45152 2.28447 T 0.027 0.01 e e staggered 0 0 0 
0 0 3.45152 2.30416 T 0.027 0.01 e e staggered 0 0 0 
0 0 3.98 0.75217 T 0.055 0.039 e e staggered 0 0 0 
0 0 4.364 0.82366 T 0.025 0.035 e e staggered 0 0 0 
0 0 2.92734 1.85026 T 0.071 0.01 e e staggered 0 0 0 
0 0 2.76986 1.83058 T 0.071 0.01 e e staggered 0 0 0 
0 0 2.92734 1.83058 T 0.071 0.01 e e staggered 0 0 0 
0 0 2.76986 1.81089 T 0.071 0.01 e e staggered 0 0 0 
0 0 2.92734 1.81089 T 0.071 0.01 e e staggered 0 0 0 
0 0 2.92734 1.79121 T 0.071 0.01 e e staggered 0 0 0 
0 0 2.92734 1.77152 T 0.071 0.01 e e staggered 0 0 0 
0 0.00985 3.89161 1.33161 T e e staggered 0 0 0 
0 0.00985 3.89161 1.8828 T e e staggered 0 0 0 
0 0.00985 3.89161 1.92217 T e e staggered 0 0 0 
0 0.00985 3.89161 2.04028 T e e staggered 0 0 0 
0 0.00985 4.67902 1.33161 T e e staggered 0 0 0 
0 0.00985 4.67902 1.41035 T e e staggered 0 0 0 
0 0.00985 4.67902 1.44973 T e e staggered 0 0 0 
0 0.00985 4.67902 1.52847 T e e staggered 0 0 0 
0 0.00985 4.67902 1.68595 T e e staggered 0 0 0 
0 0.00985 4.67902 1.72532 T e e staggered 0 0 0 
0 0.00985 4.67902 1.84343 T e e staggered 0 0 0 
0 0.00985 4.67902 1.92217 T e e staggered 0 0 0 
0 0.00985 4.67902 2.04028 T e e staggered 0 0 0 
0 0.00985 4.71839 1.33161 T e e staggered 0 0 0 
0 0.00985 4.71839 1.72532 T e e staggered 0 0 0 
0 0.00985 4.71839 1.76469 T e e staggered 0 0 0 
0 0.00985 4.71839 1.8828 T e e staggered 0 0 0 
0 0.00985 4.71839 2.07965 T e e staggered 0 0 0 
0 0.00985 4.71839 2.11902 T e e staggered 0 0 0 
0 0.00985 4.71839 2.15839 T e e staggered 0 0 0 
0 0.00985 3.93098 1.33161 T e e staggered 0 0 0 
0 0.00985 3.93098 1.37098 T e e staggered 0 0 0 
0 0.00985 3.93098 1.8828 T e e staggered 0 0 0 
0 0.00985 3.93098 1.92217 T e e staggered 0 0 0 
0 0.00985 3.93098 1.96154 T e e staggered 0 0 0 
0 0.00985 3.93098 2.00091 T e e staggered 0 0 0 
0 0.00985 3.97035 1.37098 T e e staggered 0 0 0 
0 0.00985 3.97035 2.04028 T e e staggered 0 0 0 
0 0.00985 3.97035 2.07965 T e e staggered 0 0 0 
0 0.00985 4.00973 1.33161 T e e staggered 0 0 0 
0 0.00985 4.00973 1.37098 T e e staggered 0 0 0 
0 0.00985 4.00973 1.92217 T e e staggered 0 0 0 
0 0.00985 4.00973 2.07965 T e e staggered 0 0 0 
0 0.00985 4.0491 1.33161 T e e staggered 0 0 0 
0 0.00985 4.0491 1.37098 T e e staggered 0 0 0 
0 0.00985 4.0491 1.41035 T e e staggered 0 0 0 
0 0.00985 4.0491 1.84343 T e e staggered 0 0 0 
0 0.00985 4.0491 1.92217 T e e staggered 0 0 0 
0 0.00985 4.0491 1.96154 T e e staggered 0 0 0 
0 0.00985 4.0491 2.00091 T e e staggered 0 0 0 
0 0.00985 4.08847 1.33161 T e e staggered 0 0 0 
0 0.00985 4.08847 1.41035 T e e staggered 0 0 0 
0 0.00985 4.08847 1.44973 T e e staggered 0 0 0 
0 0.00985 4.08847 1.8828 T e e staggered 0 0 0 
0 0.00985 4.08847 2.04028 T e e staggered 0 0 0 
0 0.00985 4.08847 2.07965 T e e staggered 0 0 0 
0 0.00985 4.08847 2.11902 T e e staggered 0 0 0 
0 0.00985 4.12784 1.33161 T e e staggered 0 0 0 
0 0.00985 4.12784 1.37098 T e e staggered 0 0 0 
0 0.00985 4.12784 1.41035 T e e staggered 0 0 0 
0 0.00985 4.12784 1.44973 T e e staggered 0 0 0 
0 0.00985 4.12784 1.92217 T e e staggered 0 0 0 
0 0.00985 4.12784 1.96154 T e e staggered 0 0 0 
0 0.00985 4.12784 2.00091 T e e staggered 0 0 0 
0 0.00985 4.16721 1.37098 T e e staggered 0 0 0 
0 0.00985 4.16721 1.41035 T e e staggered 0 0 0 
0 0.00985 4.16721 1.44973 T e e staggered 0 0 0 
0 0.00985 4.16721 1.4891 T e e staggered 0 0 0 
0 0.00985 4.16721 1.96154 T e e staggered 0 0 0 
0 0.00985 4.16721 2.00091 T e e staggered 0 0 0 
0 0.00985 4.20658 1.33161 T e e staggered 0 0 0 
0 0.00985 4.20658 1.37098 T e e staggered 0 0 0 
0 0.00985 4.20658 1.44973 T e e staggered 0 0 0 
0 0.00985 4.20658 1.4891 T e e staggered 0 0 0 
0 0.00985 4.20658 1.52847 T e e staggered 0 0 0 
0 0.00985 4.20658 1.92217 T e e staggered 0 0 0 
0 0.00985 4.20658 2.11902 T e e staggered 0 0 0 
0 0.00985 4.24595 1.33161 T e e staggered 0 0 0 
0 0.00985 4.24595 1.37098 T e e staggered 0 0 0 
0 0.00985 4.24595 1.41035 T e e staggered 0 0 0 
0 0.00985 4.24595 1.44973 T e e staggered 0 0 0 
0 0.00985 4.24595 1.52847 T e e staggered 0 0 0 
0 0.00985 4.24595 1.96154 T e e staggered 0 0 0 
0 0.00985 4.24595 2.00091 T e e staggered 0 0 0 
0 0.00985 4.24595 2.04028 T e e staggered 0 0 0 
0 0.00985 4.28532 1.33161 T e e staggered 0 0 0 
0 0.00985 4.28532 1.41035 T e e staggered 0 0 0 
0 0.00985 4.28532 1.44973 T e e staggered 0 0 0 
0 0.00985 4.28532 1.4891 T e e staggered 0 0 0 
0 0.00985 4.28532 1.52847 T e e staggered 0 0 0 
0 0.00985 4.28532 1.92217 T e e staggered 0 0 0 
0 0.00985 4.28532 2.00091 T e e staggered 0 0 0 
0 0.00985 4.28532 2.04028 T e e staggered 0 0 0 
0 0.00985 4.28532 2.07965 T e e staggered 0 0 0 
0 0.00985 4.32469 1.33161 T e e staggered 0 0 0 
0 0.00985 4.32469 1.37098 T e e staggered 0 0 0 
0 0.00985 4.32469 1.41035 T e e staggered 0 0 0 
0 0.00985 4.32469 1.96154 T e e staggered 0 0 0 
0 0.00985 4.32469 2.07965 T e e staggered 0 0 0 
0 0.00985 4.36406 1.41035 T e e staggered 0 0 0 
0 0.00985 4.36406 1.44973 T e e staggered 0 0 0 
0 0.00985 4.36406 1.80406 T e e staggered 0 0 0 
0 0.00985 4.36406 1.84343 T e e staggered 0 0 0 
0 0.00985 4.40343 1.96154 T e e staggered 0 0 0 
0 0.00985 4.40343 2.04028 T e e staggered 0 0 0 
0 0.00985 4.4428 1.37098 T e e staggered 0 0 0 
0 0.00985 4.4428 1.41035 T e e staggered 0 0 0 
0 0.00985 4.4428 1.52847 T e e staggered 0 0 0 
0 0.00985 4.4428 1.92217 T e e staggered 0 0 0 
0 0.00985 4.4428 1.96154 T e e staggered 0 0 0 
0 0.00985 4.4428 2.00091 T e e staggered 0 0 0 
0 0.00985 4.4428 2.04028 T e e staggered 0 0 0 
0 0.00985 4.48217 1.33161 T e e staggered 0 0 0 
0 0.00985 4.48217 1.41035 T e e staggered 0 0 0 
0 0.00985 4.48217 1.4891 T e e staggered 0 0 0 
0 0.00985 4.48217 1.52847 T e e staggered 0 0 0 
0 0.00985 4.48217 1.84343 T e e staggered 0 0 0 
0 0.00985 4.48217 1.8828 T e e staggered 0 0 0 
0 0.00985 4.48217 2.00091 T e e staggered 0 0 0 
0 0.00985 4.48217 2.07965 T e e staggered 0 0 0 
0 0.00985 4.48217 2.11902 T e e staggered 0 0 0 
0 0.00985 4.52154 1.33161 T e e staggered 0 0 0 
0 0.00985 4.52154 1.37098 T e e staggered 0 0 0 
0 0.00985 4.52154 1.41035 T e e staggered 0 0 0 
0 0.00985 4.52154 1.4891 T e e staggered 0 0 0 
0 0.00985 4.52154 1.52847 T e e staggered 0 0 0 
0 0.00985 4.52154 1.56784 T e e staggered 0 0 0 
0 0.00985 4.52154 1.8828 T e e staggered 0 0 0 
0 0.00985 4.52154 1.96154 T e e staggered 0 0 0 
0 0.00985 4.52154 2.00091 T e e staggered 0 0 0 
0 0.00985 4.52154 2.07965 T e e staggered 0 0 0 
0 0.00985 4.52154 2.11902 T e e staggered 0 0 0 
0 0.00985 4.56091 1.37098 T e e staggered 0 0 0 
0 0.00985 4.56091 1.41035 T e e staggered 0 0 0 
0 0.00985 4.56091 1.44973 T e e staggered 0 0 0 
0 0.00985 4.56091 1.4891 T e e staggered 0 0 0 
0 0.00985 4.56091 1.56784 T e e staggered 0 0 0 
0 0.00985 4.56091 1.84343 T e e staggered 0 0 0 
0 0.00985 4.56091 1.96154 T e e staggered 0 0 0 
0 0.00985 4.56091 2.00091 T e e staggered 0 0 0 
0 0.00985 4.56091 2.04028 T e e staggered 0 0 0 
0 0.00985 4.56091 2.07965 T e e staggered 0 0 0 
0 0.00985 4.56091 2.15839 T e e staggered 0 0 0 
0 0.00985 4.60028 1.37098 T e e staggered 0 0 0 
0 0.00985 4.60028 1.44973 T e e staggered 0 0 0 
0 0.00985 4.60028 1.4891 T e e staggered 0 0 0 
0 0.00985 4.60028 1.52847 T e e staggered 0 0 0 
0 0.00985 4.60028 1.56784 T e e staggered 0 0 0 
0 0.00985 4.60028 1.8828 T e e staggered 0 0 0 
0 0.00985 4.60028 1.92217 T e e staggered 0 0 0 
0 0.00985 4.60028 1.96154 T e e staggered 0 0 0 
0 0.00985 4.60028 2.11902 T e e staggered 0 0 0 
0 0.00985 4.60028 2.15839 T e e staggered 0 0 0 
0 0.00985 4.63965 1.37098 T e e staggered 0 0 0 
0 0.00985 4.63965 1.41035 T e e staggered 0 0 0 
0 0.00985 4.63965 1.44973 T e e staggered 0 0 0 
0 0.00985 4.63965 1.52847 T e e staggered 0 0 0 
0 0.00985 4.63965 1.80406 T e e staggered 0 0 0 
0 0.00985 4.63965 1.96154 T e e staggered 0 0 0 
0 0.00985 4.63965 2.04028 T e e staggered 0 0 0 
0 0.00985 4.63965 2.11902 T e e staggered 0 0 0 
0 0.00985 4.63965 2.15839 T e e staggered 0 0 0 
0 0 3.55189 1.94555 T 0.008 0.053 e e staggered 0 0 0 
0 0 3.53614 1.94555 T 0.008 0.053 e e staggered 0 0 0 
0 0 1.6622 0.74 T 0.065 0.02 e e staggered 0 0 0 
0 0 0.1975 1.0435 T 0.039 0.057 e e staggered 0 0 0 
0 0 0.1975 2.1835 T 0.039 0.057 e e staggered 0 0 0 
0 0 2.754 0.63059 T 0.038 0.013 e e staggered 0 0 0 
0 0 0.6826 3.3935 T 0.02 0.047 e e staggered 0 0 0 
0 0 0.7574 3.3935 T 0.02 0.047 e e staggered 0 0 0 
0 0 6.30729 2.31484 T 0.02 0.047 e e staggered 0 0 0 
0 0 6.23249 2.31484 T 0.02 0.047 e e staggered 0 0 0 
0 0 5.50544 2.821 T 0.14 0.05 e e staggered 0 0 0 
0 0 5.71056 2.921 T 0.14 0.05 e e staggered 0 0 0 
0 0 5.50544 2.921 T 0.14 0.05 e e staggered 0 0 0 
0 0 6.4105 2.13583 T 0.053 0.016 e e staggered 0 0 0 
0 0 2.58464 0.13781 D 0.028 0.165 e e staggered 0 0 0 
0 0 3.09645 0.13781 D 0.028 0.165 e e staggered 0 0 0 
0 0 2.1122 0.13781 T 0.028 0.165 e e staggered 0 0 0 
0 0 2.19094 0.13781 T 0.028 0.165 e e staggered 0 0 0 
0 0 2.30905 0.13781 T 0.028 0.165 e e staggered 0 0 0 
0 0 3.01771 0.13781 T 0.028 0.165 e e staggered 0 0 0 
0 0.02 1.105 4.145 T e e staggered 0 0 0 
0 0.02 5.78 1.165 T e e staggered 0 0 0 
0 0.02 0.95 0.845 T e e staggered 0 0 0 
0 0 1.7485 3.488 D 0.065 0.02 e e staggered 0 0 0 
0 0 5.7505 2.7245 D 0.039 0.057 e e staggered 0 0 0 
0 0 5.7455 3.0095 D 0.039 0.057 e e staggered 0 0 0 
0 0.015 5.372 3.963 D m e staggered 0 0 0 v t 
0 0.005 5.638 3.907 B m e staggered 0 0 0 v 
0 0.004 3.9113 1.3513 B m e staggered 0 0 0 v 
0 0.004 3.95067 1.3513 B m e staggered 0 0 0 v 
0 0.004 3.95067 2.05996 B m e staggered 0 0 0 v 
0 0.004 3.99 1.31188 B m e staggered 0 0 0 v 
0 0.004 3.99 1.35125 B m e staggered 0 0 0 v 
0 0.004 3.99005 1.94185 B m e staggered 0 0 0 v 
0 0.004 4.02942 1.39067 B m e staggered 0 0 0 v 
0 0.004 4.02942 1.86311 B m e staggered 0 0 0 v 
0 0.004 4.02942 1.94185 B m e staggered 0 0 0 v 
0 0.004 4.02942 1.98122 B m e staggered 0 0 0 v 
0 0.004 4.02942 2.02059 B m e staggered 0 0 0 v 
0 0.004 4.06874 1.31188 B m e staggered 0 0 0 v 
0 0.004 4.06879 1.39067 B m e staggered 0 0 0 v 
0 0.004 4.06879 1.43005 B m e staggered 0 0 0 v 
0 0.004 4.06879 1.90248 B m e staggered 0 0 0 v 
0 0.004 4.06879 2.05996 B m e staggered 0 0 0 v 
0 0.004 4.06879 2.1387 B m e staggered 0 0 0 v 
0 0.004 4.10811 1.31188 B m e staggered 0 0 0 v 
0 0.004 4.10816 1.3513 B m e staggered 0 0 0 v 
0 0.004 4.10816 1.39067 B m e staggered 0 0 0 v 
0 0.004 4.10816 1.43005 B m e staggered 0 0 0 v 
0 0.004 4.10816 1.94185 B m e staggered 0 0 0 v 
0 0.004 4.10816 1.98122 B m e staggered 0 0 0 v 
0 0.004 4.10816 2.02059 B m e staggered 0 0 0 v 
0 0.004 4.14753 1.3513 B m e staggered 0 0 0 v 
0 0.004 4.14753 1.39067 B m e staggered 0 0 0 v 
0 0.004 4.14753 1.43005 B m e staggered 0 0 0 v 
0 0.004 4.14753 1.46942 B m e staggered 0 0 0 v 
0 0.004 4.14753 1.98122 B m e staggered 0 0 0 v 
0 0.004 4.14753 2.02059 B m e staggered 0 0 0 v 
0 0.004 4.1869 1.31193 B m e staggered 0 0 0 v 
0 0.004 4.1869 1.3513 B m e staggered 0 0 0 v 
0 0.004 4.1869 1.43005 B m e staggered 0 0 0 v 
0 0.004 4.1869 1.46942 B m e staggered 0 0 0 v 
0 0.004 4.1869 1.94185 B m e staggered 0 0 0 v 
0 0.004 4.1869 2.1387 B m e staggered 0 0 0 v 
0 0.004 4.22627 1.31193 B m e staggered 0 0 0 v 
0 0.004 4.22627 1.3513 B m e staggered 0 0 0 v 
0 0.004 4.22627 1.39067 B m e staggered 0 0 0 v 
0 0.004 4.22627 1.43005 B m e staggered 0 0 0 v 
0 0.004 4.22627 1.98122 B m e staggered 0 0 0 v 
0 0.004 4.22627 2.02059 B m e staggered 0 0 0 v 
0 0.004 4.22627 2.05996 B m e staggered 0 0 0 v 
0 0.004 4.26564 1.31193 B m e staggered 0 0 0 v 
0 0.004 4.26564 1.39067 B m e staggered 0 0 0 v 
0 0.004 4.26564 1.50879 B m e staggered 0 0 0 v 
0 0.004 4.26564 1.94185 B m e staggered 0 0 0 v 
0 0.004 4.26564 2.02059 B m e staggered 0 0 0 v 
0 0.004 4.26564 2.05996 B m e staggered 0 0 0 v 
0 0.004 4.26564 2.09933 B m e staggered 0 0 0 v 
0 0.004 4.34437 1.31193 B m e staggered 0 0 0 v 
0 0.004 4.34437 1.3513 B m e staggered 0 0 0 v 
0 0.004 4.34437 1.39067 B m e staggered 0 0 0 v 
0 0.004 4.34437 1.98122 B m e staggered 0 0 0 v 
0 0.004 4.34437 2.09933 B m e staggered 0 0 0 v 
0 0.004 4.38374 1.82374 B m e staggered 0 0 0 v 
0 0.004 4.38374 1.86311 B m e staggered 0 0 0 v 
0 0.004 4.42311 1.98122 B m e staggered 0 0 0 v 
0 0.004 4.42311 2.05996 B m e staggered 0 0 0 v 
0 0.004 4.45939 1.35439 B m e staggered 0 0 0 v 
0 0.004 4.46248 1.39067 B m e staggered 0 0 0 v 
0 0.004 4.46248 1.50879 B m e staggered 0 0 0 v 
0 0.004 4.46248 1.94185 B m e staggered 0 0 0 v 
0 0.004 4.46248 1.98122 B m e staggered 0 0 0 v 
0 0.004 4.46248 2.02059 B m e staggered 0 0 0 v 
0 0.004 4.46248 2.05996 B m e staggered 0 0 0 v 
0 0.004 4.49876 1.31502 B m e staggered 0 0 0 v 
0 0.004 4.50185 1.39067 B m e staggered 0 0 0 v 
0 0.004 4.50185 1.46942 B m e staggered 0 0 0 v 
0 0.004 4.50185 1.86311 B m e staggered 0 0 0 v 
0 0.004 4.50185 1.90248 B m e staggered 0 0 0 v 
0 0.004 4.50185 2.02059 B m e staggered 0 0 0 v 
0 0.004 4.50185 2.09933 B m e staggered 0 0 0 v 
0 0.004 4.50185 2.1387 B m e staggered 0 0 0 v 
0 0.004 4.54122 1.31193 B m e staggered 0 0 0 v 
0 0.004 4.54122 1.3513 B m e staggered 0 0 0 v 
0 0.004 4.54122 1.39067 B m e staggered 0 0 0 v 
0 0.004 4.54122 1.46942 B m e staggered 0 0 0 v 
0 0.004 4.54122 1.50879 B m e staggered 0 0 0 v 
0 0.004 4.54122 1.54816 B m e staggered 0 0 0 v 
0 0.004 4.54122 1.90248 B m e staggered 0 0 0 v 
0 0.004 4.54122 1.98122 B m e staggered 0 0 0 v 
0 0.004 4.54122 2.02059 B m e staggered 0 0 0 v 
0 0.004 4.54122 2.09933 B m e staggered 0 0 0 v 
0 0.004 4.54122 2.1387 B m e staggered 0 0 0 v 
0 0.004 4.57844 1.35345 B m e staggered 0 0 0 v 
0 0.004 4.58059 1.39067 B m e staggered 0 0 0 v 
0 0.004 4.58059 1.43005 B m e staggered 0 0 0 v 
0 0.004 4.58059 1.46942 B m e staggered 0 0 0 v 
0 0.004 4.58059 1.54816 B m e staggered 0 0 0 v 
0 0.004 4.58059 1.86311 B m e staggered 0 0 0 v 
0 0.004 4.58059 1.98122 B m e staggered 0 0 0 v 
0 0.004 4.58059 2.02059 B m e staggered 0 0 0 v 
0 0.004 4.58059 2.05996 B m e staggered 0 0 0 v 
0 0.004 4.58059 2.09933 B m e staggered 0 0 0 v 
0 0.004 4.58059 2.17807 B m e staggered 0 0 0 v 
0 0.004 4.61996 1.3513 B m e staggered 0 0 0 v 
0 0.004 4.61996 1.43005 B m e staggered 0 0 0 v 
0 0.004 4.61996 1.46942 B m e staggered 0 0 0 v 
0 0.004 4.61996 1.50879 B m e staggered 0 0 0 v 
0 0.004 4.61996 1.54816 B m e staggered 0 0 0 v 
0 0.004 4.61996 1.90248 B m e staggered 0 0 0 v 
0 0.004 4.61996 1.94185 B m e staggered 0 0 0 v 
0 0.004 4.61996 1.98122 B m e staggered 0 0 0 v 
0 0.004 4.61996 2.1387 B m e staggered 0 0 0 v 
0 0.004 4.61996 2.17807 B m e staggered 0 0 0 v 
0 0.004 4.65933 1.3513 B m e staggered 0 0 0 v 
0 0.004 4.65933 1.39067 B m e staggered 0 0 0 v 
0 0.004 4.65933 1.43005 B m e staggered 0 0 0 v 
0 0.004 4.65933 1.50879 B m e staggered 0 0 0 v 
0 0.004 4.65933 1.82374 B m e staggered 0 0 0 v 
0 0.004 4.65933 1.98122 B m e staggered 0 0 0 v 
0 0.004 4.65933 2.05996 B m e staggered 0 0 0 v 
0 0.004 4.6987 1.31193 B m e staggered 0 0 0 v 
0 0.004 4.6987 1.39067 B m e staggered 0 0 0 v 
0 0.004 4.6987 1.43005 B m e staggered 0 0 0 v 
0 0.004 4.6987 1.50879 B m e staggered 0 0 0 v 
0 0.004 4.6987 1.66627 B m e staggered 0 0 0 v 
0 0.004 4.6987 1.70564 B m e staggered 0 0 0 v 
0 0.004 4.6987 1.86311 B m e staggered 0 0 0 v 
0 0.004 4.6987 1.94185 B m e staggered 0 0 0 v 
0 0.004 4.6987 2.05996 B m e staggered 0 0 0 v 
0 0.004 4.73807 1.31193 B m e staggered 0 0 0 v 
0 0.004 4.73807 1.70564 B m e staggered 0 0 0 v 
0 0.004 4.73807 1.78437 B m e staggered 0 0 0 v 
0 0.004 4.73807 1.90248 B m e staggered 0 0 0 v 
0 0.004 4.73807 2.09933 B m e staggered 0 0 0 v 
0 0.004 4.73807 2.1387 B m e staggered 0 0 0 v 
0 0.004 4.73807 2.17807 B m e staggered 0 0 0 v 
0 0.004 4.06879 2.09933 B m e staggered 0 0 0 v 
0 0.004 1.8317 0.5639 B m e staggered 0 0 0 v 
0 0.004 3.95067 2.09933 B m e staggered 0 0 0 v 
0 0.004 4.1869 1.50879 B m e staggered 0 0 0 v 
0 0.004 4.22627 1.50879 B m e staggered 0 0 0 v 
0 0.004 4.26564 1.46942 B m e staggered 0 0 0 v 
0 0.004 4.38374 1.39067 B m e staggered 0 0 0 v 
0 0.004 4.38374 1.43005 B m e staggered 0 0 0 v 
0 0.004 4.50185 1.50879 B m e staggered 0 0 0 v 
0 0.004 3.99005 2.09933 B m e staggered 0 0 0 v 
0 0.004 4.26564 1.43005 B m e staggered 0 0 0 v 
1 0 6.14648 1.27063 T 0.092 0.056 e e staggered 0 0 0 
1 0 5.9945 1.27063 T 0.088 0.056 e e staggered 0 0 0 
1 0 3.98 3.4056 T 0.017 0.024 e e staggered 0 0 0 
1 0 4.175 3.4076 T 0.017 0.024 e e staggered 0 0 0 
1 0 5.1245 0.91957 T 0.062 0.014 e e staggered 0 0 0 
1 0 4.4085 3.24557 T 0.062 0.014 e e staggered 0 0 0 
1 0 4.2745 3.76457 T 0.062 0.014 e e staggered 0 0 0 
1 0 0.81339 0.7085 T 0.014 0.062 e e staggered 0 0 0 
1 0 6.087 2.324 T 0.03 0.034 e e staggered 0 0 0 
1 0 3.491 2.563 T 0.034 0.03 e e staggered 0 0 0 
1 0.005 3.58 2.615 B e e staggered 0 0 0 
1 0 0.08252 1.52264 T 0.02 0.018 e e staggered 0 0 0 
1 0 0.08252 2.09351 T 0.02 0.018 e e staggered 0 0 0 
1 0 0.08252 0.95177 T 0.02 0.018 e e staggered 0 0 0 
1 0 0.08252 3.23524 T 0.02 0.018 e e staggered 0 0 0 
1 0 0.08252 2.66437 T 0.02 0.018 e e staggered 0 0 0 
1 0 4.29225 2.92521 T 0.033 0.012 e e staggered 0 0 0 
1 0 4.29225 2.90553 T 0.033 0.012 e e staggered 0 0 0 
1 0 4.29225 2.88584 T 0.033 0.012 e e staggered 0 0 0 
1 0 4.29225 2.86616 T 0.033 0.012 e e staggered 0 0 0 
1 0 4.29225 2.84647 T 0.033 0.012 e e staggered 0 0 0 
1 0 4.29225 2.82679 T 0.033 0.012 e e staggered 0 0 0 
1 0 4.2391 3.97231 T 0.049 0.012 e e staggered 0 0 0 
1 0 0.57676 2.35866 T 0.012 0.038 e e staggered 0 0 0 
1 0 0.57676 1.78779 T 0.012 0.038 e e staggered 0 0 0 
1 0 0.57676 1.21692 T 0.012 0.038 e e staggered 0 0 0 
1 0 0.57676 0.64606 T 0.012 0.038 e e staggered 0 0 0 
1 0 1.0705 0.6536 T 0.047 0.02 e e staggered 0 0 0 
1 0 1.455 3.192 T 0.034 0.03 e e staggered 0 0 0 
1 0 4.598 3.86 T 0.03 0.034 e e staggered 0 0 0 
1 0 3.481 3.235 T 0.072 0.02 e e staggered 0 0 0 
1 0.00985 3.89161 1.96154 T e e staggered 0 0 0 
1 0.00985 4.67902 1.96154 T e e staggered 0 0 0 
1 0.00985 4.71839 1.84343 T e e staggered 0 0 0 
1 0.00985 3.93098 1.84343 T e e staggered 0 0 0 
1 0.00985 3.97035 2.11902 T e e staggered 0 0 0 
1 0.00985 4.00973 2.00091 T e e staggered 0 0 0 
1 0.00985 4.0491 1.8828 T e e staggered 0 0 0 
1 0.00985 4.08847 1.76469 T e e staggered 0 0 0 
1 0.00985 4.08847 2.15839 T e e staggered 0 0 0 
1 0.00985 4.12784 2.04028 T e e staggered 0 0 0 
1 0.00985 4.16721 1.92217 T e e staggered 0 0 0 
1 0.00985 4.20658 1.80406 T e e staggered 0 0 0 
1 0.00985 4.24595 2.07965 T e e staggered 0 0 0 
1 0.00985 4.28532 1.96154 T e e staggered 0 0 0 
1 0.00985 4.32469 1.84343 T e e staggered 0 0 0 
1 0.00985 4.36406 2.11902 T e e staggered 0 0 0 
1 0.00985 4.40343 2.00091 T e e staggered 0 0 0 
1 0.00985 4.4428 1.8828 T e e staggered 0 0 0 
1 0.00985 4.48217 1.76469 T e e staggered 0 0 0 
1 0.00985 4.48217 2.15839 T e e staggered 0 0 0 
1 0.00985 4.52154 2.04028 T e e staggered 0 0 0 
1 0.00985 4.56091 1.92217 T e e staggered 0 0 0 
1 0.00985 4.60028 1.80406 T e e staggered 0 0 0 
1 0.00985 4.63965 1.68595 T e e staggered 0 0 0 
1 0.00985 4.63965 2.07965 T e e staggered 0 0 0 
1 0 4.74 2.4365 T 0.104 0.045 e e staggered 0 0 0 
1 0 3.582 2.803 T 0.024 0.028 e e staggered 0 0 0 
1 0 3.50595 1.89187 T 0.037 0.008 e e staggered 0 0 0 
1 0 1.6622 0.59 T 0.065 0.02 e e staggered 0 0 0 
1 0 2.1734 3.0845 T 0.018 0.06 e e staggered 0 0 0 
1 0 6.2655 1.0834 T 0.06 0.018 e e staggered 0 0 0 
1 0 3.124 1.645 T 0.028 0.024 e e staggered 0 0 0 
1 0 2.955 0.621 T 0.028 0.024 e e staggered 0 0 0 
1 0 2.0477 0.632 T 0.024 0.028 e e staggered 0 0 0 
1 0 3.689 2.71 T 0.028 0.024 e e staggered 0 0 0 
1 0 3.76 2.384 T 0.024 0.028 e e staggered 0 0 0 
1 0 4.426 3.7 T 0.028 0.024 e e staggered 0 0 0 
1 0 5.291 0.82 T 0.028 0.024 e e staggered 0 0 0 
1 0 5.291 0.76 T 0.028 0.024 e e staggered 0 0 0 
1 0 4.694 0.785 T 0.028 0.024 e e staggered 0 0 0 
1 0 4.694 0.865 T 0.028 0.024 e e staggered 0 0 0 
1 0 4.575 2.461 T 0.024 0.028 e e staggered 0 0 0 
1 0 4.15 2.552 T 0.024 0.028 e e staggered 0 0 0 
1 0 4.209 2.552 T 0.024 0.028 e e staggered 0 0 0 
1 0 4.093 2.552 T 0.024 0.028 e e staggered 0 0 0 
1 0 3.801 2.552 T 0.024 0.028 e e staggered 0 0 0 
1 0 3.86 2.552 T 0.024 0.028 e e staggered 0 0 0 
1 0 5.914 1.025 T 0.028 0.024 e e staggered 0 0 0 
1 0 5.956 1.125 T 0.028 0.024 e e staggered 0 0 0 
1 0 0.51452 2.233 T 0.024 0.028 e e staggered 0 0 0 
1 0 0.575 2.091 T 0.024 0.028 e e staggered 0 0 0 
1 0 0.514 1.65 T 0.028 0.024 e e staggered 0 0 0 
1 0 0.58 1.486 T 0.024 0.028 e e staggered 0 0 0 
1 0 0.505 1.0839 T 0.024 0.028 e e staggered 0 0 0 
1 0 0.58 0.926 T 0.024 0.028 e e staggered 0 0 0 
1 0 1.2157 0.7086 T 0.028 0.024 e e staggered 0 0 0 
1 0 1.2157 0.7536 T 0.028 0.024 e e staggered 0 0 0 
1 0 0.578 2.611 T 0.024 0.028 e e staggered 0 0 0 
1 0 2.083 2.931 T 0.024 0.028 e e staggered 0 0 0 
1 0 2.128 2.931 T 0.024 0.028 e e staggered 0 0 0 
1 0 2.173 2.931 T 0.024 0.028 e e staggered 0 0 0 
1 0 1.959 3.289 T 0.024 0.028 e e staggered 0 0 0 
1 0 3.159 2.434 T 0.028 0.024 e e staggered 0 0 0 
1 0 3.159 2.389 T 0.028 0.024 e e staggered 0 0 0 
1 0 4.926 2.115 T 0.028 0.024 e e staggered 0 0 0 
1 0 4.395 2.461 T 0.024 0.028 e e staggered 0 0 0 
1 0 3.201 2.209 T 0.028 0.024 e e staggered 0 0 0 
1 0 3.254 2.165 T 0.028 0.024 e e staggered 0 0 0 
1 0 5.001 1.335 T 0.028 0.024 e e staggered 0 0 0 
1 0 5.001 1.385 T 0.028 0.024 e e staggered 0 0 0 
1 0 4.926 1.765 T 0.028 0.024 e e staggered 0 0 0 
1 0 4.396 3.865 T 0.028 0.024 e e staggered 0 0 0 
1 0 4.935 3.504 T 0.024 0.028 e e staggered 0 0 0 
1 0 3.978 2.552 T 0.024 0.028 e e staggered 0 0 0 
1 0 3.919 2.552 T 0.024 0.028 e e staggered 0 0 0 
1 0 6.421 1.08 T 0.028 0.024 e e staggered 0 0 0 
1 0 6.421 1.02 T 0.028 0.024 e e staggered 0 0 0 
1 0 6.421 0.965 T 0.028 0.024 e e staggered 0 0 0 
1 0 5.914 0.965 T 0.028 0.024 e e staggered 0 0 0 
1 0 5.89953 2.239 T 0.028 0.024 e e staggered 0 0 0 
1 0 5.96902 1.90865 T 0.024 0.028 e e staggered 0 0 0 
1 0 4.037 2.552 T 0.024 0.028 e e staggered 0 0 0 
1 0 3.335 2.553 T 0.024 0.028 e e staggered 0 0 0 
1 0 4.2 2.936 T 0.038 0.054 e e staggered 0 0 0 
1 0 4.2 2.855 T 0.038 0.054 e e staggered 0 0 0 
1 0 2.9552 0.6678 T 0.028 0.024 e e staggered 0 0 0 
1 0 4.509 3.27 T 0.028 0.024 e e staggered 0 0 0 
1 0 0.64 2.271 T 0.024 0.028 e e staggered 0 0 0 
1 0 0.606 1.68945 T 0.024 0.028 e e staggered 0 0 0 
1 0 0.625 1.126 T 0.024 0.028 e e staggered 0 0 0 
1 0 1.1737 0.6136 T 0.028 0.024 e e staggered 0 0 0 
1 0 1.548 0.6212 T 0.024 0.028 e e staggered 0 0 0 
1 0 2.218 2.973 T 0.024 0.028 e e staggered 0 0 0 
1 0 5.249 0.92 T 0.028 0.024 e e staggered 0 0 0 
1 0 4.187 2.792 T 0.028 0.024 e e staggered 0 0 0 
1 0 4.354 3.965 T 0.028 0.024 e e staggered 0 0 0 
1 0 3.582 2.856 T 0.024 0.028 e e staggered 0 0 0 
1 0 4.53 3.849 T 0.024 0.028 e e staggered 0 0 0 
1 0 4.384 3.79 T 0.028 0.024 e e staggered 0 0 0 
1 0 6.379 1.135 T 0.028 0.024 e e staggered 0 0 0 
1 0 6.141 2.32 T 0.024 0.028 e e staggered 0 0 0 
1 0 3.546 2.555 T 0.024 0.028 e e staggered 0 0 0 
1 0 2.848 0.63059 T 0.038 0.013 e e staggered 0 0 0 
1 0 3.695 2.5135 T 0.02 0.047 e e staggered 0 0 0 
1 0 3.7324 2.5135 T 0.02 0.047 e e staggered 0 0 0 
1 0.0125 4.60028 1.84343 D e e staggered 0 0 0 
1 0.0125 3.93098 1.84343 D e e staggered 0 0 0 
1 0.0125 4.71839 2.00091 D e e staggered 0 0 0 
1 0.0125 3.93098 2.15839 D e e staggered 0 0 0 
1 0.0125 3.93098 2.11902 D e e staggered 0 0 0 
1 0.0125 3.97035 2.04028 D e e staggered 0 0 0 
1 0.0125 3.97036 2.00091 D e e staggered 0 0 0 
1 0.0125 4.12784 2.04028 D e e staggered 0 0 0 
1 0.0125 4.12784 1.96154 D e e staggered 0 0 0 
1 0.0125 4.16721 1.96154 D e e staggered 0 0 0 
1 0.0125 4.24595 2.11902 D e e staggered 0 0 0 
1 0.0125 4.31006 1.8978 D e e staggered 0 0 0 
1 0.0125 4.20658 1.84343 D e e staggered 0 0 0 
1 0.0125 4.52154 1.80406 D e e staggered 0 0 0 
1 0.0125 4.63965 1.80406 D e e staggered 0 0 0 
1 0.0125 4.63965 1.68595 D e e staggered 0 0 0 
1 0.0125 4.4428 1.92217 D e e staggered 0 0 0 
1 0.0125 4.48216 1.92216 D e e staggered 0 0 0 
1 0.0125 4.63965 1.84343 D e e staggered 0 0 0 
1 0.0125 4.60028 1.92217 D e e staggered 0 0 0 
1 0.0125 4.52154 2.07965 D e e staggered 0 0 0 
1 0.0125 4.40343 2.15839 D e e staggered 0 0 0 
1 0.0125 4.60028 1.96154 D e e staggered 0 0 0 
1 0.0125 4.00973 1.92217 D e e staggered 0 0 0 
1 0.0125 4.0491 1.92217 D e e staggered 0 0 0 
1 0.0125 4.67902 2.11902 D e e staggered 0 0 0 
1 0 4.0875 2.325 D 0.045 0.104 e e staggered 0 0 0 
1 0 4.066 2.215 D 0.028 0.024 e e staggered 0 0 0 
1 0 4.49685 2.22 D 0.028 0.024 e e staggered 0 0 0 
1 0 0.3695 3.0284 D 0.06 0.018 e e staggered 0 0 0 
1 0 4.694 0.965 D 0.028 0.024 e e staggered 0 0 0 
1 0 3.973 3.291 D 0.028 0.024 e e staggered 0 0 0 
1 0 3.839 3.81 D 0.028 0.024 e e staggered 0 0 0 
1 0 3.068 3.26 D 0.028 0.024 e e staggered 0 0 0 
1 0 4.324 2.975 D 0.028 0.024 e e staggered 0 0 0 
1 0 0.85 1.549 D 0.028 0.024 e e staggered 0 0 0 
1 0 0.741 2.915 D 0.028 0.024 e e staggered 0 0 0 
1 0 0.577 0.697 D 0.024 0.028 e e staggered 0 0 0 
1 0 0.199 2.925 D 0.028 0.024 e e staggered 0 0 0 
1 0 0.335 2.829 D 0.024 0.028 e e staggered 0 0 0 
1 0 0.199 2.975 D 0.028 0.024 e e staggered 0 0 0 
1 0 0.85 2.402 D 0.024 0.028 e e staggered 0 0 0 
1 0 0.896 2.402 D 0.024 0.028 e e staggered 0 0 0 
1 0 1.1738 0.6587 D 0.028 0.024 e e staggered 0 0 0 
1 0 0.715 2.402 D 0.024 0.028 e e staggered 0 0 0 
1 0 0.85 1.639 D 0.028 0.024 e e staggered 0 0 0 
1 0 0.851 0.665 D 0.028 0.024 e e staggered 0 0 0 
1 0 4.884 2.025 D 0.028 0.024 e e staggered 0 0 0 
1 0 4.926 1.765 D 0.028 0.024 e e staggered 0 0 0 
1 0 4.926 1.975 D 0.028 0.024 e e staggered 0 0 0 
1 0 4.53 2.461 D 0.024 0.028 e e staggered 0 0 0 
1 0 3.371 2.255 D 0.028 0.024 e e staggered 0 0 0 
1 0 3.419 2.255 D 0.028 0.024 e e staggered 0 0 0 
1 0 2.509 2.375 D 0.028 0.024 e e staggered 0 0 0 
1 0 5.555 0.608 D 0.024 0.028 e e staggered 0 0 0 
1 0 4.926 1.63 D 0.028 0.024 e e staggered 0 0 0 
1 0 3.395 2.864 D 0.024 0.028 e e staggered 0 0 0 
1 0 4.575 2.461 D 0.024 0.028 e e staggered 0 0 0 
1 0 4.395 2.461 D 0.024 0.028 e e staggered 0 0 0 
1 0 3.256 3.205 D 0.028 0.024 e e staggered 0 0 0 
1 0 3.256 3.385 D 0.028 0.024 e e staggered 0 0 0 
1 0 3.256 3.34 D 0.028 0.024 e e staggered 0 0 0 
1 0 3.068 3.35 D 0.028 0.024 e e staggered 0 0 0 
1 0 3.744 3.37 D 0.028 0.024 e e staggered 0 0 0 
1 0 3.744 3.28 D 0.028 0.024 e e staggered 0 0 0 
1 0 3.744 3.235 D 0.028 0.024 e e staggered 0 0 0 
1 0 3.506 3.28 D 0.028 0.024 e e staggered 0 0 0 
1 0 3.506 3.37 D 0.028 0.024 e e staggered 0 0 0 
1 0 3.485 2.906 D 0.024 0.028 e e staggered 0 0 0 
1 0 4.989 3.455 D 0.028 0.024 e e staggered 0 0 0 
1 0 4.224 4.115 D 0.028 0.024 e e staggered 0 0 0 
1 0 4.224 4.065 D 0.028 0.024 e e staggered 0 0 0 
1 0 5.544 2.721 D 0.028 0.024 e e staggered 0 0 0 
1 0 5.452 2.813 D 0.024 0.028 e e staggered 0 0 0 
1 0 5.273 4.20101 D 0.024 0.028 e e staggered 0 0 0 
1 0 5.435 4.219 D 0.024 0.028 e e staggered 0 0 0 
1 0 1.309 0.753 D 0.028 0.024 e e staggered 0 0 0 
1 0 5.452 3.061 D 0.024 0.028 e e staggered 0 0 0 
1 0 5.452 2.9645 D 0.024 0.028 e e staggered 0 0 0 
1 0 6.027 4.219 D 0.024 0.028 e e staggered 0 0 0 
1 0 6.14 4.219 D 0.024 0.028 e e staggered 0 0 0 
1 0 0.788 0.911 D 0.024 0.028 e e staggered 0 0 0 
1 0 5.555 4.219 D 0.024 0.028 e e staggered 0 0 0 
1 0 5.67 4.219 D 0.024 0.028 e e staggered 0 0 0 
1 0 5.435 4.166 D 0.024 0.028 e e staggered 0 0 0 
1 0 0.743 0.911 D 0.024 0.028 e e staggered 0 0 0 
1 0 5.79 4.219 D 0.024 0.028 e e staggered 0 0 0 
1 0 6.01902 1.95065 D 0.024 0.028 e e staggered 0 0 0 
1 0 6.06902 1.95065 D 0.024 0.028 e e staggered 0 0 0 
1 0 5.91902 1.90865 D 0.024 0.028 e e staggered 0 0 0 
1 0 4.2 2.855 D 0.038 0.054 e e staggered 0 0 0 
1 0 4.2 2.936 D 0.038 0.054 e e staggered 0 0 0 
1 0 3.505 1.831 D 0.024 0.028 e e staggered 0 0 0 
1 0 3.98 3.429 D 0.024 0.028 e e staggered 0 0 0 
1 0 4.17 3.429 D 0.024 0.028 e e staggered 0 0 0 
1 0 0.241 3.075 D 0.028 0.024 e e staggered 0 0 0 
1 0 0.635 0.615 D 0.028 0.024 e e staggered 0 0 0 
1 0 0.86 0.791 D 0.024 0.028 e e staggered 0 0 0 
1 0 4.78 1.86311 D 0.024 0.028 e e staggered 0 0 0 
1 0 2.461 2.355 D 0.028 0.024 e e staggered 0 0 0 
1 0 4.3 1.987 D 0.024 0.028 e e staggered 0 0 0 
1 0 4.306 1.837 D 0.024 0.028 e e staggered 0 0 0 
1 0 4.51311 1.755 D 0.028 0.024 e e staggered 0 0 0 
1 0 4.354 3.965 D 0.028 0.024 e e staggered 0 0 0 
1 0 2.46559 2.287 D 0.013 0.038 e e staggered 0 0 0 
1 0.005 1.1133 0.5981 B m e staggered 0 0 0 v 
1 0.005 0.11264 1.52264 B m e staggered 0 0 0 v 
1 0.005 0.11963 2.66437 B m e staggered 0 0 0 v 
1 0.005 0.11976 3.23524 B m e staggered 0 0 0 v 
1 0.005 0.125 2.095 B m e staggered 0 0 0 v 
1 0.005 0.125 0.96 B m e staggered 0 0 0 v 
1 0.005 1.25 0.765 B m e staggered 0 0 0 v 
1 0.005 1.401 3.069 B m e staggered 0 0 0 v 
1 0.005 1.5327 0.584 B m e staggered 0 0 0 v 
1 0.005 0.16 2.975 B m e staggered 0 0 0 v 
1 0.005 1.605 0.715 B m e staggered 0 0 0 v 
1 0.005 1.605 0.755 B m e staggered 0 0 0 v 
1 0.005 1.826 2.895 B m e staggered 0 0 0 v 
1 0.005 1.959 3.325 B m e staggered 0 0 0 v 
1 0.005 2.0477 0.6778 B m e staggered 0 0 0 v 
1 0.005 2.285 0.755 B m e staggered 0 0 0 v 
1 0.005 2.285 0.79 B m e staggered 0 0 0 v 
1 0.005 0.241 3.109 B m e staggered 0 0 0 v 
1 0.005 2.49 2.903 B m e staggered 0 0 0 v 
1 0.005 2.964 0.702 B m e staggered 0 0 0 v 
1 0.005 3.09 1.645 B m e staggered 0 0 0 v 
1 0.005 3.106 3.26 B m e staggered 0 0 0 v 
1 0.005 3.119 2.434 B m e staggered 0 0 0 v 
1 0.005 3.24 2.2075 B m e staggered 0 0 0 v 
1 0.005 3.335 2.589 B m e staggered 0 0 0 v 
1 0.005 3.395 2.82 B m e staggered 0 0 0 v 
1 0.005 3.41 3.04 B m e staggered 0 0 0 v 
1 0.005 3.414 3.235 B m e staggered 0 0 0 v 
1 0.005 3.485 2.6 B m e staggered 0 0 0 v 
1 0.005 3.49 2.955 B m e staggered 0 0 0 v 
1 0.005 3.49128 1.86628 B m e staggered 0 0 0 v 
1 0.005 3.525 2.6 B m e staggered 0 0 0 v 
1 0.005 3.55 3.37 B m e staggered 0 0 0 v 
1 0.005 3.5768 2.7178 B m e staggered 0 0 0 v 
1 0.005 3.7 3.37 B m e staggered 0 0 0 v 
1 0.005 3.71 3.26 B m e staggered 0 0 0 v 
1 0.005 3.735 2.47 B m e staggered 0 0 0 v 
1 0.005 0.374 2.829 B m e staggered 0 0 0 v 
1 0.005 3.758 2.552 B m e staggered 0 0 0 v 
1 0.005 3.795 2.375 B m e staggered 0 0 0 v 
1 0.005 3.839 3.846 B m e staggered 0 0 0 v 
1 0.005 3.86 2.5925 B m e staggered 0 0 0 v 
1 0.005 3.98 3.365 B m e staggered 0 0 0 v 
1 0.005 4.075 2.25 B m e staggered 0 0 0 v 
1 0.005 4.175 3.37 B m e staggered 0 0 0 v 
1 0.005 4.209 2.59 B m e staggered 0 0 0 v 
1 0.005 4.235 4.155 B m e staggered 0 0 0 v 
1 0.005 4.384 3.824 B m e staggered 0 0 0 v 
1 0.005 4.395 2.5 B m e staggered 0 0 0 v 
1 0.005 4.505 3.685 B m e staggered 0 0 0 v 
1 0.005 4.509 3.309 B m e staggered 0 0 0 v 
1 0.005 4.535 3.815 B m e staggered 0 0 0 v 
1 0.005 4.575 2.5 B m e staggered 0 0 0 v 
1 0.005 4.61 3.025 B m e staggered 0 0 0 v 
1 0.005 4.635 0.92 B m e staggered 0 0 0 v 
1 0.005 4.645 2.985 B m e staggered 0 0 0 v 
1 0.005 4.655 0.785 B m e staggered 0 0 0 v 
1 0.005 4.71 2.39 B m e staggered 0 0 0 v 
1 0.005 4.77 2.39 B m e staggered 0 0 0 v 
1 0.005 4.85 2.02739 B m e staggered 0 0 0 v 
1 0.005 4.905 2.1675 B m e staggered 0 0 0 v 
1 0.005 4.95 3.46 B m e staggered 0 0 0 v 
1 0.005 4.96 1.63 B m e staggered 0 0 0 v 
1 0.005 4.965 1.975 B m e staggered 0 0 0 v 
1 0.005 5.0395 1.335 B m e staggered 0 0 0 v 
1 0.005 0.505 1.048 B m e staggered 0 0 0 v 
1 0.005 0.514 1.616 B m e staggered 0 0 0 v 
1 0.005 0.51452 2.199 B m e staggered 0 0 0 v 
1 0.005 5.19 3.075 B m e staggered 0 0 0 v 
1 0.005 5.221 4.165 B m e staggered 0 0 0 v 
1 0.005 5.249 0.99 B m e staggered 0 0 0 v 
1 0.005 5.265 0.675 B m e staggered 0 0 0 v 
1 0.005 5.33 0.82 B m e staggered 0 0 0 v 
1 0.005 5.375 3.04 B m e staggered 0 0 0 v 
1 0.005 5.41 2.815 B m e staggered 0 0 0 v 
1 0.005 5.42 2.9645 B m e staggered 0 0 0 v 
1 0.005 0.5459 2.6687 B m e staggered 0 0 0 v 
1 0.005 5.515 0.59597 B m e staggered 0 0 0 v 
1 0.005 5.53 1.085 B m e staggered 0 0 0 v 
1 0.005 5.544 2.675 B m e staggered 0 0 0 v 
1 0.005 5.62 2.5487 B m e staggered 0 0 0 v 
1 0.005 0.58 2.135 B m e staggered 0 0 0 v 
1 0.005 5.84 4.219 B m e staggered 0 0 0 v 
1 0.005 5.85 2.265 B m e staggered 0 0 0 v 
1 0.005 5.88 0.965 B m e staggered 0 0 0 v 
1 0.005 5.92 1.27063 B m e staggered 0 0 0 v 
1 0.005 5.94003 1.87 B m e staggered 0 0 0 v 
1 0.005 0.596 0.602 B m e staggered 0 0 0 v 
1 0.005 5.975 4.219 B m e staggered 0 0 0 v 
1 0.005 5.995 1.165 B m e staggered 0 0 0 v 
1 0.005 0.601 0.73 B m e staggered 0 0 0 v 
1 0.005 0.605 1.52 B m e staggered 0 0 0 v 
1 0.005 6.105 1.905 B m e staggered 0 0 0 v 
1 0.005 6.141 2.364 B m e staggered 0 0 0 v 
1 0.005 6.145 3.98 B m e staggered 0 0 0 v 
1 0.005 6.1865 2.493 B m e staggered 0 0 0 v 
1 0.005 6.22 1.27063 B m e staggered 0 0 0 v 
1 0.005 0.625 1.17 B m e staggered 0 0 0 v 
1 0.005 6.379 1.169 B m e staggered 0 0 0 v 
1 0.005 0.64445 1.68945 B m e staggered 0 0 0 v 
1 0.005 6.47 1.08 B m e staggered 0 0 0 v 
1 0.005 0.674 2.271 B m e staggered 0 0 0 v 
1 0.005 0.677 2.402 B m e staggered 0 0 0 v 
1 0.005 0.764 0.872 B m e staggered 0 0 0 v 
1 0.005 0.78 2.915 B m e staggered 0 0 0 v 
1 0.005 0.821 0.793 B m e staggered 0 0 0 v 
1 0.005 0.857 2.365 B m e staggered 0 0 0 v 
1 0.005 0.86 0.631 B m e staggered 0 0 0 v 
1 0.005 0.884 1.549 B m e staggered 0 0 0 v 
1 0.005 4.239 2.785 B m e staggered 0 0 0 v 
1 0.005 4.249 2.843 B m e staggered 0 0 0 v 
1 0.005 4.249 2.929 B m e staggered 0 0 0 v 
1 0.005 4.97 1.75 B m e staggered 0 0 0 v 
1 0.005 0.59 0.965 B m e staggered 0 0 0 v 
1 0.004 2.128 2.895 B m e staggered 0 0 0 v 
1 0.004 2.245 3.02 B m e staggered 0 0 0 v 
1 0.004 3.106 3.35 B m e staggered 0 0 0 v 
1 0.004 3.222 3.205 B m e staggered 0 0 0 v 
1 0.004 3.222 3.385 B m e staggered 0 0 0 v 
1 0.004 3.548 2.856 B m e staggered 0 0 0 v 
1 0.004 3.55 3.28 B m e staggered 0 0 0 v 
1 0.004 4.32 3.965 B m e staggered 0 0 0 v 
1 0.004 4.43 3.865 B m e staggered 0 0 0 v 
1 0.004 0.883 1.639 B m e staggered 0 0 0 v 
1 0.004 3.855 1.96154 B m e staggered 0 0 0 v 
1 0.004 3.9113 1.86311 B m e staggered 0 0 0 v 
1 0.004 3.95067 2.1387 B m e staggered 0 0 0 v 
1 0.004 3.99005 2.02059 B m e staggered 0 0 0 v 
1 0.004 4.02942 1.90248 B m e staggered 0 0 0 v 
1 0.004 4.06879 1.78437 B m e staggered 0 0 0 v 
1 0.004 4.06879 2.17807 B m e staggered 0 0 0 v 
1 0.004 4.10816 2.05996 B m e staggered 0 0 0 v 
1 0.004 4.14753 1.94185 B m e staggered 0 0 0 v 
1 0.004 4.1869 1.82374 B m e staggered 0 0 0 v 
1 0.004 4.22627 2.09933 B m e staggered 0 0 0 v 
1 0.004 4.26564 1.98122 B m e staggered 0 0 0 v 
1 0.004 4.34437 1.86311 B m e staggered 0 0 0 v 
1 0.004 4.38374 2.1387 B m e staggered 0 0 0 v 
1 0.004 4.42311 2.02059 B m e staggered 0 0 0 v 
1 0.004 4.46248 1.90248 B m e staggered 0 0 0 v 
1 0.004 4.50185 1.78437 B m e staggered 0 0 0 v 
1 0.004 4.50185 2.17807 B m e staggered 0 0 0 v 
1 0.004 4.54122 2.05996 B m e staggered 0 0 0 v 
1 0.004 4.58059 1.94185 B m e staggered 0 0 0 v 
1 0.004 4.61996 1.82374 B m e staggered 0 0 0 v 
1 0.004 4.65933 1.66627 B m e staggered 0 0 0 v 
1 0.004 4.65933 2.09933 B m e staggered 0 0 0 v 
1 0.004 4.6987 1.98122 B m e staggered 0 0 0 v 
1 0.004 4.73807 1.86311 B m e staggered 0 0 0 v 
2 0 6.14648 1.37063 T 0.092 0.056 e e staggered 0 0 0 
2 0 5.9945 1.37063 T 0.088 0.056 e e staggered 0 0 0 
2 0.008 0.24606 3.4315 B e e staggered 0 0 0 
2 0.008 0.4587 3.4315 B e e staggered 0 0 0 
2 0.008 0.44098 3.4008 B e e staggered 0 0 0 
2 0.008 0.22834 3.4008 B e e staggered 0 0 0 
2 0.012 0.43705 3.51576 B e e staggered 0 0 0 
2 0.012 0.43705 3.31655 B e e staggered 0 0 0 
2 0.012 0.24807 3.47245 B e e staggered 0 0 0 
2 0.012 0.24807 3.35985 B e e staggered 0 0 0 
2 0 3.98 3.4804 T 0.017 0.024 e e staggered 0 0 0 
2 0 4.175 3.4824 T 0.017 0.024 e e staggered 0 0 0 
2 0 4.8855 0.74043 T 0.062 0.014 e e staggered 0 0 0 
2 0 4.1695 3.06643 T 0.062 0.014 e e staggered 0 0 0 
2 0 4.0355 3.58543 T 0.062 0.014 e e staggered 0 0 0 
2 0 0.73662 0.9475 T 0.014 0.062 e e staggered 0 0 0 
2 0 1.27064 3.578 T 0.012 0.064 e e staggered 0 0 0 
2 0 1.1919 3.578 T 0.012 0.064 e e staggered 0 0 0 
2 0 1.09347 3.578 T 0.012 0.064 e e staggered 0 0 0 
2 0 1.07379 3.578 T 0.012 0.064 e e staggered 0 0 0 
2 0 1.03442 3.578 T 0.012 0.064 e e staggered 0 0 0 
2 0 0.99505 3.578 T 0.012 0.064 e e staggered 0 0 0 
2 0 0.894 3.33916 T 0.064 0.012 e e staggered 0 0 0 
2 0 1.01473 3.12 T 0.012 0.064 e e staggered 0 0 0 
2 0 1.25095 3.12 T 0.012 0.064 e e staggered 0 0 0 
2 0 1.352 3.24073 T 0.064 0.012 e e staggered 0 0 0 
2 0 4.472 3.5315 T 0.039 0.055 e e staggered 0 0 0 
2 0 3.23744 2.765 T 0.14 0.05 e e staggered 0 0 0 
2 0 3.23744 2.865 T 0.14 0.05 e e staggered 0 0 0 
2 0.0315 0.06039 1.38346 B e e staggered 0 0 0 
2 0.0315 0.26039 1.38346 B e e staggered 0 0 0 
2 0.0315 0.06039 1.18346 B e e staggered 0 0 0 
2 0.0315 0.26039 1.18346 B e e staggered 0 0 0 
2 0.0315 0.06039 0.8126 B e e staggered 0 0 0 
2 0.0315 0.26039 0.8126 B e e staggered 0 0 0 
2 0.0315 0.06039 0.6126 B e e staggered 0 0 0 
2 0.0315 0.26039 0.6126 B e e staggered 0 0 0 
2 0.0315 0.06039 2.5252 B e e staggered 0 0 0 
2 0.0315 0.26039 2.5252 B e e staggered 0 0 0 
2 0.0315 0.06039 2.3252 B e e staggered 0 0 0 
2 0.0315 0.26039 2.3252 B e e staggered 0 0 0 
2 0.0315 0.06039 1.95433 B e e staggered 0 0 0 
2 0.0315 0.26039 1.95433 B e e staggered 0 0 0 
2 0.0315 0.06039 1.75433 B e e staggered 0 0 0 
2 0.0315 0.26039 1.75433 B e e staggered 0 0 0 
2 0.0059999 1.62033 2.9756199 T e e staggered 0 0 0 
2 0 1.68 3.015 T 0.057 0.071 e e staggered 0 0 0 
2 0.0059999 5.16767 2.7463801 T e e staggered 0 0 0 
2 0 5.108 2.707 T 0.057 0.071 e e staggered 0 0 0 
2 0.0059999 5.56533 0.6396199 T e e staggered 0 0 0 
2 0 5.625 0.679 T 0.057 0.071 e e staggered 0 0 0 
2 0.0059999 3.9513801 2.88533 T e e staggered 0 0 0 
2 0 3.912 2.945 T 0.071 0.057 e e staggered 0 0 0 
2 0 4.41975 2.88584 T 0.033 0.012 e e staggered 0 0 0 
2 0 4.2391 3.992 T 0.049 0.012 e e staggered 0 0 0 
2 0 4.144 4.0871 T 0.012 0.049 e e staggered 0 0 0 
2 0 4.0489 3.992 T 0.049 0.012 e e staggered 0 0 0 
2 0 4.144 3.8969 T 0.012 0.049 e e staggered 0 0 0 
2 0 4.144 3.992 T 0.115 0.115 e e staggered 0 0 0 
2 0 0.51772 2.49174 T 0.012 0.038 e e staggered 0 0 0 
2 0 0.51772 1.92087 T 0.012 0.038 e e staggered 0 0 0 
2 0 0.51772 1.35 T 0.012 0.038 e e staggered 0 0 0 
2 0 0.51772 0.77914 T 0.012 0.038 e e staggered 0 0 0 
2 0.006 6.40039 0.75004 B e e staggered 0 0 0 
2 0.006 6.46863 0.72178 B e e staggered 0 0 0 
2 0.006 6.49689 0.65354 B e e staggered 0 0 0 
2 0.006 6.46863 0.5853 B e e staggered 0 0 0 
2 0.006 6.40039 0.55704 B e e staggered 0 0 0 
2 0.006 6.33215 0.5853 B e e staggered 0 0 0 
2 0.006 6.30389 0.65354 B e e staggered 0 0 0 
2 0.006 6.33215 0.72178 B e e staggered 0 0 0 
2 0.006 0.29528 3.82681 B e e staggered 0 0 0 
2 0.006 0.36352 3.79855 B e e staggered 0 0 0 
2 0.006 0.39178 3.73031 B e e staggered 0 0 0 
2 0.006 0.36352 3.66207 B e e staggered 0 0 0 
2 0.006 0.29528 3.63381 B e e staggered 0 0 0 
2 0.006 0.22704 3.66207 B e e staggered 0 0 0 
2 0.006 0.19878 3.73031 B e e staggered 0 0 0 
2 0.006 0.22704 3.79855 B e e staggered 0 0 0 
2 0.006 0.29528 0.46461 B e e staggered 0 0 0 
2 0.006 0.36352 0.43635 B e e staggered 0 0 0 
2 0.006 0.39178 0.36811 B e e staggered 0 0 0 
2 0.006 0.36352 0.29987 B e e staggered 0 0 0 
2 0.006 0.29528 0.27161 B e e staggered 0 0 0 
2 0.006 0.22704 0.29987 B e e staggered 0 0 0 
2 0.006 0.19878 0.36811 B e e staggered 0 0 0 
2 0.006 0.22704 0.43635 B e e staggered 0 0 0 
2 0.006 6.40039 4.27485 B e e staggered 0 0 0 
2 0.006 6.46863 4.24659 B e e staggered 0 0 0 
2 0.006 6.49689 4.17835 B e e staggered 0 0 0 
2 0.006 6.46863 4.11011 B e e staggered 0 0 0 
2 0.006 6.40039 4.08185 B e e staggered 0 0 0 
2 0.006 6.33215 4.11011 B e e staggered 0 0 0 
2 0.006 6.30389 4.17835 B e e staggered 0 0 0 
2 0.006 6.33215 4.24659 B e e staggered 0 0 0 
2 0 0.9575 0.691 T 0.047 0.02 e e staggered 0 0 0 
2 0.0395 2.86067 1.04043 B e e staggered 0 0 0 
2 0.0395 1.26067 1.84043 B e e staggered 0 0 0 
2 0 5.98016 2.14382 T 0.012 0.041 e e staggered 0 0 0 
2 0 5.96047 2.14382 T 0.012 0.041 e e staggered 0 0 0 
2 0 5.99 2.094 T 0.071 0.039 e e staggered 0 0 0 
2 0.038 5.88779 3.67519 B e e staggered 0 0 0 
2 0.038 5.88779 3.50984 B e e staggered 0 0 0 
2 0.038 5.88779 3.34449 B e e staggered 0 0 0 
2 0.083 4.94094 4.12008 B e e staggered 0 0 0 
2 0.083 4.94094 3.09646 B e e staggered 0 0 0 
2 0.083 2.55906 4.12008 B e e staggered 0 0 0 
2 0.083 2.55906 3.09646 B e e staggered 0 0 0 
2 0 0.81999 2.64131 T 0.014 0.011 e e staggered 0 0 0 
2 0 0.81999 2.661 T 0.014 0.011 e e staggered 0 0 0 
2 0 3.41953 2.40504 T 0.01 0.023 e e staggered 0 0 0 
2 0 3.45152 2.32384 T 0.027 0.01 e e staggered 0 0 0 
2 0 4.08 0.75217 T 0.055 0.039 e e staggered 0 0 0 
2 0 4.414 0.82366 T 0.025 0.035 e e staggered 0 0 0 
2 0 4.78656 3.67205 T 0.088 0.04 e e staggered 0 0 0 
2 0 3.769 3.385 T 0.072 0.02 e e staggered 0 0 0 
2 0 2.92734 1.86995 T 0.071 0.01 e e staggered 0 0 0 
2 0 2.76986 1.85026 T 0.071 0.01 e e staggered 0 0 0 
2 0 2.76986 1.79121 T 0.071 0.01 e e staggered 0 0 0 
2 0.00985 3.89161 1.37098 T e e staggered 0 0 0 
2 0.00985 3.89161 1.41035 T e e staggered 0 0 0 
2 0.00985 3.89161 1.4891 T e e staggered 0 0 0 
2 0.00985 3.89161 1.56784 T e e staggered 0 0 0 
2 0.00985 3.89161 1.64658 T e e staggered 0 0 0 
2 0.00985 3.89161 1.72532 T e e staggered 0 0 0 
2 0.00985 3.89161 1.76469 T e e staggered 0 0 0 
2 0.00985 3.89161 2.15839 T e e staggered 0 0 0 
2 0.00985 4.67902 1.37098 T e e staggered 0 0 0 
2 0.00985 4.67902 1.76469 T e e staggered 0 0 0 
2 0.00985 4.67902 2.15839 T e e staggered 0 0 0 
2 0.00985 4.71839 1.64658 T e e staggered 0 0 0 
2 0.00985 4.71839 2.04028 T e e staggered 0 0 0 
2 0.00985 3.93098 1.41035 T e e staggered 0 0 0 
2 0.00985 3.93098 1.76469 T e e staggered 0 0 0 
2 0.00985 3.93098 2.04028 T e e staggered 0 0 0 
2 0.00985 3.97035 1.41035 T e e staggered 0 0 0 
2 0.00985 3.97035 1.52847 T e e staggered 0 0 0 
2 0.00985 3.97035 1.68595 T e e staggered 0 0 0 
2 0.00985 3.97035 1.76469 T e e staggered 0 0 0 
2 0.00985 3.97035 1.92217 T e e staggered 0 0 0 
2 0.00985 4.00973 1.41035 T e e staggered 0 0 0 
2 0.00985 4.00973 1.44973 T e e staggered 0 0 0 
2 0.00985 4.00973 1.60721 T e e staggered 0 0 0 
2 0.00985 4.00973 1.76469 T e e staggered 0 0 0 
2 0.00985 4.00973 1.80406 T e e staggered 0 0 0 
2 0.00985 4.0491 1.44973 T e e staggered 0 0 0 
2 0.00985 4.0491 1.4891 T e e staggered 0 0 0 
2 0.00985 4.0491 1.56784 T e e staggered 0 0 0 
2 0.00985 4.0491 1.64658 T e e staggered 0 0 0 
2 0.00985 4.0491 1.72532 T e e staggered 0 0 0 
2 0.00985 4.0491 2.07965 T e e staggered 0 0 0 
2 0.00985 4.08847 1.4891 T e e staggered 0 0 0 
2 0.00985 4.08847 1.72532 T e e staggered 0 0 0 
2 0.00985 4.08847 1.96154 T e e staggered 0 0 0 
2 0.00985 4.12784 1.4891 T e e staggered 0 0 0 
2 0.00985 4.12784 1.52847 T e e staggered 0 0 0 
2 0.00985 4.12784 1.56784 T e e staggered 0 0 0 
2 0.00985 4.12784 1.60721 T e e staggered 0 0 0 
2 0.00985 4.12784 1.64658 T e e staggered 0 0 0 
2 0.00985 4.12784 1.68595 T e e staggered 0 0 0 
2 0.00985 4.12784 1.76469 T e e staggered 0 0 0 
2 0.00985 4.12784 1.84343 T e e staggered 0 0 0 
2 0.00985 4.16721 1.33161 T e e staggered 0 0 0 
2 0.00985 4.16721 1.56784 T e e staggered 0 0 0 
2 0.00985 4.16721 1.64658 T e e staggered 0 0 0 
2 0.00985 4.16721 1.72532 T e e staggered 0 0 0 
2 0.00985 4.16721 2.11902 T e e staggered 0 0 0 
2 0.00985 4.20658 1.60721 T e e staggered 0 0 0 
2 0.00985 4.20658 1.68595 T e e staggered 0 0 0 
2 0.00985 4.20658 1.76469 T e e staggered 0 0 0 
2 0.00985 4.20658 2.00091 T e e staggered 0 0 0 
2 0.00985 4.24595 1.4891 T e e staggered 0 0 0 
2 0.00985 4.24595 1.56784 T e e staggered 0 0 0 
2 0.00985 4.24595 1.64658 T e e staggered 0 0 0 
2 0.00985 4.24595 1.72532 T e e staggered 0 0 0 
2 0.00985 4.24595 1.8828 T e e staggered 0 0 0 
2 0.00985 4.28532 1.37098 T e e staggered 0 0 0 
2 0.00985 4.28532 1.60721 T e e staggered 0 0 0 
2 0.00985 4.28532 1.64658 T e e staggered 0 0 0 
2 0.00985 4.28532 1.68595 T e e staggered 0 0 0 
2 0.00985 4.28532 2.15839 T e e staggered 0 0 0 
2 0.00985 4.32469 1.56784 T e e staggered 0 0 0 
2 0.00985 4.32469 1.64658 T e e staggered 0 0 0 
2 0.00985 4.32469 1.68595 T e e staggered 0 0 0 
2 0.00985 4.32469 1.72532 T e e staggered 0 0 0 
2 0.00985 4.32469 2.04028 T e e staggered 0 0 0 
2 0.00985 4.36406 1.52847 T e e staggered 0 0 0 
2 0.00985 4.36406 1.60721 T e e staggered 0 0 0 
2 0.00985 4.36406 1.64658 T e e staggered 0 0 0 
2 0.00985 4.36406 1.68595 T e e staggered 0 0 0 
2 0.00985 4.36406 1.92217 T e e staggered 0 0 0 
2 0.00985 4.40343 1.41035 T e e staggered 0 0 0 
2 0.00985 4.40343 1.56784 T e e staggered 0 0 0 
2 0.00985 4.40343 1.64658 T e e staggered 0 0 0 
2 0.00985 4.40343 1.72532 T e e staggered 0 0 0 
2 0.00985 4.40343 1.80406 T e e staggered 0 0 0 
2 0.00985 4.4428 1.60721 T e e staggered 0 0 0 
2 0.00985 4.4428 1.68595 T e e staggered 0 0 0 
2 0.00985 4.4428 1.76469 T e e staggered 0 0 0 
2 0.00985 4.4428 2.07965 T e e staggered 0 0 0 
2 0.00985 4.48217 1.56784 T e e staggered 0 0 0 
2 0.00985 4.48217 1.64658 T e e staggered 0 0 0 
2 0.00985 4.48217 1.72532 T e e staggered 0 0 0 
2 0.00985 4.48217 1.96154 T e e staggered 0 0 0 
2 0.00985 4.52154 1.44973 T e e staggered 0 0 0 
2 0.00985 4.52154 1.84343 T e e staggered 0 0 0 
2 0.00985 4.56091 1.33161 T e e staggered 0 0 0 
2 0.00985 4.56091 1.72532 T e e staggered 0 0 0 
2 0.00985 4.56091 2.11902 T e e staggered 0 0 0 
2 0.00985 4.60028 1.60721 T e e staggered 0 0 0 
2 0.00985 4.60028 2.00091 T e e staggered 0 0 0 
2 0.00985 4.63965 1.4891 T e e staggered 0 0 0 
2 0.00985 4.63965 1.8828 T e e staggered 0 0 0 
2 0 5.2975 1.595 T 0.045 0.104 e e staggered 0 0 0 
2 0 5.2975 1.345 T 0.045 0.104 e e staggered 0 0 0 
2 0 5.2975 1.47 T 0.045 0.104 e e staggered 0 0 0 
2 0 4.74 2.5415 T 0.104 0.045 e e staggered 0 0 0 
2 0 3.582 2.761 T 0.024 0.028 e e staggered 0 0 0 
2 0 5.29108 3.306 T 0.094 0.13 e e staggered 0 0 0 
2 0 3.50595 1.93911 T 0.037 0.008 e e staggered 0 0 0 
2 0 1.65781 3.91187 T 0.012 0.045 e e staggered 0 0 0 
2 0 1.67946 3.91187 T 0.012 0.045 e e staggered 0 0 0 
2 0 1.70112 3.91187 T 0.012 0.045 e e staggered 0 0 0 
2 0 1.70112 4.02013 T 0.012 0.045 e e staggered 0 0 0 
2 0 1.67946 4.02013 T 0.012 0.045 e e staggered 0 0 0 
2 0 1.65781 4.02013 T 0.012 0.045 e e staggered 0 0 0 
2 0 3.34119 4.06613 T 0.012 0.045 e e staggered 0 0 0 
2 0 3.31954 4.06613 T 0.012 0.045 e e staggered 0 0 0 
2 0 3.29788 4.06613 T 0.012 0.045 e e staggered 0 0 0 
2 0 3.29788 3.95787 T 0.012 0.045 e e staggered 0 0 0 
2 0 3.31954 3.95787 T 0.012 0.045 e e staggered 0 0 0 
2 0 3.34119 3.95787 T 0.012 0.045 e e staggered 0 0 0 
2 0 5.52087 2.14319 T 0.045 0.012 e e staggered 0 0 0 
2 0 5.52087 2.12154 T 0.045 0.012 e e staggered 0 0 0 
2 0 5.52087 2.09988 T 0.045 0.012 e e staggered 0 0 0 
2 0 5.62913 2.09988 T 0.045 0.012 e e staggered 0 0 0 
2 0 5.62913 2.12154 T 0.045 0.012 e e staggered 0 0 0 
2 0 5.62913 2.14319 T 0.045 0.012 e e staggered 0 0 0 
2 0 1.8832 0.74 T 0.065 0.02 e e staggered 0 0 0 
2 0 2.0966 3.2655 T 0.018 0.06 e e staggered 0 0 0 
2 0 0.8594 2.2465 T 0.018 0.06 e e staggered 0 0 0 
2 0 6.0845 1.0066 T 0.06 0.018 e e staggered 0 0 0 
2 0 5.59271 3.77637 T 0.047 0.012 e e staggered 0 0 0 
2 0 3.816 2.725 T 0.028 0.024 e e staggered 0 0 0 
2 0 5.328 2.611 T 0.024 0.028 e e staggered 0 0 0 
2 0 3.964 0.97 T 0.028 0.024 e e staggered 0 0 0 
2 0 4.101 0.97 T 0.028 0.024 e e staggered 0 0 0 
2 0 2.595 0.655 T 0.028 0.024 e e staggered 0 0 0 
2 0 3.604 1.74549 T 0.024 0.028 e e staggered 0 0 0 
2 0 0.455 1.22 T 0.024 0.028 e e staggered 0 0 0 
2 0 0.443 0.689 T 0.024 0.028 e e staggered 0 0 0 
2 0 0.452 2.368 T 0.024 0.028 e e staggered 0 0 0 
2 0 0.455 1.644 T 0.024 0.028 e e staggered 0 0 0 
2 0 5.291 0.87 T 0.028 0.024 e e staggered 0 0 0 
2 0 4.554 3.22 T 0.028 0.024 e e staggered 0 0 0 
2 0 4.426 3.745 T 0.028 0.024 e e staggered 0 0 0 
2 0 0.631 3.29 T 0.028 0.024 e e staggered 0 0 0 
2 0 0.595 3.596 T 0.024 0.028 e e staggered 0 0 0 
2 0 3.816 2.68 T 0.028 0.024 e e staggered 0 0 0 
2 0 0.619 2.79 T 0.028 0.024 e e staggered 0 0 0 
2 0 0.835 2.524 T 0.024 0.028 e e staggered 0 0 0 
2 0 4.566 2.845 T 0.028 0.024 e e staggered 0 0 0 
2 0 4.4585 1.123 T 0.028 0.024 e e staggered 0 0 0 
2 0 4.3245 1.123 T 0.028 0.024 e e staggered 0 0 0 
2 0 5.762 3.617 T 0.028 0.024 e e staggered 0 0 0 
2 0 5.762 3.667 T 0.028 0.024 e e staggered 0 0 0 
2 0 5.762 3.757 T 0.028 0.024 e e staggered 0 0 0 
2 0 5.46443 3.967 T 0.028 0.024 e e staggered 0 0 0 
2 0 5.762 3.517 T 0.028 0.024 e e staggered 0 0 0 
2 0 3.159 2.344 T 0.028 0.024 e e staggered 0 0 0 
2 0 3.159 2.479 T 0.028 0.024 e e staggered 0 0 0 
2 0 4.44 2.461 T 0.024 0.028 e e staggered 0 0 0 
2 0 3.159 2.164 T 0.028 0.024 e e staggered 0 0 0 
2 0 5.001 1.43 T 0.028 0.024 e e staggered 0 0 0 
2 0 4.46 0.973 T 0.028 0.024 e e staggered 0 0 0 
2 0 4.322 0.973 T 0.028 0.024 e e staggered 0 0 0 
2 0 4.926 1.72 T 0.028 0.024 e e staggered 0 0 0 
2 0 4.926 1.675 T 0.028 0.024 e e staggered 0 0 0 
2 0 3.159 2.569 T 0.028 0.024 e e staggered 0 0 0 
2 0 3.564 4.077 T 0.028 0.024 e e staggered 0 0 0 
2 0 4.735 3.504 T 0.024 0.028 e e staggered 0 0 0 
2 0 4.396 3.915 T 0.028 0.024 e e staggered 0 0 0 
2 0 4.396 4.015 T 0.028 0.024 e e staggered 0 0 0 
2 0 5.89953 2.28402 T 0.028 0.024 e e staggered 0 0 0 
2 0 3.285 2.553 T 0.024 0.028 e e staggered 0 0 0 
2 0 1.484 2.95 T 0.028 0.024 e e staggered 0 0 0 
2 0 5.601 3.915 T 0.028 0.024 e e staggered 0 0 0 
2 0 6.1437 4.07875 T 0.031 0.031 e e staggered 0 0 0 
2 0 6.02559 4.07875 T 0.031 0.031 e e staggered 0 0 0 
2 0 5.90748 4.07875 T 0.031 0.031 e e staggered 0 0 0 
2 0 5.43504 4.07875 T 0.031 0.031 e e staggered 0 0 0 
2 0 5.283 4.15049 T 0.031 0.031 e e staggered 0 0 0 
2 0 5.55315 4.07875 T 0.031 0.031 e e staggered 0 0 0 
2 0 5.78937 4.07875 T 0.031 0.031 e e staggered 0 0 0 
2 0 5.67126 4.07875 T 0.031 0.031 e e staggered 0 0 0 
2 0 0.51043 1.57 T 0.012 0.015 e e staggered 0 0 0 
2 0 0.50357 1 T 0.012 0.015 e e staggered 0 0 0 
2 0 0.49657 2.68 T 0.012 0.015 e e staggered 0 0 0 
2 0 0.51643 2.166 T 0.012 0.015 e e staggered 0 0 0 
2 0 1.71457 2.9 T 0.012 0.015 e e staggered 0 0 0 
2 0 5.73143 3.712 T 0.012 0.015 e e staggered 0 0 0 
2 0 5.48557 3.912 T 0.012 0.015 e e staggered 0 0 0 
2 0 1.45057 3.901 T 0.012 0.015 e e staggered 0 0 0 
2 0 1.29043 3.79 T 0.012 0.015 e e staggered 0 0 0 
2 0 1.21457 3.79 T 0.012 0.015 e e staggered 0 0 0 
2 0 3.63673 2.41243 T 0.015 0.012 e e staggered 0 0 0 
2 0 3.63673 2.32557 T 0.015 0.012 e e staggered 0 0 0 
2 0 5.43957 0.635 T 0.012 0.015 e e staggered 0 0 0 
2 0 5.78043 0.609 T 0.012 0.015 e e staggered 0 0 0 
2 0 3.96243 2.774 T 0.012 0.015 e e staggered 0 0 0 
2 0 4.95257 2.777 T 0.012 0.015 e e staggered 0 0 0 
2 0 3.982 3.10043 T 0.015 0.012 e e staggered 0 0 0 
2 0 3.54743 4.121 T 0.012 0.015 e e staggered 0 0 0 
2 0 5.29043 2.725 T 0.012 0.015 e e staggered 0 0 0 
2 0 5.51 2.35043 T 0.015 0.012 e e staggered 0 0 0 
2 0 3.798 1.06 T 0.038 0.054 e e staggered 0 0 0 
2 0 3.515 1.648 T 0.054 0.038 e e staggered 0 0 0 
2 0 3.705 1.648 T 0.054 0.038 e e staggered 0 0 0 
2 0 1.46 3.007 T 0.054 0.038 e e staggered 0 0 0 
2 0 1.848 3.26 T 0.038 0.054 e e staggered 0 0 0 
2 0 5.336 3.738 T 0.054 0.038 e e staggered 0 0 0 
2 0 5.254 3.738 T 0.054 0.038 e e staggered 0 0 0 
2 0 5.298 3.827 T 0.038 0.054 e e staggered 0 0 0 
2 0 1.714 4.151 T 0.038 0.054 e e staggered 0 0 0 
2 0 1.744 3.776 T 0.038 0.054 e e staggered 0 0 0 
2 0 2.186 4.104 T 0.054 0.038 e e staggered 0 0 0 
2 0 2.261 4.104 T 0.054 0.038 e e staggered 0 0 0 
2 0 2.236 3.828 T 0.054 0.038 e e staggered 0 0 0 
2 0 5.273 1.24 T 0.038 0.054 e e staggered 0 0 0 
2 0 5.723 1.61 T 0.038 0.054 e e staggered 0 0 0 
2 0 5.385 2.057 T 0.054 0.038 e e staggered 0 0 0 
2 0 5.39 1.597 T 0.054 0.038 e e staggered 0 0 0 
2 0 5.35 1.853 T 0.054 0.038 e e staggered 0 0 0 
2 0 4.933 1.264 T 0.038 0.054 e e staggered 0 0 0 
2 0 5.55 0.863 T 0.038 0.054 e e staggered 0 0 0 
2 0 5.632 0.859 T 0.038 0.054 e e staggered 0 0 0 
2 0 5.575 0.932 T 0.054 0.038 e e staggered 0 0 0 
2 0 3.285 3.827 T 0.038 0.054 e e staggered 0 0 0 
2 0 3.32 3.718 T 0.054 0.038 e e staggered 0 0 0 
2 0 3.48 3.718 T 0.054 0.038 e e staggered 0 0 0 
2 0 4.455 2.672 T 0.054 0.038 e e staggered 0 0 0 
2 0 4.134 2.936 T 0.038 0.054 e e staggered 0 0 0 
2 0 3.4 3.718 T 0.054 0.038 e e staggered 0 0 0 
2 0 4.134 2.855 T 0.038 0.054 e e staggered 0 0 0 
2 0 3.729 2.87 T 0.054 0.038 e e staggered 0 0 0 
2 0 5.05 3.837 T 0.054 0.038 e e staggered 0 0 0 
2 0 3.732 2.952 T 0.054 0.038 e e staggered 0 0 0 
2 0 3.255 4.202 T 0.038 0.054 e e staggered 0 0 0 
2 0 4.588 3.927 T 0.038 0.054 e e staggered 0 0 0 
2 0 5.08 2.534 T 0.038 0.054 e e staggered 0 0 0 
2 0 1.888 3.105 T 0.038 0.054 e e staggered 0 0 0 
2 0 5.162 2.521 T 0.038 0.054 e e staggered 0 0 0 
2 0 5.76 2.087 T 0.054 0.038 e e staggered 0 0 0 
2 0 6.225 1.97074 T 0.054 0.038 e e staggered 0 0 0 
2 0 3.769 0.97 T 0.028 0.024 e e staggered 0 0 0 
2 0 3.575 1.621 T 0.024 0.028 e e staggered 0 0 0 
2 0 2.9972 0.6678 T 0.028 0.024 e e staggered 0 0 0 
2 0 2.15 0.636 T 0.024 0.028 e e staggered 0 0 0 
2 0 2.105 0.636 T 0.024 0.028 e e staggered 0 0 0 
2 0 3.911 0.97 T 0.028 0.024 e e staggered 0 0 0 
2 0 3.705 2.384 T 0.024 0.028 e e staggered 0 0 0 
2 0 1.51 3.206 T 0.024 0.028 e e staggered 0 0 0 
2 0 4.551 3.27 T 0.028 0.024 e e staggered 0 0 0 
2 0 1.861 3.19 T 0.028 0.024 e e staggered 0 0 0 
2 0 1.885 2.981 T 0.024 0.028 e e staggered 0 0 0 
2 0 1.866 3.04 T 0.028 0.024 e e staggered 0 0 0 
2 0 0.64 2.229 T 0.024 0.028 e e staggered 0 0 0 
2 0 0.606 1.64745 T 0.024 0.028 e e staggered 0 0 0 
2 0 0.625 1.084 T 0.024 0.028 e e staggered 0 0 0 
2 0 5.762 3.567 T 0.028 0.024 e e staggered 0 0 0 
2 0 5.637 3.569 T 0.028 0.024 e e staggered 0 0 0 
2 0 5.762 3.807 T 0.028 0.024 e e staggered 0 0 0 
2 0 5.762 3.857 T 0.028 0.024 e e staggered 0 0 0 
2 0 0.95048 2.683 T 0.028 0.024 e e staggered 0 0 0 
2 0 0.951 2.728 T 0.028 0.024 e e staggered 0 0 0 
2 0 0.907 2.58048 T 0.028 0.024 e e staggered 0 0 0 
2 0 1.2157 0.6136 T 0.028 0.024 e e staggered 0 0 0 
2 0 0.715 2.444 T 0.024 0.028 e e staggered 0 0 0 
2 0 0.714 2.252 T 0.024 0.028 e e staggered 0 0 0 
2 0 1.692 4.091 T 0.028 0.024 e e staggered 0 0 0 
2 0 1.712 3.841 T 0.028 0.024 e e staggered 0 0 0 
2 0 1.435 3.946 T 0.028 0.024 e e staggered 0 0 0 
2 0 1.445 3.704 T 0.024 0.028 e e staggered 0 0 0 
2 0 1.548 0.6632 T 0.024 0.028 e e staggered 0 0 0 
2 0 2.176 3.845 T 0.024 0.028 e e staggered 0 0 0 
2 0 2.218 2.931 T 0.024 0.028 e e staggered 0 0 0 
2 0 5.41 1.836 T 0.024 0.028 e e staggered 0 0 0 
2 0 5.291 0.92 T 0.028 0.024 e e staggered 0 0 0 
2 0 3.159 2.524 T 0.028 0.024 e e staggered 0 0 0 
2 0 5.056 2.474 T 0.028 0.024 e e staggered 0 0 0 
2 0 5.772 0.658 T 0.024 0.028 e e staggered 0 0 0 
2 0 5.569 0.792 T 0.028 0.024 e e staggered 0 0 0 
2 0 5.649 0.792 T 0.028 0.024 e e staggered 0 0 0 
2 0 5.64 0.944 T 0.024 0.028 e e staggered 0 0 0 
2 0 3.255 3.706 T 0.024 0.028 e e staggered 0 0 0 
2 0 3.307 3.887 T 0.028 0.024 e e staggered 0 0 0 
2 0 4.566 2.945 T 0.028 0.024 e e staggered 0 0 0 
2 0 4.566 2.895 T 0.028 0.024 e e staggered 0 0 0 
2 0 4.39 2.699 T 0.024 0.028 e e staggered 0 0 0 
2 0 4.145 2.792 T 0.028 0.024 e e staggered 0 0 0 
2 0 4.961 2.728 T 0.024 0.028 e e staggered 0 0 0 
2 0 5.089 3.775 T 0.028 0.024 e e staggered 0 0 0 
2 0 4.396 3.965 T 0.028 0.024 e e staggered 0 0 0 
2 0 2.895 3.206 T 0.028 0.024 e e staggered 0 0 0 
2 0 3.797 2.891 T 0.024 0.028 e e staggered 0 0 0 
2 0 3.797 2.969 T 0.024 0.028 e e staggered 0 0 0 
2 0 3.933 3.092 T 0.028 0.024 e e staggered 0 0 0 
2 0 3.594 4.197 T 0.028 0.024 e e staggered 0 0 0 
2 0 3.564 4.032 T 0.028 0.024 e e staggered 0 0 0 
2 0 3.662 2.976 T 0.024 0.028 e e staggered 0 0 0 
2 0 3.582 2.898 T 0.024 0.028 e e staggered 0 0 0 
2 0 3.287 4.137 T 0.028 0.024 e e staggered 0 0 0 
2 0 4.53 3.891 T 0.024 0.028 e e staggered 0 0 0 
2 0 5.162 2.592 T 0.028 0.024 e e staggered 0 0 0 
2 0 5.084 2.597 T 0.028 0.024 e e staggered 0 0 0 
2 0 5.555 2.366 T 0.024 0.028 e e staggered 0 0 0 
2 0 5.7 2.109 T 0.024 0.028 e e staggered 0 0 0 
2 0 4.426 3.79 T 0.028 0.024 e e staggered 0 0 0 
2 0 5.331 2.238 T 0.024 0.028 e e staggered 0 0 0 
2 0 5.45 2.089 T 0.024 0.028 e e staggered 0 0 0 
2 0 6.421 1.135 T 0.028 0.024 e e staggered 0 0 0 
2 0 6.289 1.97074 T 0.024 0.028 e e staggered 0 0 0 
2 0 6.141 2.278 T 0.024 0.028 e e staggered 0 0 0 
2 0 6.071 2.225 T 0.028 0.024 e e staggered 0 0 0 
2 0 6.071 2.27 T 0.028 0.024 e e staggered 0 0 0 
2 0 3.38484 2.553 T 0.024 0.028 e e staggered 0 0 0 
2 0 3.435 2.553 T 0.024 0.028 e e staggered 0 0 0 
2 0 3.546 2.513 T 0.024 0.028 e e staggered 0 0 0 
2 0 0.86207 2.091 T 0.041 0.087 e e staggered 0 0 0 
2 0 0.74593 2.091 T 0.041 0.087 e e staggered 0 0 0 
2 0 0.2055 0.9565 T 0.043 0.057 e e staggered 0 0 0 
2 0 0.2055 2.0965 T 0.043 0.057 e e staggered 0 0 0 
2 0 1.21169 3.91846 T 0.055 0.047 e e staggered 0 0 0 
2 0 1.29831 3.85154 T 0.055 0.047 e e staggered 0 0 0 
2 0 2.754 0.57941 T 0.038 0.013 e e staggered 0 0 0 
2 0 3.695 2.6265 T 0.02 0.047 e e staggered 0 0 0 
2 0 0.72 3.3935 T 0.02 0.047 e e staggered 0 0 0 
2 0 6.26989 2.31484 T 0.02 0.047 e e staggered 0 0 0 
2 0 6.22356 3.015 T 0.14 0.05 e e staggered 0 0 0 
2 0 5.50544 2.621 T 0.14 0.05 e e staggered 0 0 0 
2 0 5.50544 3.021 T 0.14 0.05 e e staggered 0 0 0 
2 0 6.4105 2.16142 T 0.053 0.016 e e staggered 0 0 0 
2 0 6.51582 2.07087 T 0.075 0.059 e e staggered 0 0 0 
2 0 6.51582 2.14961 T 0.075 0.059 e e staggered 0 0 0 
2 0.0165 6.40952 2.01181 B e e staggered 0 0 0 
2 0.0165 6.40952 2.20867 B e e staggered 0 0 0 
2 0.012 6.51582 1.97244 B e e staggered 0 0 0 
2 0.012 6.51582 2.24804 B e e staggered 0 0 0 
2 0 3.2815 3.40457 T 0.062 0.014 e e staggered 0 0 0 
2 0 1.91535 0.13781 D 0.028 0.165 e e staggered 0 0 0 
2 0 2.30905 0.13781 D 0.028 0.165 e e staggered 0 0 0 
2 0 2.42716 0.13781 D 0.028 0.165 e e staggered 0 0 0 
2 0 2.54527 0.13781 D 0.028 0.165 e e staggered 0 0 0 
2 0 2.62401 0.13781 D 0.028 0.165 e e staggered 0 0 0 
2 0 2.74212 0.13781 D 0.028 0.165 e e staggered 0 0 0 
2 0 2.78149 0.13781 D 0.028 0.165 e e staggered 0 0 0 
2 0 2.8996 0.13781 D 0.028 0.165 e e staggered 0 0 0 
2 0 2.93897 0.13781 D 0.028 0.165 e e staggered 0 0 0 
2 0 3.05708 0.13781 D 0.028 0.165 e e staggered 0 0 0 
2 0 1.91535 0.13781 T 0.028 0.165 e e staggered 0 0 0 
2 0 2.03346 0.13781 T 0.028 0.165 e e staggered 0 0 0 
2 0 2.34842 0.13781 T 0.028 0.165 e e staggered 0 0 0 
2 0 2.46653 0.13781 T 0.028 0.165 e e staggered 0 0 0 
2 0 2.54527 0.13781 T 0.028 0.165 e e staggered 0 0 0 
2 0 2.66338 0.13781 T 0.028 0.165 e e staggered 0 0 0 
2 0 2.70275 0.13781 T 0.028 0.165 e e staggered 0 0 0 
2 0 2.82086 0.13781 T 0.028 0.165 e e staggered 0 0 0 
2 0 2.86023 0.13781 T 0.028 0.165 e e staggered 0 0 0 
2 0 2.97834 0.13781 T 0.028 0.165 e e staggered 0 0 0 
2 0 3.09645 0.13781 T 0.028 0.165 e e staggered 0 0 0 
2 0 3.0535 2.143 D 0.055 0.039 e e staggered 0 0 0 
2 0.0125 4.7184 2.07965 D e e staggered 0 0 0 
2 0.0125 4.71839 2.1584 D e e staggered 0 0 0 
2 0.0125 4.71839 1.68595 D e e staggered 0 0 0 
2 0.0125 4.67902 1.84343 D e e staggered 0 0 0 
2 0.0125 4.56091 1.8828 D e e staggered 0 0 0 
2 0.0125 4.48217 1.80405 D e e staggered 0 0 0 
2 0.0125 4.4428 1.80405 D e e staggered 0 0 0 
2 0.0125 4.00973 1.56785 D e e staggered 0 0 0 
2 0.0125 4.12785 1.56784 D e e staggered 0 0 0 
2 0.0125 4.0491 1.64659 D e e staggered 0 0 0 
2 0.0125 4.12785 1.60721 D e e staggered 0 0 0 
2 0.0125 4.00973 1.44972 D e e staggered 0 0 0 
2 0.0125 4.0491 1.41036 D e e staggered 0 0 0 
2 0.0125 3.97036 1.84343 D e e staggered 0 0 0 
2 0.0125 4.12784 1.64657 D e e staggered 0 0 0 
2 0.0125 4.00972 1.80406 D e e staggered 0 0 0 
2 0.0125 3.97036 1.64658 D e e staggered 0 0 0 
2 0.0125 3.93098 1.7647 D e e staggered 0 0 0 
2 0.0125 3.8916 1.4891 D e e staggered 0 0 0 
2 0.0125 3.97035 1.48911 D e e staggered 0 0 0 
2 0.0125 4.75777 2.00091 D e e staggered 0 0 0 
2 0.0125 4.16721 1.56783 D e e staggered 0 0 0 
2 0.0125 4.24596 1.56784 D e e staggered 0 0 0 
2 0.0125 4.20657 1.68595 D e e staggered 0 0 0 
2 0.0125 4.16721 1.68596 D e e staggered 0 0 0 
2 0.0125 4.24595 1.64659 D e e staggered 0 0 0 
2 0.0125 4.20658 1.48909 D e e staggered 0 0 0 
2 0.0125 4.20658 1.44973 D e e staggered 0 0 0 
2 0.0125 4.12783 1.52847 D e e staggered 0 0 0 
2 0.0125 4.12783 1.4891 D e e staggered 0 0 0 
2 0.0125 4.309 1.48469 D e e staggered 0 0 0 
2 0.0125 4.36406 1.52846 D e e staggered 0 0 0 
2 0.0125 4.36406 1.48911 D e e staggered 0 0 0 
2 0.0125 3.8916 2.15839 D e e staggered 0 0 0 
2 0.0125 3.93098 2.07964 D e e staggered 0 0 0 
2 0.0125 3.93097 2.04028 D e e staggered 0 0 0 
2 0.0125 3.93098 2.00091 D e e staggered 0 0 0 
2 0.0125 4.4428 1.41035 D e e staggered 0 0 0 
2 0.0125 4.40343 1.37099 D e e staggered 0 0 0 
2 0.0125 4.16722 2.04028 D e e staggered 0 0 0 
2 0.0125 4.08846 1.96154 D e e staggered 0 0 0 
2 0.0125 4.16721 2.00092 D e e staggered 0 0 0 
2 0.0125 4.24595 2.1584 D e e staggered 0 0 0 
2 0.0125 4.31006 1.93718 D e e staggered 0 0 0 
2 0.0125 4.20658 1.88281 D e e staggered 0 0 0 
2 0.0125 4.20657 1.80406 D e e staggered 0 0 0 
2 0.0125 4.36406 1.64659 D e e staggered 0 0 0 
2 0.0125 4.40344 1.80406 D e e staggered 0 0 0 
2 0.0125 4.52154 1.84344 D e e staggered 0 0 0 
2 0.0125 4.67903 1.80406 D e e staggered 0 0 0 
2 0.0125 4.60027 1.68595 D e e staggered 0 0 0 
2 0.0125 4.63964 1.56784 D e e staggered 0 0 0 
2 0.0125 4.40343 1.64657 D e e staggered 0 0 0 
2 0.0125 4.4428 1.60722 D e e staggered 0 0 0 
2 0.0125 4.48218 1.64658 D e e staggered 0 0 0 
2 0.0125 4.48217 1.56783 D e e staggered 0 0 0 
2 0.0125 4.52154 1.64657 D e e staggered 0 0 0 
2 0.0125 4.40342 1.92217 D e e staggered 0 0 0 
2 0.0125 4.48216 1.96154 D e e staggered 0 0 0 
2 0.0125 4.63965 1.88281 D e e staggered 0 0 0 
2 0.0125 4.63966 1.92217 D e e staggered 0 0 0 
2 0.0125 4.40343 1.56783 D e e staggered 0 0 0 
2 0.0125 4.5609 1.41035 D e e staggered 0 0 0 
2 0.0125 4.76666 1.38867 D e e staggered 0 0 0 
2 0.0125 4.48216 2.07965 D e e staggered 0 0 0 
2 0.0125 4.40343 2.19777 D e e staggered 0 0 0 
2 0.0125 4.63966 1.96154 D e e staggered 0 0 0 
2 0.0125 4.00973 1.6072 D e e staggered 0 0 0 
2 0.0125 3.97036 1.52847 D e e staggered 0 0 0 
2 0.0125 3.97035 1.92217 D e e staggered 0 0 0 
2 0.0125 4.20658 1.6072 D e e staggered 0 0 0 
2 0.0125 4.0491 1.96155 D e e staggered 0 0 0 
2 0.0125 4.48218 1.68595 D e e staggered 0 0 0 
2 0.0125 4.52154 1.41035 D e e staggered 0 0 0 
2 0.0125 4.60028 1.56785 D e e staggered 0 0 0 
2 0.0125 4.67902 2.1584 D e e staggered 0 0 0 
2 0 3.9825 2.325 D 0.045 0.104 e e staggered 0 0 0 
2 0 1.035 3.094 D 0.024 0.028 e e staggered 0 0 0 
2 0 1.375 3.559 D 0.024 0.028 e e staggered 0 0 0 
2 0 1.085 3.606 D 0.024 0.028 e e staggered 0 0 0 
2 0 1.22 3.606 D 0.024 0.028 e e staggered 0 0 0 
2 0 4.024 2.215 D 0.028 0.024 e e staggered 0 0 0 
2 0 4.46511 1.755 D 0.028 0.024 e e staggered 0 0 0 
2 0 4.45485 2.22 D 0.028 0.024 e e staggered 0 0 0 
2 0 1.6355 4.031 D 0.005 0.024 e e staggered 0 0 0 
2 0 3.3635 3.947 D 0.005 0.024 e e staggered 0 0 0 
2 0 5.64 2.1655 D 0.024 0.005 e e staggered 0 0 0 
2 0 5.316 3.51999 D 0.108 0.085 e e staggered 0 0 0 
2 0 2.69 2.1935 D 0.02 0.047 e e staggered 0 0 0 
2 0 1.7485 3.388 D 0.065 0.02 e e staggered 0 0 0 
2 0 0.5505 2.9516 D 0.06 0.018 e e staggered 0 0 0 
2 0 1.479 3 D 0.028 0.024 e e staggered 0 0 0 
2 0 5.278 2.611 D 0.024 0.028 e e staggered 0 0 0 
2 0 1.873 4.13 D 0.038 0.054 e e staggered 0 0 0 
2 0 3.185 3.757 D 0.054 0.038 e e staggered 0 0 0 
2 0 5.753 1.99 D 0.038 0.054 e e staggered 0 0 0 
2 0 4.681 1.755 D 0.028 0.024 e e staggered 0 0 0 
2 0 4.15 2.552 D 0.024 0.028 e e staggered 0 0 0 
2 0 4.209 2.552 D 0.024 0.028 e e staggered 0 0 0 
2 0 4.093 2.552 D 0.024 0.028 e e staggered 0 0 0 
2 0 3.801 2.552 D 0.024 0.028 e e staggered 0 0 0 
2 0 3.86 2.552 D 0.024 0.028 e e staggered 0 0 0 
2 0 4.694 0.915 D 0.028 0.024 e e staggered 0 0 0 
2 0 3.973 3.239 D 0.028 0.024 e e staggered 0 0 0 
2 0 3.839 3.758 D 0.028 0.024 e e staggered 0 0 0 
2 0 1.885 2.981 D 0.024 0.028 e e staggered 0 0 0 
2 0 4.585 1.139 D 0.024 0.028 e e staggered 0 0 0 
2 0 4.53 1.139 D 0.024 0.028 e e staggered 0 0 0 
2 0 0.858 2.831 D 0.024 0.028 e e staggered 0 0 0 
2 0 0.995 3.564 D 0.024 0.028 e e staggered 0 0 0 
2 0 0.833 0.911 D 0.024 0.028 e e staggered 0 0 0 
2 0 0.698 0.911 D 0.024 0.028 e e staggered 0 0 0 
2 0 3.919 2.552 D 0.024 0.028 e e staggered 0 0 0 
2 0 0.199 2.875 D 0.028 0.024 e e staggered 0 0 0 
2 0 0.29 2.829 D 0.024 0.028 e e staggered 0 0 0 
2 0 0.199 3.025 D 0.028 0.024 e e staggered 0 0 0 
2 0 5.762 3.857 D 0.028 0.024 e e staggered 0 0 0 
2 0 1.038 0.718 D 0.028 0.024 e e staggered 0 0 0 
2 0 2.083 2.931 D 0.024 0.028 e e staggered 0 0 0 
2 0 2.128 2.931 D 0.024 0.028 e e staggered 0 0 0 
2 0 1.435 3.946 D 0.028 0.024 e e staggered 0 0 0 
2 0 0.889 0.71 D 0.028 0.024 e e staggered 0 0 0 
2 0 2.173 2.931 D 0.024 0.028 e e staggered 0 0 0 
2 0 4.485 2.461 D 0.024 0.028 e e staggered 0 0 0 
2 0 2.54 2.174 D 0.024 0.028 e e staggered 0 0 0 
2 0 6.21 1.96774 D 0.024 0.028 e e staggered 0 0 0 
2 0 5.772 0.658 D 0.024 0.028 e e staggered 0 0 0 
2 0 4.926 1.675 D 0.028 0.024 e e staggered 0 0 0 
2 0 4.62 2.461 D 0.024 0.028 e e staggered 0 0 0 
2 0 4.44 2.461 D 0.024 0.028 e e staggered 0 0 0 
2 0 4.961 2.728 D 0.024 0.028 e e staggered 0 0 0 
2 0 3.256 3.43 D 0.028 0.024 e e staggered 0 0 0 
2 0 3.256 3.25 D 0.028 0.024 e e staggered 0 0 0 
2 0 3.256 3.295 D 0.028 0.024 e e staggered 0 0 0 
2 0 3.068 3.305 D 0.028 0.024 e e staggered 0 0 0 
2 0 3.933 3.092 D 0.028 0.024 e e staggered 0 0 0 
2 0 3.506 3.325 D 0.028 0.024 e e staggered 0 0 0 
2 0 5.4525 2.6795 D 0.024 0.028 e e staggered 0 0 0 
2 0 3.978 2.552 D 0.024 0.028 e e staggered 0 0 0 
2 0 0.878 0.911 D 0.024 0.028 e e staggered 0 0 0 
2 0 5.555 2.366 D 0.024 0.028 e e staggered 0 0 0 
2 0 6.421 1.08 D 0.028 0.024 e e staggered 0 0 0 
2 0 6.421 1.02 D 0.028 0.024 e e staggered 0 0 0 
2 0 6.421 0.965 D 0.028 0.024 e e staggered 0 0 0 
2 0 5.96902 1.90865 D 0.024 0.028 e e staggered 0 0 0 
2 0 4.037 2.552 D 0.024 0.028 e e staggered 0 0 0 
2 0 1.175 3.606 D 0.024 0.028 e e staggered 0 0 0 
2 0 5.762 3.907 D 0.028 0.024 e e staggered 0 0 0 
2 0 5.404 0.69 D 0.028 0.024 e e staggered 0 0 0 
2 0 5.557 0.747 D 0.024 0.028 e e staggered 0 0 0 
2 0 3.798 1.06 D 0.038 0.054 e e staggered 0 0 0 
2 0 3.46 1.312 D 0.054 0.038 e e staggered 0 0 0 
2 0 3.785 1.302 D 0.054 0.038 e e staggered 0 0 0 
2 0 5.461 3.206 D 0.038 0.054 e e staggered 0 0 0 
2 0 5.465 3.288 D 0.038 0.054 e e staggered 0 0 0 
2 0 5.465 3.364 D 0.038 0.054 e e staggered 0 0 0 
2 0 5.465 3.441 D 0.038 0.054 e e staggered 0 0 0 
2 0 5.4 1.853 D 0.054 0.038 e e staggered 0 0 0 
2 0 3.678 2.23 D 0.038 0.054 e e staggered 0 0 0 
2 0 3.068 1.945 D 0.038 0.054 e e staggered 0 0 0 
2 0 4.933 1.263 D 0.038 0.054 e e staggered 0 0 0 
2 0 3.035 2.913 D 0.054 0.038 e e staggered 0 0 0 
2 0 3.11 2.913 D 0.054 0.038 e e staggered 0 0 0 
2 0 2.96 2.913 D 0.054 0.038 e e staggered 0 0 0 
2 0 4.134 2.855 D 0.038 0.054 e e staggered 0 0 0 
2 0 4.134 2.936 D 0.038 0.054 e e staggered 0 0 0 
2 0 3.662 2.952 D 0.054 0.038 e e staggered 0 0 0 
2 0 5.08 2.454 D 0.038 0.054 e e staggered 0 0 0 
2 0 3.77 0.769 D 0.024 0.028 e e staggered 0 0 0 
2 0 3.52 1.334 D 0.024 0.028 e e staggered 0 0 0 
2 0 2.2 0.656 D 0.024 0.028 e e staggered 0 0 0 
2 0 2.155 0.656 D 0.024 0.028 e e staggered 0 0 0 
2 0 3.505 1.789 D 0.024 0.028 e e staggered 0 0 0 
2 0 3.87629 1.29361 D 0.028 0.024 e e staggered 0 0 0 
2 0 3.8443 1.745 D 0.028 0.024 e e staggered 0 0 0 
2 0 3.98 3.471 D 0.024 0.028 e e staggered 0 0 0 
2 0 0.7 3.384 D 0.024 0.028 e e staggered 0 0 0 
2 0 1.265 3.606 D 0.024 0.028 e e staggered 0 0 0 
2 0 4.17 3.471 D 0.024 0.028 e e staggered 0 0 0 
2 0 0.199 3.075 D 0.028 0.024 e e staggered 0 0 0 
2 0 0.677 0.615 D 0.028 0.024 e e staggered 0 0 0 
2 0 0.86 0.833 D 0.024 0.028 e e staggered 0 0 0 
2 0 4.78 1.82111 D 0.024 0.028 e e staggered 0 0 0 
2 0 1.63 3.504 D 0.024 0.028 e e staggered 0 0 0 
2 0 5.39 1.604 D 0.024 0.028 e e staggered 0 0 0 
2 0 3.651 2.17 D 0.028 0.024 e e staggered 0 0 0 
2 0 3.041 2.005 D 0.028 0.024 e e staggered 0 0 0 
2 0 3.041 2.05 D 0.028 0.024 e e staggered 0 0 0 
2 0 4.199 1.75 D 0.028 0.024 e e staggered 0 0 0 
2 0 4.098 1.75 D 0.028 0.024 e e staggered 0 0 0 
2 0 4.305 1.591 D 0.024 0.028 e e staggered 0 0 0 
2 0 2.79 2.206 D 0.024 0.028 e e staggered 0 0 0 
2 0 2.855 2.886 D 0.024 0.028 e e staggered 0 0 0 
2 0 2.79 2.296 D 0.024 0.028 e e staggered 0 0 0 
2 0 2.59 2.264 D 0.024 0.028 e e staggered 0 0 0 
2 0 3.245 2.859 D 0.024 0.028 e e staggered 0 0 0 
2 0 2.9 2.886 D 0.024 0.028 e e staggered 0 0 0 
2 0 2.419 2.355 D 0.028 0.024 e e staggered 0 0 0 
2 0 5.825 0.796 D 0.024 0.028 e e staggered 0 0 0 
2 0 4.3 2.029 D 0.024 0.028 e e staggered 0 0 0 
2 0 4.306 1.795 D 0.024 0.028 e e staggered 0 0 0 
2 0 4.323 1.741 D 0.028 0.024 e e staggered 0 0 0 
2 0 4.305 1.649 D 0.024 0.028 e e staggered 0 0 0 
2 0 4.55511 1.755 D 0.028 0.024 e e staggered 0 0 0 
2 0 4.311 0.73 D 0.028 0.024 e e staggered 0 0 0 
2 0 4.275 0.961 D 0.024 0.028 e e staggered 0 0 0 
2 0 4.32 0.961 D 0.024 0.028 e e staggered 0 0 0 
2 0 4.566 2.895 D 0.028 0.024 e e staggered 0 0 0 
2 0 4.566 2.845 D 0.028 0.024 e e staggered 0 0 0 
2 0 5.035 3.854 D 0.024 0.028 e e staggered 0 0 0 
2 0 5.085 3.854 D 0.024 0.028 e e staggered 0 0 0 
2 0 4.24 3.983 D 0.024 0.028 e e staggered 0 0 0 
2 0 3.564 4.032 D 0.028 0.024 e e staggered 0 0 0 
2 0 4.614 3.895 D 0.028 0.024 e e staggered 0 0 0 
2 0 4.614 3.94 D 0.028 0.024 e e staggered 0 0 0 
2 0 4.396 3.965 D 0.028 0.024 e e staggered 0 0 0 
2 0 1.196 3.475 D 0.028 0.024 e e staggered 0 0 0 
2 0 1.13 3.606 D 0.024 0.028 e e staggered 0 0 0 
2 0 1.376 3.5 D 0.028 0.024 e e staggered 0 0 0 
2 0 5.7425 2.6375 D 0.043 0.057 e e staggered 0 0 0 
2 0 5.7375 2.9225 D 0.043 0.057 e e staggered 0 0 0 
2 0 2.41441 2.193 D 0.013 0.038 e e staggered 0 0 0 
2 0.005 1.025 4.2 B m e staggered 0 0 0 v 
2 0.005 1.03 3.64 B m e staggered 0 0 0 v 
2 0.005 1.038 0.7624 B m e staggered 0 0 0 v 
2 0.005 1.045 3.055 B m e staggered 0 0 0 v 
2 0.005 1.065 3.64 B m e staggered 0 0 0 v 
2 0.005 1.1 3.64 B m e staggered 0 0 0 v 
2 0.005 1.155 3.89 B m e staggered 0 0 0 v 
2 0.005 1.17 3.97 B m e staggered 0 0 0 v 
2 0.005 1.185 3.79 B m e staggered 0 0 0 v 
2 0.005 1.195 0.57694 B m e staggered 0 0 0 v 
2 0.005 1.2 3.645 B m e staggered 0 0 0 v 
2 0.005 1.2 3.68 B m e staggered 0 0 0 v 
2 0.005 1.2 3.715 B m e staggered 0 0 0 v 
2 0.005 1.21169 3.96892 B m e staggered 0 0 0 v 
2 0.005 1.235 3.475 B m e staggered 0 0 0 v 
2 0.005 1.25095 3.06095 B m e staggered 0 0 0 v 
2 0.005 1.27 3.97061 B m e staggered 0 0 0 v 
2 0.005 1.275 2.905 B m e staggered 0 0 0 v 
2 0.005 1.29 3.65 B m e staggered 0 0 0 v 
2 0.005 1.29 3.705 B m e staggered 0 0 0 v 
2 0.005 1.32 3.755 B m e staggered 0 0 0 v 
2 0.005 1.32 3.79 B m e staggered 0 0 0 v 
2 0.005 1.355 3.83 B m e staggered 0 0 0 v 
2 0.005 1.355 3.905 B m e staggered 0 0 0 v 
2 0.005 1.355 3.96 B m e staggered 0 0 0 v 
2 0.005 1.401 3.956 B m e staggered 0 0 0 v 
2 0.005 1.40123 3.91604 B m e staggered 0 0 0 v 
2 0.005 1.409 3.554 B m e staggered 0 0 0 v 
2 0.005 1.41 2.985 B m e staggered 0 0 0 v 
2 0.005 1.42 3.5 B m e staggered 0 0 0 v 
2 0.005 1.4213 3.2563 B m e staggered 0 0 0 v 
2 0.005 1.45 2.965 B m e staggered 0 0 0 v 
2 0.005 1.48 3.7 B m e staggered 0 0 0 v 
2 0.005 1.51 3.242 B m e staggered 0 0 0 v 
2 0.005 1.515 3.7 B m e staggered 0 0 0 v 
2 0.005 1.591 3.504 B m e staggered 0 0 0 v 
2 0.005 0.16 3.025 B m e staggered 0 0 0 v 
2 0.005 0.16 3.075 B m e staggered 0 0 0 v 
2 0.005 1.65 2.94 B m e staggered 0 0 0 v 
2 0.005 1.667 3.388 B m e staggered 0 0 0 v 
2 0.005 1.685 2.94 B m e staggered 0 0 0 v 
2 0.005 0.17 2.045 B m e staggered 0 0 0 v 
2 0.005 1.746 4.016 B m e staggered 0 0 0 v 
2 0.005 1.746 4.061 B m e staggered 0 0 0 v 
2 0.005 0.175 0.91 B m e staggered 0 0 0 v 
2 0.005 1.751 3.871 B m e staggered 0 0 0 v 
2 0.005 1.76 4.16 B m e staggered 0 0 0 v 
2 0.005 1.786 3.746 B m e staggered 0 0 0 v 
2 0.005 1.786 3.786 B m e staggered 0 0 0 v 
2 0.005 1.89 3.26 B m e staggered 0 0 0 v 
2 0.005 1.895 3.19 B m e staggered 0 0 0 v 
2 0.005 1.9 3.015 B m e staggered 0 0 0 v 
2 0.005 1.9 3.055 B m e staggered 0 0 0 v 
2 0.005 1.915 4.13 B m e staggered 0 0 0 v 
2 0.005 1.9216 0.7784 B m e staggered 0 0 0 v 
2 0.005 0.199 2.83 B m e staggered 0 0 0 v 
2 0.005 2.15 0.69 B m e staggered 0 0 0 v 
2 0.005 2.176 4.151 B m e staggered 0 0 0 v 
2 0.005 2.18 3.811 B m e staggered 0 0 0 v 
2 0.005 2.2 0.69 B m e staggered 0 0 0 v 
2 0.005 2.215 3.785 B m e staggered 0 0 0 v 
2 0.005 2.215 4.15 B m e staggered 0 0 0 v 
2 0.005 2.256 4.151 B m e staggered 0 0 0 v 
2 0.005 2.26 3.785 B m e staggered 0 0 0 v 
2 0.005 2.295 4.15 B m e staggered 0 0 0 v 
2 0.005 2.41441 2.15 B m e staggered 0 0 0 v 
2 0.005 2.419 2.388 B m e staggered 0 0 0 v 
2 0.005 2.54 2.135 B m e staggered 0 0 0 v 
2 0.005 2.59 2.23 B m e staggered 0 0 0 v 
2 0.005 2.595 0.701 B m e staggered 0 0 0 v 
2 0.005 2.69 2.15 B m e staggered 0 0 0 v 
2 0.005 2.71 1.845 B m e staggered 0 0 0 v 
2 0.005 2.7233 0.54871 B m e staggered 0 0 0 v 
2 0.005 2.7526 2.23 B m e staggered 0 0 0 v 
2 0.005 2.805 2.243 B m e staggered 0 0 0 v 
2 0.005 2.822 1.79121 B m e staggered 0 0 0 v 
2 0.005 2.88 2.93 B m e staggered 0 0 0 v 
2 0.005 2.885 3.17 B m e staggered 0 0 0 v 
2 0.005 2.92 2.9472 B m e staggered 0 0 0 v 
2 0.005 2.985 1.845 B m e staggered 0 0 0 v 
2 0.005 2.995 2.955 B m e staggered 0 0 0 v 
2 0.005 3.01 3.12 B m e staggered 0 0 0 v 
2 0.005 3.035 0.694 B m e staggered 0 0 0 v 
2 0.005 3.08967 2.04 B m e staggered 0 0 0 v 
2 0.005 3.11 1.935 B m e staggered 0 0 0 v 
2 0.005 3.116 2.524 B m e staggered 0 0 0 v 
2 0.005 3.12 2.344 B m e staggered 0 0 0 v 
2 0.005 3.12 2.955 B m e staggered 0 0 0 v 
2 0.005 3.145 2.765 B m e staggered 0 0 0 v 
2 0.005 3.213 4.167 B m e staggered 0 0 0 v 
2 0.005 3.21899 3.43 B m e staggered 0 0 0 v 
2 0.005 3.248 4.107 B m e staggered 0 0 0 v 
2 0.005 3.248 4.152 B m e staggered 0 0 0 v 
2 0.005 3.253 3.872 B m e staggered 0 0 0 v 
2 0.005 3.253 3.917 B m e staggered 0 0 0 v 
2 0.005 3.253 3.962 B m e staggered 0 0 0 v 
2 0.005 3.26 3.74 B m e staggered 0 0 0 v 
2 0.005 3.305 2.915 B m e staggered 0 0 0 v 
2 0.005 3.315 3.76 B m e staggered 0 0 0 v 
2 0.005 3.38 3.15 B m e staggered 0 0 0 v 
2 0.005 3.385 3.76 B m e staggered 0 0 0 v 
2 0.005 3.40953 2.37 B m e staggered 0 0 0 v 
2 0.005 3.415 2.335 B m e staggered 0 0 0 v 
2 0.005 3.42 3.76 B m e staggered 0 0 0 v 
2 0.005 3.435 2.589 B m e staggered 0 0 0 v 
2 0.005 3.473 1.79 B m e staggered 0 0 0 v 
2 0.005 3.49 3.03 B m e staggered 0 0 0 v 
2 0.005 3.501 1.694 B m e staggered 0 0 0 v 
2 0.005 3.505 2.295 B m e staggered 0 0 0 v 
2 0.005 3.51 1.305 B m e staggered 0 0 0 v 
2 0.005 3.512 1.966 B m e staggered 0 0 0 v 
2 0.005 3.526 1.694 B m e staggered 0 0 0 v 
2 0.005 3.535 1.305 B m e staggered 0 0 0 v 
2 0.005 3.54 1.28 B m e staggered 0 0 0 v 
2 0.005 3.54975 2.479 B m e staggered 0 0 0 v 
2 0.005 3.55 2.425 B m e staggered 0 0 0 v 
2 0.005 3.551 1.694 B m e staggered 0 0 0 v 
2 0.005 3.555 3.065 B m e staggered 0 0 0 v 
2 0.005 3.56 1.305 B m e staggered 0 0 0 v 
2 0.005 3.576 1.694 B m e staggered 0 0 0 v 
2 0.005 3.6 4.024 B m e staggered 0 0 0 v 
2 0.005 3.60311 4.0988 B m e staggered 0 0 0 v 
2 0.005 3.605 2.43 B m e staggered 0 0 0 v 
2 0.005 3.615 2.961 B m e staggered 0 0 0 v 
2 0.005 3.621 2.91 B m e staggered 0 0 0 v 
2 0.005 3.623 2.861 B m e staggered 0 0 0 v 
2 0.005 3.631 4.183 B m e staggered 0 0 0 v 
2 0.005 3.631 4.228 B m e staggered 0 0 0 v 
2 0.005 3.636 1.766 B m e staggered 0 0 0 v 
2 0.005 3.645 2.13 B m e staggered 0 0 0 v 
2 0.005 3.647 1.694 B m e staggered 0 0 0 v 
2 0.005 3.658 2.861 B m e staggered 0 0 0 v 
2 0.005 3.658 2.911 B m e staggered 0 0 0 v 
2 0.005 3.67 1.26 B m e staggered 0 0 0 v 
2 0.005 3.67 2.13 B m e staggered 0 0 0 v 
2 0.005 3.67 2.41243 B m e staggered 0 0 0 v 
2 0.005 3.676 1.693 B m e staggered 0 0 0 v 
2 0.005 3.695 2.675 B m e staggered 0 0 0 v 
2 0.005 3.6956 2.13 B m e staggered 0 0 0 v 
2 0.005 3.703 2.911 B m e staggered 0 0 0 v 
2 0.005 3.718 1.29 B m e staggered 0 0 0 v 
2 0.005 3.718 1.32 B m e staggered 0 0 0 v 
2 0.005 3.7206 2.13 B m e staggered 0 0 0 v 
2 0.005 3.725 2.32 B m e staggered 0 0 0 v 
2 0.005 3.743 1.29 B m e staggered 0 0 0 v 
2 0.005 3.743 1.32 B m e staggered 0 0 0 v 
2 0.005 3.748 2.911 B m e staggered 0 0 0 v 
2 0.005 3.76838 1.0023 B m e staggered 0 0 0 v 
2 0.005 3.78 2.735 B m e staggered 0 0 0 v 
2 0.005 3.78 2.932 B m e staggered 0 0 0 v 
2 0.005 3.798 1.771 B m e staggered 0 0 0 v 
2 0.005 3.8 2.045 B m e staggered 0 0 0 v 
2 0.005 3.83 2.932 B m e staggered 0 0 0 v 
2 0.005 3.83 3.415 B m e staggered 0 0 0 v 
2 0.005 3.839 3.726 B m e staggered 0 0 0 v 
2 0.005 3.84 1.0298 B m e staggered 0 0 0 v 
2 0.005 3.84 1.095 B m e staggered 0 0 0 v 
2 0.005 3.843 3.687 B m e staggered 0 0 0 v 
2 0.005 3.933 3.125 B m e staggered 0 0 0 v 
2 0.005 3.973 3.207 B m e staggered 0 0 0 v 
2 0.005 3.975 3.129 B m e staggered 0 0 0 v 
2 0.005 3.978 2.593 B m e staggered 0 0 0 v 
2 0.005 3.98 3.52 B m e staggered 0 0 0 v 
2 0.005 3.99 2.21407 B m e staggered 0 0 0 v 
2 0.005 3.99 2.25 B m e staggered 0 0 0 v 
2 0.005 3.995 1.2 B m e staggered 0 0 0 v 
2 0.005 3.998 2.784 B m e staggered 0 0 0 v 
2 0.005 4.037 2.593 B m e staggered 0 0 0 v 
2 0.005 4.07 1.2 B m e staggered 0 0 0 v 
2 0.005 4.075 3.05 B m e staggered 0 0 0 v 
2 0.005 4.091 2.813 B m e staggered 0 0 0 v 
2 0.005 4.092 2.917 B m e staggered 0 0 0 v 
2 0.005 4.093 2.863 B m e staggered 0 0 0 v 
2 0.005 4.1 3.58543 B m e staggered 0 0 0 v 
2 0.005 4.135 0.885 B m e staggered 0 0 0 v 
2 0.005 4.175 3.52 B m e staggered 0 0 0 v 
2 0.005 0.42 2.368 B m e staggered 0 0 0 v 
2 0.005 4.22 0.775 B m e staggered 0 0 0 v 
2 0.005 4.23 1.005 B m e staggered 0 0 0 v 
2 0.005 4.278 1.003 B m e staggered 0 0 0 v 
2 0.005 4.294 1.075 B m e staggered 0 0 0 v 
2 0.005 4.31 1.165 B m e staggered 0 0 0 v 
2 0.005 4.31 4.16 B m e staggered 0 0 0 v 
2 0.005 4.335 1.005 B m e staggered 0 0 0 v 
2 0.005 4.345 0.77 B m e staggered 0 0 0 v 
2 0.005 4.395 2.665 B m e staggered 0 0 0 v 
2 0.005 4.44 2.26 B m e staggered 0 0 0 v 
2 0.005 4.44 2.5 B m e staggered 0 0 0 v 
2 0.005 4.44 2.63 B m e staggered 0 0 0 v 
2 0.005 4.442 1.005 B m e staggered 0 0 0 v 
2 0.005 4.46 3.745 B m e staggered 0 0 0 v 
2 0.005 4.472 3.475 B m e staggered 0 0 0 v 
2 0.005 4.4843 0.8954 B m e staggered 0 0 0 v 
2 0.005 4.5 1.082 B m e staggered 0 0 0 v 
2 0.005 4.5 4.07 B m e staggered 0 0 0 v 
2 0.005 4.54 3.935 B m e staggered 0 0 0 v 
2 0.005 4.54 3.97 B m e staggered 0 0 0 v 
2 0.005 4.546 1.085 B m e staggered 0 0 0 v 
2 0.005 0.455 1.26 B m e staggered 0 0 0 v 
2 0.005 0.455 1.61 B m e staggered 0 0 0 v 
2 0.005 4.59 3.26 B m e staggered 0 0 0 v 
2 0.005 4.595 3.22 B m e staggered 0 0 0 v 
2 0.005 4.6 2.845 B m e staggered 0 0 0 v 
2 0.005 4.6 2.895 B m e staggered 0 0 0 v 
2 0.005 4.62 2.245 B m e staggered 0 0 0 v 
2 0.005 4.62 2.5 B m e staggered 0 0 0 v 
2 0.005 4.635 0.865 B m e staggered 0 0 0 v 
2 0.005 0.47 1 B m e staggered 0 0 0 v 
2 0.005 4.71 3.47 B m e staggered 0 0 0 v 
2 0.005 4.714 3.633 B m e staggered 0 0 0 v 
2 0.005 0.476 0.689 B m e staggered 0 0 0 v 
2 0.005 4.775 2.59 B m e staggered 0 0 0 v 
2 0.005 4.78 1.98 B m e staggered 0 0 0 v 
2 0.005 4.79867 1.38867 B m e staggered 0 0 0 v 
2 0.005 4.81 0.707 B m e staggered 0 0 0 v 
2 0.005 4.815 1.82016 B m e staggered 0 0 0 v 
2 0.005 0.485 2.715 B m e staggered 0 0 0 v 
2 0.005 4.894 1.263 B m e staggered 0 0 0 v 
2 0.005 4.918 2.777 B m e staggered 0 0 0 v 
2 0.005 4.925 2.722 B m e staggered 0 0 0 v 
2 0.005 4.933 1.215 B m e staggered 0 0 0 v 
2 0.005 4.96 1.675 B m e staggered 0 0 0 v 
2 0.005 4.96 1.79258 B m e staggered 0 0 0 v 
2 0.005 4.96 2.055 B m e staggered 0 0 0 v 
2 0.005 4.965 1.925 B m e staggered 0 0 0 v 
2 0.005 5.0395 1.43 B m e staggered 0 0 0 v 
2 0.005 5.045 3.76 B m e staggered 0 0 0 v 
2 0.005 5.05 3.795 B m e staggered 0 0 0 v 
2 0.005 5.061 2.806 B m e staggered 0 0 0 v 
2 0.005 5.071 2.407 B m e staggered 0 0 0 v 
2 0.005 5.119 2.762 B m e staggered 0 0 0 v 
2 0.005 5.121 2.407 B m e staggered 0 0 0 v 
2 0.005 5.121 2.447 B m e staggered 0 0 0 v 
2 0.005 5.121 2.495 B m e staggered 0 0 0 v 
2 0.005 5.121 2.625 B m e staggered 0 0 0 v 
2 0.005 5.122 2.587 B m e staggered 0 0 0 v 
2 0.005 5.123 2.544 B m e staggered 0 0 0 v 
2 0.005 0.51772 1.305 B m e staggered 0 0 0 v 
2 0.005 0.51772 1.87987 B m e staggered 0 0 0 v 
2 0.005 0.51772 2.45074 B m e staggered 0 0 0 v 
2 0.005 0.51772 0.736 B m e staggered 0 0 0 v 
2 0.005 5.17 2.125 B m e staggered 0 0 0 v 
2 0.005 5.237 3.777 B m e staggered 0 0 0 v 
2 0.005 5.237 3.841 B m e staggered 0 0 0 v 
2 0.005 5.25176 4.11925 B m e staggered 0 0 0 v 
2 0.005 5.271 3.406 B m e staggered 0 0 0 v 
2 0.005 5.271 3.456 B m e staggered 0 0 0 v 
2 0.005 5.276 3.189 B m e staggered 0 0 0 v 
2 0.005 5.282 3.777 B m e staggered 0 0 0 v 
2 0.005 5.298 2.23 B m e staggered 0 0 0 v 
2 0.005 5.3035 2.5748 B m e staggered 0 0 0 v 
2 0.005 5.322 3.777 B m e staggered 0 0 0 v 
2 0.005 5.324 3.406 B m e staggered 0 0 0 v 
2 0.005 5.324 3.456 B m e staggered 0 0 0 v 
2 0.005 5.325 2.725 B m e staggered 0 0 0 v 
2 0.005 5.329 3.189 B m e staggered 0 0 0 v 
2 0.005 5.33 0.87 B m e staggered 0 0 0 v 
2 0.005 5.335 1.245 B m e staggered 0 0 0 v 
2 0.005 5.34 1.605 B m e staggered 0 0 0 v 
2 0.005 5.345 1.3 B m e staggered 0 0 0 v 
2 0.005 5.345 1.365 B m e staggered 0 0 0 v 
2 0.005 5.346 1.483 B m e staggered 0 0 0 v 
2 0.005 5.346 1.52 B m e staggered 0 0 0 v 
2 0.005 5.369 2.015 B m e staggered 0 0 0 v 
2 0.005 5.37 0.69 B m e staggered 0 0 0 v 
2 0.005 5.381 3.406 B m e staggered 0 0 0 v 
2 0.005 5.381 3.456 B m e staggered 0 0 0 v 
2 0.005 5.385 1.895 B m e staggered 0 0 0 v 
2 0.005 5.385 4.07875 B m e staggered 0 0 0 v 
2 0.005 5.386 3.189 B m e staggered 0 0 0 v 
2 0.005 0.539 1.57 B m e staggered 0 0 0 v 
2 0.005 5.409 2.015 B m e staggered 0 0 0 v 
2 0.005 5.41346 3.03507 B m e staggered 0 0 0 v 
2 0.005 5.425 1.895 B m e staggered 0 0 0 v 
2 0.005 5.43 3.967 B m e staggered 0 0 0 v 
2 0.005 5.435 2.05 B m e staggered 0 0 0 v 
2 0.005 5.43957 0.60543 B m e staggered 0 0 0 v 
2 0.005 5.44 1.59 B m e staggered 0 0 0 v 
2 0.005 5.49 2.675 B m e staggered 0 0 0 v 
2 0.005 5.517 2.563 B m e staggered 0 0 0 v 
2 0.005 5.538 2.402 B m e staggered 0 0 0 v 
2 0.005 5.59 0.85 B m e staggered 0 0 0 v 
2 0.005 5.59 0.888 B m e staggered 0 0 0 v 
2 0.005 5.59941 0.6212 B m e staggered 0 0 0 v 
2 0.005 5.602 3.865 B m e staggered 0 0 0 v 
2 0.005 5.602 0.815 B m e staggered 0 0 0 v 
2 0.005 5.625 0.746 B m e staggered 0 0 0 v 
2 0.005 5.63341 0.62102 B m e staggered 0 0 0 v 
2 0.005 5.645 3.79 B m e staggered 0 0 0 v 
2 0.005 5.647 2.044 B m e staggered 0 0 0 v 
2 0.005 5.687 2.043 B m e staggered 0 0 0 v 
2 0.005 5.732 2.043 B m e staggered 0 0 0 v 
2 0.005 0.575 2.185 B m e staggered 0 0 0 v 
2 0.005 5.75072 1.655 B m e staggered 0 0 0 v 
2 0.005 5.763 3.712 B m e staggered 0 0 0 v 
2 0.005 5.76459 1.61971 B m e staggered 0 0 0 v 
2 0.005 5.801 3.667 B m e staggered 0 0 0 v 
2 0.005 5.802 3.617 B m e staggered 0 0 0 v 
2 0.005 5.803 3.567 B m e staggered 0 0 0 v 
2 0.005 5.803 3.757 B m e staggered 0 0 0 v 
2 0.005 5.803 3.807 B m e staggered 0 0 0 v 
2 0.005 5.803 3.857 B m e staggered 0 0 0 v 
2 0.005 5.805 1.945 B m e staggered 0 0 0 v 
2 0.005 5.805 0.658 B m e staggered 0 0 0 v 
2 0.005 5.80643 0.609 B m e staggered 0 0 0 v 
2 0.005 5.814 2.9225 B m e staggered 0 0 0 v 
2 0.005 5.815 2.67 B m e staggered 0 0 0 v 
2 0.005 5.83 1.92 B m e staggered 0 0 0 v 
2 0.005 5.859 0.796 B m e staggered 0 0 0 v 
2 0.005 5.865 2.3 B m e staggered 0 0 0 v 
2 0.005 5.97703 1.87 B m e staggered 0 0 0 v 
2 0.005 5.99 0.925 B m e staggered 0 0 0 v 
2 0.005 0.606 1.612 B m e staggered 0 0 0 v 
2 0.005 6.105 2.27 B m e staggered 0 0 0 v 
2 0.005 0.614 1.049 B m e staggered 0 0 0 v 
2 0.005 0.61489 3.32329 B m e staggered 0 0 0 v 
2 0.005 6.141 2.241 B m e staggered 0 0 0 v 
2 0.005 6.165 1.94874 B m e staggered 0 0 0 v 
2 0.005 6.22 1.36 B m e staggered 0 0 0 v 
2 0.005 6.26989 2.37989 B m e staggered 0 0 0 v 
2 0.005 6.335 1.96874 B m e staggered 0 0 0 v 
2 0.005 6.335 3.015 B m e staggered 0 0 0 v 
2 0.005 0.635 3.596 B m e staggered 0 0 0 v 
2 0.005 6.36 2.16142 B m e staggered 0 0 0 v 
2 0.005 6.47 1.135 B m e staggered 0 0 0 v 
2 0.005 0.66 4.19 B m e staggered 0 0 0 v 
2 0.005 0.66 0.911 B m e staggered 0 0 0 v 
2 0.005 0.664 0.774 B m e staggered 0 0 0 v 
2 0.005 0.675 2.229 B m e staggered 0 0 0 v 
2 0.005 0.677 0.65 B m e staggered 0 0 0 v 
2 0.005 0.695 1 B m e staggered 0 0 0 v 
2 0.005 0.714 2.217 B m e staggered 0 0 0 v 
2 0.005 0.715 2.478 B m e staggered 0 0 0 v 
2 0.005 0.72 3.35 B m e staggered 0 0 0 v 
2 0.005 0.74593 2.02207 B m e staggered 0 0 0 v 
2 0.005 0.80148 2.53648 B m e staggered 0 0 0 v 
2 0.005 0.83 4.17 B m e staggered 0 0 0 v 
2 0.005 0.833 0.871 B m e staggered 0 0 0 v 
2 0.005 0.8575 2.0275 B m e staggered 0 0 0 v 
2 0.005 0.866 1.413 B m e staggered 0 0 0 v 
2 0.005 0.872 2.583 B m e staggered 0 0 0 v 
2 0.005 0.889 0.67 B m e staggered 0 0 0 v 
2 0.005 0.93032 2.46477 B m e staggered 0 0 0 v 
2 0.005 0.94 4.2 B m e staggered 0 0 0 v 
2 0.005 0.945 1.05 B m e staggered 0 0 0 v 
2 0.005 0.95593 3.33347 B m e staggered 0 0 0 v 
2 0.005 0.988 2.724 B m e staggered 0 0 0 v 
2 0.005 0.99 3.5 B m e staggered 0 0 0 v 
2 0.005 1.6985 2.9895 B m e staggered 0 0 0 v 
2 0.005 4.0965 3.9445 B m e staggered 0 0 0 v 
2 0.005 4.0965 4.0395 B m e staggered 0 0 0 v 
2 0.005 4.1235 3.9715 B m e staggered 0 0 0 v 
2 0.005 4.1235 4.0125 B m e staggered 0 0 0 v 
2 0.005 4.1645 3.9715 B m e staggered 0 0 0 v 
2 0.005 4.1645 4.0125 B m e staggered 0 0 0 v 
2 0.005 4.1915 3.9445 B m e staggered 0 0 0 v 
2 0.005 4.1915 4.0395 B m e staggered 0 0 0 v 
2 0.005 5.1265 2.6815 B m e staggered 0 0 0 v 
2 0.005 5.6435 0.6535 B m e staggered 0 0 0 v 
2 0.005 5.9645 2.1035 B m e staggered 0 0 0 v 
2 0.005 6.0155 2.0845 B m e staggered 0 0 0 v 
2 0.005 1.5086 0.674 B m e staggered 0 0 0 v 
2 0.005 1.746 4.106 B m e staggered 0 0 0 v 
2 0.005 1.751 3.826 B m e staggered 0 0 0 v 
2 0.005 2.285 3.825 B m e staggered 0 0 0 v 
2 0.005 3.12 2.17 B m e staggered 0 0 0 v 
2 0.005 3.213 4.236 B m e staggered 0 0 0 v 
2 0.005 3.285 2.589 B m e staggered 0 0 0 v 
2 0.005 3.67 2.32 B m e staggered 0 0 0 v 
2 0.005 4.414 0.781 B m e staggered 0 0 0 v 
2 0.005 4.71 2.592 B m e staggered 0 0 0 v 
2 0.005 5.332 2.2 B m e staggered 0 0 0 v 
2 0.005 5.48557 3.877 B m e staggered 0 0 0 v 
2 0.005 5.637 3.524 B m e staggered 0 0 0 v 
2 0.005 0.575 2.89 B m e staggered 0 0 0 v 
2 0.005 5.92 1.36 B m e staggered 0 0 0 v 
2 0.005 0.987 2.683 B m e staggered 0 0 0 v 
2 0.004 1.00413 4.33598 B m e staggered 0 0 0 v 
2 0.004 1.0146 0.54197 B m e staggered 0 0 0 v 
2 0.004 1.041 3.825 B m e staggered 0 0 0 v 
2 0.004 1.04413 4.33598 B m e staggered 0 0 0 v 
2 0.004 1.0546 0.54197 B m e staggered 0 0 0 v 
2 0.004 1.08413 4.33598 B m e staggered 0 0 0 v 
2 0.004 1.0946 0.54197 B m e staggered 0 0 0 v 
2 0.004 1.12413 4.33598 B m e staggered 0 0 0 v 
2 0.004 1.1346 0.54197 B m e staggered 0 0 0 v 
2 0.004 1.137 3.825 B m e staggered 0 0 0 v 
2 0.004 1.16413 4.33598 B m e staggered 0 0 0 v 
2 0.004 1.1746 0.54197 B m e staggered 0 0 0 v 
2 0.004 1.20413 4.33598 B m e staggered 0 0 0 v 
2 0.004 1.2146 0.54197 B m e staggered 0 0 0 v 
2 0.004 0.12413 4.33598 B m e staggered 0 0 0 v 
2 0.004 1.24413 4.33598 B m e staggered 0 0 0 v 
2 0.004 1.2546 0.54197 B m e staggered 0 0 0 v 
2 0.004 0.12878 0.21717 B m e staggered 0 0 0 v 
2 0.004 1.28413 4.33598 B m e staggered 0 0 0 v 
2 0.004 1.2945 0.53917 B m e staggered 0 0 0 v 
2 0.004 1.32413 4.33598 B m e staggered 0 0 0 v 
2 0.004 1.3292 0.51926 B m e staggered 0 0 0 v 
2 0.004 1.34977 0.48496 B m e staggered 0 0 0 v 
2 0.004 1.35299 0.24509 B m e staggered 0 0 0 v 
2 0.004 1.35299 0.28509 B m e staggered 0 0 0 v 
2 0.004 1.35299 0.32509 B m e staggered 0 0 0 v 
2 0.004 1.35299 0.36509 B m e staggered 0 0 0 v 
2 0.004 1.35299 0.40509 B m e staggered 0 0 0 v 
2 0.004 1.35299 0.44509 B m e staggered 0 0 0 v 
2 0.004 1.36413 4.33598 B m e staggered 0 0 0 v 
2 0.004 1.38163 0.21717 B m e staggered 0 0 0 v 
2 0.004 1.385 0.75 B m e staggered 0 0 0 v 
2 0.004 1.40413 4.33598 B m e staggered 0 0 0 v 
2 0.004 1.42163 0.21717 B m e staggered 0 0 0 v 
2 0.004 1.44 0.625 B m e staggered 0 0 0 v 
2 0.004 1.44413 4.33598 B m e staggered 0 0 0 v 
2 0.004 1.46163 0.21717 B m e staggered 0 0 0 v 
2 0.004 1.48413 4.33598 B m e staggered 0 0 0 v 
2 0.004 1.50163 0.21717 B m e staggered 0 0 0 v 
2 0.004 1.5184 0.79935 B m e staggered 0 0 0 v 
2 0.004 1.52413 4.33598 B m e staggered 0 0 0 v 
2 0.004 1.54163 0.21717 B m e staggered 0 0 0 v 
2 0.004 1.56413 4.33598 B m e staggered 0 0 0 v 
2 0.004 1.58163 0.21717 B m e staggered 0 0 0 v 
2 0.004 1.58795 0.25667 B m e staggered 0 0 0 v 
2 0.004 1.58795 0.29667 B m e staggered 0 0 0 v 
2 0.004 1.58795 0.33667 B m e staggered 0 0 0 v 
2 0.004 1.58795 0.37667 B m e staggered 0 0 0 v 
2 0.004 1.58795 0.41667 B m e staggered 0 0 0 v 
2 0.004 1.59112 0.45654 B m e staggered 0 0 0 v 
2 0.004 1.60413 4.33598 B m e staggered 0 0 0 v 
2 0.004 1.60736 0.49309 B m e staggered 0 0 0 v 
2 0.004 1.63543 0.52159 B m e staggered 0 0 0 v 
2 0.004 0.16413 4.33598 B m e staggered 0 0 0 v 
2 0.004 1.64413 4.33598 B m e staggered 0 0 0 v 
2 0.004 1.671 4.056 B m e staggered 0 0 0 v 
2 0.004 0.16878 0.21717 B m e staggered 0 0 0 v 
2 0.004 1.68413 4.33598 B m e staggered 0 0 0 v 
2 0.004 1.72413 4.33598 B m e staggered 0 0 0 v 
2 0.004 1.76413 4.33598 B m e staggered 0 0 0 v 
2 0.004 1.78196 0.50601 B m e staggered 0 0 0 v 
2 0.004 1.80341 0.47225 B m e staggered 0 0 0 v 
2 0.004 1.80413 4.33598 B m e staggered 0 0 0 v 
2 0.004 1.84413 4.33598 B m e staggered 0 0 0 v 
2 0.004 1.88413 4.33598 B m e staggered 0 0 0 v 
2 0.004 1.91535 0.289 B m e staggered 0 0 0 v 
2 0.004 1.92413 4.33598 B m e staggered 0 0 0 v 
2 0.004 1.96413 4.33598 B m e staggered 0 0 0 v 
2 0.004 2.00413 4.33598 B m e staggered 0 0 0 v 
2 0.004 2.0195 0.2905 B m e staggered 0 0 0 v 
2 0.004 0.20413 4.33598 B m e staggered 0 0 0 v 
2 0.004 2.04413 4.33598 B m e staggered 0 0 0 v 
2 0.004 0.20878 0.21717 B m e staggered 0 0 0 v 
2 0.004 2.083 2.895 B m e staggered 0 0 0 v 
2 0.004 2.08413 4.33598 B m e staggered 0 0 0 v 
2 0.004 2.0966 3.315 B m e staggered 0 0 0 v 
2 0.004 2.12413 4.33598 B m e staggered 0 0 0 v 
2 0.004 2.16413 4.33598 B m e staggered 0 0 0 v 
2 0.004 2.173 2.895 B m e staggered 0 0 0 v 
2 0.004 2.20413 4.33598 B m e staggered 0 0 0 v 
2 0.004 2.218 2.895 B m e staggered 0 0 0 v 
2 0.004 2.24413 4.33598 B m e staggered 0 0 0 v 
2 0.004 2.28413 4.33598 B m e staggered 0 0 0 v 
2 0.004 2.32413 4.33598 B m e staggered 0 0 0 v 
2 0.004 2.327 0.291 B m e staggered 0 0 0 v 
2 0.004 2.36413 4.33598 B m e staggered 0 0 0 v 
2 0.004 2.40413 4.33598 B m e staggered 0 0 0 v 
2 0.004 2.40508 0.667 B m e staggered 0 0 0 v 
2 0.004 2.40508 0.763 B m e staggered 0 0 0 v 
2 0.004 2.43822 0.763 B m e staggered 0 0 0 v 
2 0.004 0.24413 4.33598 B m e staggered 0 0 0 v 
2 0.004 2.44413 4.33598 B m e staggered 0 0 0 v 
2 0.004 2.44619 0.289 B m e staggered 0 0 0 v 
2 0.004 0.24878 0.21717 B m e staggered 0 0 0 v 
2 0.004 2.48413 4.33598 B m e staggered 0 0 0 v 
2 0.004 2.52413 4.33598 B m e staggered 0 0 0 v 
2 0.004 2.53422 0.763 B m e staggered 0 0 0 v 
2 0.004 2.54527 0.289 B m e staggered 0 0 0 v 
2 0.004 2.56413 4.33598 B m e staggered 0 0 0 v 
2 0.004 2.60413 4.33598 B m e staggered 0 0 0 v 
2 0.004 2.63507 0.763 B m e staggered 0 0 0 v 
2 0.004 2.64304 0.289 B m e staggered 0 0 0 v 
2 0.004 2.64339 0.321 B m e staggered 0 0 0 v 
2 0.004 2.64339 0.417 B m e staggered 0 0 0 v 
2 0.004 2.64413 4.33598 B m e staggered 0 0 0 v 
2 0.004 2.68413 4.33598 B m e staggered 0 0 0 v 
2 0.004 2.72309 0.289 B m e staggered 0 0 0 v 
2 0.004 2.72413 4.33598 B m e staggered 0 0 0 v 
2 0.004 2.73107 0.763 B m e staggered 0 0 0 v 
2 0.004 2.76413 4.33598 B m e staggered 0 0 0 v 
2 0.004 2.77 1.987 B m e staggered 0 0 0 v 
2 0.004 2.78655 0.763 B m e staggered 0 0 0 v 
2 0.004 2.80052 0.289 B m e staggered 0 0 0 v 
2 0.004 2.80087 0.321 B m e staggered 0 0 0 v 
2 0.004 2.80087 0.417 B m e staggered 0 0 0 v 
2 0.004 2.80413 4.33598 B m e staggered 0 0 0 v 
2 0.004 0.28413 4.33598 B m e staggered 0 0 0 v 
2 0.004 2.84413 4.33598 B m e staggered 0 0 0 v 
2 0.004 2.845 1.811 B m e staggered 0 0 0 v 
2 0.004 2.845 1.907 B m e staggered 0 0 0 v 
2 0.004 2.86151 3.295 B m e staggered 0 0 0 v 
2 0.004 2.866 1.987 B m e staggered 0 0 0 v 
2 0.004 0.28878 0.21717 B m e staggered 0 0 0 v 
2 0.004 2.88057 0.289 B m e staggered 0 0 0 v 
2 0.004 2.88255 0.763 B m e staggered 0 0 0 v 
2 0.004 2.88413 4.33598 B m e staggered 0 0 0 v 
2 0.004 2.92413 4.33598 B m e staggered 0 0 0 v 
2 0.004 2.958 0.289 B m e staggered 0 0 0 v 
2 0.004 2.95835 0.321 B m e staggered 0 0 0 v 
2 0.004 2.95835 0.417 B m e staggered 0 0 0 v 
2 0.004 2.96413 4.33598 B m e staggered 0 0 0 v 
2 0.004 2.98726 0.43529 B m e staggered 0 0 0 v 
2 0.004 2.98726 0.49471 B m e staggered 0 0 0 v 
2 0.004 3.00413 4.33598 B m e staggered 0 0 0 v 
2 0.004 3.04413 4.33598 B m e staggered 0 0 0 v 
2 0.004 3.07708 0.289 B m e staggered 0 0 0 v 
2 0.004 3.08413 4.33598 B m e staggered 0 0 0 v 
2 0.004 3.10237 0.89763 B m e staggered 0 0 0 v 
2 0.004 3.106 3.305 B m e staggered 0 0 0 v 
2 0.004 3.12413 4.33598 B m e staggered 0 0 0 v 
2 0.004 3.16413 4.33598 B m e staggered 0 0 0 v 
2 0.004 3.17025 0.82975 B m e staggered 0 0 0 v 
2 0.004 3.17402 0.54197 B m e staggered 0 0 0 v 
2 0.004 3.1951 1.90299 B m e staggered 0 0 0 v 
2 0.004 3.20413 4.33598 B m e staggered 0 0 0 v 
2 0.004 3.21402 0.54197 B m e staggered 0 0 0 v 
2 0.004 3.222 3.25 B m e staggered 0 0 0 v 
2 0.004 0.32413 4.33598 B m e staggered 0 0 0 v 
2 0.004 3.24413 4.33598 B m e staggered 0 0 0 v 
2 0.004 3.25402 0.54197 B m e staggered 0 0 0 v 
2 0.004 0.32878 0.21717 B m e staggered 0 0 0 v 
2 0.004 3.28413 4.33598 B m e staggered 0 0 0 v 
2 0.004 3.2911 1.90299 B m e staggered 0 0 0 v 
2 0.004 3.29402 0.54197 B m e staggered 0 0 0 v 
2 0.004 3.32413 4.33598 B m e staggered 0 0 0 v 
2 0.004 3.33402 0.54197 B m e staggered 0 0 0 v 
2 0.004 3.36413 4.33598 B m e staggered 0 0 0 v 
2 0.004 3.37402 0.54197 B m e staggered 0 0 0 v 
2 0.004 3.375 1.13 B m e staggered 0 0 0 v 
2 0.004 3.375 1.226 B m e staggered 0 0 0 v 
2 0.004 3.38599 1.085 B m e staggered 0 0 0 v 
2 0.004 3.40413 4.33598 B m e staggered 0 0 0 v 
2 0.004 3.41402 0.54197 B m e staggered 0 0 0 v 
2 0.004 3.44413 4.33598 B m e staggered 0 0 0 v 
2 0.004 3.45301 1.86699 B m e staggered 0 0 0 v 
2 0.004 3.45301 1.96299 B m e staggered 0 0 0 v 
2 0.004 3.45402 0.54197 B m e staggered 0 0 0 v 
2 0.004 3.48199 1.085 B m e staggered 0 0 0 v 
2 0.004 3.48264 1.04707 B m e staggered 0 0 0 v 
2 0.004 3.48413 4.33598 B m e staggered 0 0 0 v 
2 0.004 3.49402 0.54197 B m e staggered 0 0 0 v 
2 0.004 3.52413 4.33598 B m e staggered 0 0 0 v 
2 0.004 3.53402 0.54197 B m e staggered 0 0 0 v 
2 0.004 3.548 2.898 B m e staggered 0 0 0 v 
2 0.004 3.5485 2.761 B m e staggered 0 0 0 v 
2 0.004 3.55 3.325 B m e staggered 0 0 0 v 
2 0.004 3.56413 4.33598 B m e staggered 0 0 0 v 
2 0.004 3.57402 0.54197 B m e staggered 0 0 0 v 
2 0.004 3.57864 1.04707 B m e staggered 0 0 0 v 
2 0.004 3.593 0.92 B m e staggered 0 0 0 v 
2 0.004 3.60413 4.33598 B m e staggered 0 0 0 v 
2 0.004 3.61402 0.54197 B m e staggered 0 0 0 v 
2 0.004 0.36413 4.33598 B m e staggered 0 0 0 v 
2 0.004 3.64413 4.33598 B m e staggered 0 0 0 v 
2 0.004 3.65101 1.85159 B m e staggered 0 0 0 v 
2 0.004 3.65101 1.94759 B m e staggered 0 0 0 v 
2 0.004 3.65402 0.54197 B m e staggered 0 0 0 v 
2 0.004 0.36878 0.21717 B m e staggered 0 0 0 v 
2 0.004 3.68413 4.33598 B m e staggered 0 0 0 v 
2 0.004 3.689 0.92 B m e staggered 0 0 0 v 
2 0.004 3.69402 0.54197 B m e staggered 0 0 0 v 
2 0.004 3.72413 4.33598 B m e staggered 0 0 0 v 
2 0.004 3.73402 0.54197 B m e staggered 0 0 0 v 
2 0.004 3.735 0.78 B m e staggered 0 0 0 v 
2 0.004 3.735 0.94 B m e staggered 0 0 0 v 
2 0.004 3.76413 4.33598 B m e staggered 0 0 0 v 
2 0.004 3.77402 0.54197 B m e staggered 0 0 0 v 
2 0.004 3.80413 4.33598 B m e staggered 0 0 0 v 
2 0.004 3.805 0.774 B m e staggered 0 0 0 v 
2 0.004 3.81402 0.54197 B m e staggered 0 0 0 v 
2 0.004 3.84413 4.33598 B m e staggered 0 0 0 v 
2 0.004 3.85402 0.54197 B m e staggered 0 0 0 v 
2 0.004 3.88413 4.33598 B m e staggered 0 0 0 v 
2 0.004 3.89402 0.54197 B m e staggered 0 0 0 v 
2 0.004 3.9 1.005 B m e staggered 0 0 0 v 
2 0.004 3.92413 4.33598 B m e staggered 0 0 0 v 
2 0.004 3.93402 0.54197 B m e staggered 0 0 0 v 
2 0.004 3.96413 4.33598 B m e staggered 0 0 0 v 
2 0.004 3.97402 0.54197 B m e staggered 0 0 0 v 
2 0.004 3.9845 1.16099 B m e staggered 0 0 0 v 
2 0.004 0.04 0.25619 B m e staggered 0 0 0 v 
2 0.004 0.04 2.81619 B m e staggered 0 0 0 v 
2 0.004 0.04 2.85619 B m e staggered 0 0 0 v 
2 0.004 0.04 2.89619 B m e staggered 0 0 0 v 
2 0.004 0.04 2.93619 B m e staggered 0 0 0 v 
2 0.004 0.04 0.29619 B m e staggered 0 0 0 v 
2 0.004 0.04 2.97619 B m e staggered 0 0 0 v 
2 0.004 0.04 3.01619 B m e staggered 0 0 0 v 
2 0.004 0.04 3.05619 B m e staggered 0 0 0 v 
2 0.004 0.04 3.09619 B m e staggered 0 0 0 v 
2 0.004 0.04 3.13619 B m e staggered 0 0 0 v 
2 0.004 0.04 0.33619 B m e staggered 0 0 0 v 
2 0.004 0.04 3.37619 B m e staggered 0 0 0 v 
2 0.004 0.04 3.41619 B m e staggered 0 0 0 v 
2 0.004 0.04 3.45619 B m e staggered 0 0 0 v 
2 0.004 0.04 3.49619 B m e staggered 0 0 0 v 
2 0.004 0.04 3.53619 B m e staggered 0 0 0 v 
2 0.004 0.04 3.57619 B m e staggered 0 0 0 v 
2 0.004 0.04 3.61619 B m e staggered 0 0 0 v 
2 0.004 0.04 3.65619 B m e staggered 0 0 0 v 
2 0.004 0.04 3.69619 B m e staggered 0 0 0 v 
2 0.004 0.04 3.73619 B m e staggered 0 0 0 v 
2 0.004 0.04 0.37619 B m e staggered 0 0 0 v 
2 0.004 0.04 3.77619 B m e staggered 0 0 0 v 
2 0.004 0.04 3.81619 B m e staggered 0 0 0 v 
2 0.004 0.04 3.85619 B m e staggered 0 0 0 v 
2 0.004 0.04 3.89619 B m e staggered 0 0 0 v 
2 0.004 0.04 3.93619 B m e staggered 0 0 0 v 
2 0.004 0.04 3.97619 B m e staggered 0 0 0 v 
2 0.004 0.04 4.01619 B m e staggered 0 0 0 v 
2 0.004 0.04 4.05619 B m e staggered 0 0 0 v 
2 0.004 0.04 4.09619 B m e staggered 0 0 0 v 
2 0.004 0.04 4.13619 B m e staggered 0 0 0 v 
2 0.004 0.04 0.41619 B m e staggered 0 0 0 v 
2 0.004 0.04 4.17619 B m e staggered 0 0 0 v 
2 0.004 0.04 4.21619 B m e staggered 0 0 0 v 
2 0.004 0.04 4.25619 B m e staggered 0 0 0 v 
2 0.004 0.04 4.29619 B m e staggered 0 0 0 v 
2 0.004 0.04 0.45619 B m e staggered 0 0 0 v 
2 0.004 0.04 0.49619 B m e staggered 0 0 0 v 
2 0.004 4.00413 4.33598 B m e staggered 0 0 0 v 
2 0.004 4.01402 0.54197 B m e staggered 0 0 0 v 
2 0.004 0.40413 4.33598 B m e staggered 0 0 0 v 
2 0.004 4.04413 4.33598 B m e staggered 0 0 0 v 
2 0.004 4.05402 0.54197 B m e staggered 0 0 0 v 
2 0.004 0.40878 0.21717 B m e staggered 0 0 0 v 
2 0.004 4.0805 1.16099 B m e staggered 0 0 0 v 
2 0.004 4.08413 4.33598 B m e staggered 0 0 0 v 
2 0.004 4.092 1.005 B m e staggered 0 0 0 v 
2 0.004 4.09402 0.54197 B m e staggered 0 0 0 v 
2 0.004 4.12413 4.33598 B m e staggered 0 0 0 v 
2 0.004 4.13402 0.54197 B m e staggered 0 0 0 v 
2 0.004 4.13622 0.75 B m e staggered 0 0 0 v 
2 0.004 4.16413 4.33598 B m e staggered 0 0 0 v 
2 0.004 4.17402 0.54197 B m e staggered 0 0 0 v 
2 0.004 4.20413 4.33598 B m e staggered 0 0 0 v 
2 0.004 4.21402 0.54197 B m e staggered 0 0 0 v 
2 0.004 4.24413 4.33598 B m e staggered 0 0 0 v 
2 0.004 4.25402 0.54197 B m e staggered 0 0 0 v 
2 0.004 4.28413 4.33598 B m e staggered 0 0 0 v 
2 0.004 4.29402 0.54197 B m e staggered 0 0 0 v 
2 0.004 4.32413 4.33598 B m e staggered 0 0 0 v 
2 0.004 4.33402 0.54197 B m e staggered 0 0 0 v 
2 0.004 4.3445 1.16599 B m e staggered 0 0 0 v 
2 0.004 4.36413 4.33598 B m e staggered 0 0 0 v 
2 0.004 4.37402 0.54197 B m e staggered 0 0 0 v 
2 0.004 4.395 3.37892 B m e staggered 0 0 0 v 
2 0.004 0.04413 4.33598 B m e staggered 0 0 0 v 
2 0.004 4.40413 4.33598 B m e staggered 0 0 0 v 
2 0.004 4.41402 0.54197 B m e staggered 0 0 0 v 
2 0.004 4.43 3.965 B m e staggered 0 0 0 v 
2 0.004 4.43 4.015 B m e staggered 0 0 0 v 
2 0.004 0.44413 4.33598 B m e staggered 0 0 0 v 
2 0.004 4.44 4.165 B m e staggered 0 0 0 v 
2 0.004 4.4405 1.16599 B m e staggered 0 0 0 v 
2 0.004 4.44413 4.33598 B m e staggered 0 0 0 v 
2 0.004 4.45402 0.54197 B m e staggered 0 0 0 v 
2 0.004 4.465 2.895 B m e staggered 0 0 0 v 
2 0.004 0.44878 0.21717 B m e staggered 0 0 0 v 
2 0.004 4.48413 4.33598 B m e staggered 0 0 0 v 
2 0.004 4.49402 0.54197 B m e staggered 0 0 0 v 
2 0.004 4.5093 1.22167 B m e staggered 0 0 0 v 
2 0.004 4.52413 4.33598 B m e staggered 0 0 0 v 
2 0.004 4.53402 0.54197 B m e staggered 0 0 0 v 
2 0.004 4.56413 4.33598 B m e staggered 0 0 0 v 
2 0.004 4.57402 0.54197 B m e staggered 0 0 0 v 
2 0.004 4.60413 4.33598 B m e staggered 0 0 0 v 
2 0.004 4.6053 1.22167 B m e staggered 0 0 0 v 
2 0.004 4.61402 0.54197 B m e staggered 0 0 0 v 
2 0.004 4.64413 4.33598 B m e staggered 0 0 0 v 
2 0.004 4.65402 0.54197 B m e staggered 0 0 0 v 
2 0.004 4.68413 4.33598 B m e staggered 0 0 0 v 
2 0.004 4.69402 0.54197 B m e staggered 0 0 0 v 
2 0.004 4.72413 4.33598 B m e staggered 0 0 0 v 
2 0.004 4.73402 0.54197 B m e staggered 0 0 0 v 
2 0.004 4.76413 4.33598 B m e staggered 0 0 0 v 
2 0.004 4.77402 0.54197 B m e staggered 0 0 0 v 
2 0.004 0.04878 0.21717 B m e staggered 0 0 0 v 
2 0.004 4.80413 4.33598 B m e staggered 0 0 0 v 
2 0.004 4.81402 0.54197 B m e staggered 0 0 0 v 
2 0.004 0.48413 4.33598 B m e staggered 0 0 0 v 
2 0.004 4.84413 4.33598 B m e staggered 0 0 0 v 
2 0.004 4.85402 0.54197 B m e staggered 0 0 0 v 
2 0.004 0.48878 0.21717 B m e staggered 0 0 0 v 
2 0.004 4.88413 4.33598 B m e staggered 0 0 0 v 
2 0.004 4.89402 0.54197 B m e staggered 0 0 0 v 
2 0.004 4.92413 4.33598 B m e staggered 0 0 0 v 
2 0.004 4.93402 0.54197 B m e staggered 0 0 0 v 
2 0.004 4.96413 4.33598 B m e staggered 0 0 0 v 
2 0.004 4.97402 0.54197 B m e staggered 0 0 0 v 
2 0.004 5.00413 4.33598 B m e staggered 0 0 0 v 
2 0.004 5.01402 0.54197 B m e staggered 0 0 0 v 
2 0.004 5.04413 4.33598 B m e staggered 0 0 0 v 
2 0.004 5.05402 0.54197 B m e staggered 0 0 0 v 
2 0.004 5.08413 4.33598 B m e staggered 0 0 0 v 
2 0.004 5.09402 0.54197 B m e staggered 0 0 0 v 
2 0.004 5.12413 4.33598 B m e staggered 0 0 0 v 
2 0.004 5.13402 0.54197 B m e staggered 0 0 0 v 
2 0.004 5.16413 4.33598 B m e staggered 0 0 0 v 
2 0.004 5.17402 0.54197 B m e staggered 0 0 0 v 
2 0.004 5.20413 4.33598 B m e staggered 0 0 0 v 
2 0.004 5.21402 0.54197 B m e staggered 0 0 0 v 
2 0.004 0.52413 4.33598 B m e staggered 0 0 0 v 
2 0.004 5.24413 4.33598 B m e staggered 0 0 0 v 
2 0.004 5.25402 0.54197 B m e staggered 0 0 0 v 
2 0.004 0.52878 0.21717 B m e staggered 0 0 0 v 
2 0.004 5.28413 4.33598 B m e staggered 0 0 0 v 
2 0.004 5.29402 0.54197 B m e staggered 0 0 0 v 
2 0.004 5.32413 4.33598 B m e staggered 0 0 0 v 
2 0.004 5.33402 0.54197 B m e staggered 0 0 0 v 
2 0.004 5.36413 4.33598 B m e staggered 0 0 0 v 
2 0.004 5.37402 0.54197 B m e staggered 0 0 0 v 
2 0.004 5.40413 4.33598 B m e staggered 0 0 0 v 
2 0.004 5.41402 0.54197 B m e staggered 0 0 0 v 
2 0.004 5.44413 4.33598 B m e staggered 0 0 0 v 
2 0.004 5.45402 0.54197 B m e staggered 0 0 0 v 
2 0.004 5.48413 4.33598 B m e staggered 0 0 0 v 
2 0.004 5.49402 0.54197 B m e staggered 0 0 0 v 
2 0.004 0.55055 0.25073 B m e staggered 0 0 0 v 
2 0.004 0.55055 0.29073 B m e staggered 0 0 0 v 
2 0.004 0.55055 0.33073 B m e staggered 0 0 0 v 
2 0.004 0.55055 0.37073 B m e staggered 0 0 0 v 
2 0.004 0.55055 0.41073 B m e staggered 0 0 0 v 
2 0.004 0.55055 0.45073 B m e staggered 0 0 0 v 
2 0.004 5.52413 4.33598 B m e staggered 0 0 0 v 
2 0.004 5.53402 0.54197 B m e staggered 0 0 0 v 
2 0.004 0.55558 0.49041 B m e staggered 0 0 0 v 
2 0.004 5.56413 4.33598 B m e staggered 0 0 0 v 
2 0.004 5.57402 0.54197 B m e staggered 0 0 0 v 
2 0.004 5.60413 4.33598 B m e staggered 0 0 0 v 
2 0.004 5.61402 0.54197 B m e staggered 0 0 0 v 
2 0.004 0.56413 4.33598 B m e staggered 0 0 0 v 
2 0.004 5.64413 4.33598 B m e staggered 0 0 0 v 
2 0.004 5.65402 0.54197 B m e staggered 0 0 0 v 
2 0.004 5.666 2.129 B m e staggered 0 0 0 v 
2 0.004 5.68413 4.33598 B m e staggered 0 0 0 v 
2 0.004 5.69402 0.54197 B m e staggered 0 0 0 v 
2 0.004 5.72413 4.33598 B m e staggered 0 0 0 v 
2 0.004 5.73402 0.54197 B m e staggered 0 0 0 v 
2 0.004 5.76413 4.33598 B m e staggered 0 0 0 v 
2 0.004 5.77402 0.54197 B m e staggered 0 0 0 v 
2 0.004 0.57859 0.52313 B m e staggered 0 0 0 v 
2 0.004 5.80413 4.33598 B m e staggered 0 0 0 v 
2 0.004 5.81402 0.54197 B m e staggered 0 0 0 v 
2 0.004 5.84413 4.33598 B m e staggered 0 0 0 v 
2 0.004 5.85402 0.54197 B m e staggered 0 0 0 v 
2 0.004 5.88413 4.33598 B m e staggered 0 0 0 v 
2 0.004 5.89402 0.54197 B m e staggered 0 0 0 v 
2 0.004 5.92413 4.33598 B m e staggered 0 0 0 v 
2 0.004 5.93402 0.54197 B m e staggered 0 0 0 v 
2 0.004 5.96413 4.33598 B m e staggered 0 0 0 v 
2 0.004 5.97402 0.54197 B m e staggered 0 0 0 v 
2 0.004 6.00413 4.33598 B m e staggered 0 0 0 v 
2 0.004 6.01402 0.54197 B m e staggered 0 0 0 v 
2 0.004 0.60413 4.33598 B m e staggered 0 0 0 v 
2 0.004 6.04413 4.33598 B m e staggered 0 0 0 v 
2 0.004 6.05402 0.54197 B m e staggered 0 0 0 v 
2 0.004 6.08413 4.33598 B m e staggered 0 0 0 v 
2 0.004 6.09402 0.54197 B m e staggered 0 0 0 v 
2 0.004 6.12413 4.33598 B m e staggered 0 0 0 v 
2 0.004 6.13402 0.54197 B m e staggered 0 0 0 v 
2 0.004 0.61463 0.54048 B m e staggered 0 0 0 v 
2 0.004 6.16413 4.33598 B m e staggered 0 0 0 v 
2 0.004 6.17402 0.54197 B m e staggered 0 0 0 v 
2 0.004 6.19961 2.21274 B m e staggered 0 0 0 v 
2 0.004 6.19961 2.30874 B m e staggered 0 0 0 v 
2 0.004 6.20413 4.33598 B m e staggered 0 0 0 v 
2 0.004 6.21402 0.54197 B m e staggered 0 0 0 v 
2 0.004 6.24413 4.33598 B m e staggered 0 0 0 v 
2 0.004 6.25402 0.54197 B m e staggered 0 0 0 v 
2 0.004 6.28413 4.33598 B m e staggered 0 0 0 v 
2 0.004 6.29402 0.54197 B m e staggered 0 0 0 v 
2 0.004 6.32413 4.33598 B m e staggered 0 0 0 v 
2 0.004 6.36413 4.33598 B m e staggered 0 0 0 v 
2 0.004 6.40413 4.33598 B m e staggered 0 0 0 v 
2 0.004 0.64413 4.33598 B m e staggered 0 0 0 v 
2 0.004 6.44413 4.33598 B m e staggered 0 0 0 v 
2 0.004 6.48413 4.33598 B m e staggered 0 0 0 v 
2 0.004 6.49402 0.54197 B m e staggered 0 0 0 v 
2 0.004 6.52413 4.33598 B m e staggered 0 0 0 v 
2 0.004 6.53402 0.54197 B m e staggered 0 0 0 v 
2 0.004 0.6546 0.54197 B m e staggered 0 0 0 v 
2 0.004 6.56039 1.01205 B m e staggered 0 0 0 v 
2 0.004 6.56039 1.05205 B m e staggered 0 0 0 v 
2 0.004 6.56039 1.09205 B m e staggered 0 0 0 v 
2 0.004 6.56039 1.13205 B m e staggered 0 0 0 v 
2 0.004 6.56039 1.17205 B m e staggered 0 0 0 v 
2 0.004 6.56039 1.21205 B m e staggered 0 0 0 v 
2 0.004 6.56039 1.25205 B m e staggered 0 0 0 v 
2 0.004 6.56039 1.29205 B m e staggered 0 0 0 v 
2 0.004 6.56039 1.33205 B m e staggered 0 0 0 v 
2 0.004 6.56039 1.37205 B m e staggered 0 0 0 v 
2 0.004 6.56039 1.41205 B m e staggered 0 0 0 v 
2 0.004 6.56039 1.45205 B m e staggered 0 0 0 v 
2 0.004 6.56039 1.49205 B m e staggered 0 0 0 v 
2 0.004 6.56039 1.53205 B m e staggered 0 0 0 v 
2 0.004 6.56039 1.57205 B m e staggered 0 0 0 v 
2 0.004 6.56039 1.61205 B m e staggered 0 0 0 v 
2 0.004 6.56039 1.65205 B m e staggered 0 0 0 v 
2 0.004 6.56039 1.69205 B m e staggered 0 0 0 v 
2 0.004 6.56039 1.73205 B m e staggered 0 0 0 v 
2 0.004 6.56039 1.77205 B m e staggered 0 0 0 v 
2 0.004 6.56039 1.81205 B m e staggered 0 0 0 v 
2 0.004 6.56039 2.35585 B m e staggered 0 0 0 v 
2 0.004 6.56039 3.11909 B m e staggered 0 0 0 v 
2 0.004 6.56039 3.15909 B m e staggered 0 0 0 v 
2 0.004 6.56039 3.19909 B m e staggered 0 0 0 v 
2 0.004 6.56039 3.23909 B m e staggered 0 0 0 v 
2 0.004 6.56039 3.27909 B m e staggered 0 0 0 v 
2 0.004 6.56039 3.31909 B m e staggered 0 0 0 v 
2 0.004 6.56039 3.35909 B m e staggered 0 0 0 v 
2 0.004 6.56039 3.39909 B m e staggered 0 0 0 v 
2 0.004 6.56039 3.43909 B m e staggered 0 0 0 v 
2 0.004 6.56039 3.47909 B m e staggered 0 0 0 v 
2 0.004 6.56039 3.51909 B m e staggered 0 0 0 v 
2 0.004 6.56039 3.55909 B m e staggered 0 0 0 v 
2 0.004 6.56039 3.59909 B m e staggered 0 0 0 v 
2 0.004 6.56039 3.63909 B m e staggered 0 0 0 v 
2 0.004 6.56039 3.67909 B m e staggered 0 0 0 v 
2 0.004 6.56039 3.71909 B m e staggered 0 0 0 v 
2 0.004 6.56039 3.75909 B m e staggered 0 0 0 v 
2 0.004 6.56039 3.79909 B m e staggered 0 0 0 v 
2 0.004 6.56039 3.83909 B m e staggered 0 0 0 v 
2 0.004 6.56039 3.87909 B m e staggered 0 0 0 v 
2 0.004 6.56039 3.91909 B m e staggered 0 0 0 v 
2 0.004 6.56039 3.95909 B m e staggered 0 0 0 v 
2 0.004 6.56039 3.99909 B m e staggered 0 0 0 v 
2 0.004 6.56039 4.03909 B m e staggered 0 0 0 v 
2 0.004 6.56039 4.07909 B m e staggered 0 0 0 v 
2 0.004 6.56039 4.11909 B m e staggered 0 0 0 v 
2 0.004 6.56039 4.15909 B m e staggered 0 0 0 v 
2 0.004 6.56039 4.19909 B m e staggered 0 0 0 v 
2 0.004 6.56039 4.23909 B m e staggered 0 0 0 v 
2 0.004 6.56039 4.27909 B m e staggered 0 0 0 v 
2 0.004 6.56039 4.31909 B m e staggered 0 0 0 v 
2 0.004 6.56039 0.57205 B m e staggered 0 0 0 v 
2 0.004 6.56039 0.61205 B m e staggered 0 0 0 v 
2 0.004 6.56039 0.65205 B m e staggered 0 0 0 v 
2 0.004 6.56039 0.69205 B m e staggered 0 0 0 v 
2 0.004 6.56039 0.73205 B m e staggered 0 0 0 v 
2 0.004 6.56039 0.77205 B m e staggered 0 0 0 v 
2 0.004 6.56039 0.81205 B m e staggered 0 0 0 v 
2 0.004 6.56039 0.85205 B m e staggered 0 0 0 v 
2 0.004 6.56039 0.89205 B m e staggered 0 0 0 v 
2 0.004 6.56039 0.93205 B m e staggered 0 0 0 v 
2 0.004 6.56039 0.97205 B m e staggered 0 0 0 v 
2 0.004 0.67 2.831 B m e staggered 0 0 0 v 
2 0.004 0.671 3.575 B m e staggered 0 0 0 v 
2 0.004 0.68413 4.33598 B m e staggered 0 0 0 v 
2 0.004 0.6946 0.54197 B m e staggered 0 0 0 v 
2 0.004 0.72413 4.33598 B m e staggered 0 0 0 v 
2 0.004 0.7346 0.54197 B m e staggered 0 0 0 v 
2 0.004 0.76413 4.33598 B m e staggered 0 0 0 v 
2 0.004 0.767 3.575 B m e staggered 0 0 0 v 
2 0.004 0.7746 0.54197 B m e staggered 0 0 0 v 
2 0.004 0.79248 2.661 B m e staggered 0 0 0 v 
2 0.004 0.80413 4.33598 B m e staggered 0 0 0 v 
2 0.004 0.8146 0.54197 B m e staggered 0 0 0 v 
2 0.004 0.08413 4.33598 B m e staggered 0 0 0 v 
2 0.004 0.84413 4.33598 B m e staggered 0 0 0 v 
2 0.004 0.8546 0.54197 B m e staggered 0 0 0 v 
2 0.004 0.856 2.637 B m e staggered 0 0 0 v 
2 0.004 0.868 2.3 B m e staggered 0 0 0 v 
2 0.004 0.08878 0.21717 B m e staggered 0 0 0 v 
2 0.004 0.88413 4.33598 B m e staggered 0 0 0 v 
2 0.004 0.8946 0.54197 B m e staggered 0 0 0 v 
2 0.004 0.92413 4.33598 B m e staggered 0 0 0 v 
2 0.004 0.9346 0.54197 B m e staggered 0 0 0 v 
2 0.004 0.96413 4.33598 B m e staggered 0 0 0 v 
2 0.004 0.9746 0.54197 B m e staggered 0 0 0 v 
2 0.004 4.26564 2.17807 B m e staggered 0 0 0 v 
2 0.004 4.54123 1.70564 B m e staggered 0 0 0 v 
2 0.004 4.73807 1.66627 B m e staggered 0 0 0 v 
2 0.004 0.858 2.87452 B m e staggered 0 0 0 v 
2 0.004 3.795 0.725 B m e staggered 0 0 0 v 
2 0.004 3.964 1.005 B m e staggered 0 0 0 v 
2 0.005 3.8865 2.9265 B m e staggered 0 0 0 v 
2 0.005 5.0895 2.7325 B m e staggered 0 0 0 v 
2 0.004 3.87193 1.3513 B m e staggered 0 0 0 v 
2 0.004 3.87193 1.39067 B m e staggered 0 0 0 v 
2 0.004 3.87193 1.46942 B m e staggered 0 0 0 v 
2 0.004 3.87193 1.54816 B m e staggered 0 0 0 v 
2 0.004 3.87193 1.6269 B m e staggered 0 0 0 v 
2 0.004 3.87193 1.70564 B m e staggered 0 0 0 v 
2 0.004 3.87193 1.78437 B m e staggered 0 0 0 v 
2 0.004 3.87193 2.17807 B m e staggered 0 0 0 v 
2 0.004 3.9113 1.39067 B m e staggered 0 0 0 v 
2 0.004 3.9113 1.78437 B m e staggered 0 0 0 v 
2 0.004 3.9113 2.05996 B m e staggered 0 0 0 v 
2 0.004 3.95067 1.39067 B m e staggered 0 0 0 v 
2 0.004 3.95067 1.50879 B m e staggered 0 0 0 v 
2 0.004 3.95067 1.66627 B m e staggered 0 0 0 v 
2 0.004 3.95067 1.78437 B m e staggered 0 0 0 v 
2 0.004 3.95067 1.94185 B m e staggered 0 0 0 v 
2 0.004 3.99005 1.39067 B m e staggered 0 0 0 v 
2 0.004 3.99005 1.43005 B m e staggered 0 0 0 v 
2 0.004 3.99005 1.58753 B m e staggered 0 0 0 v 
2 0.004 3.99005 1.78437 B m e staggered 0 0 0 v 
2 0.004 3.99005 1.82374 B m e staggered 0 0 0 v 
2 0.004 4.02942 1.43005 B m e staggered 0 0 0 v 
2 0.004 4.02942 1.46942 B m e staggered 0 0 0 v 
2 0.004 4.02942 1.54816 B m e staggered 0 0 0 v 
2 0.004 4.02942 1.6269 B m e staggered 0 0 0 v 
2 0.004 4.02942 1.70564 B m e staggered 0 0 0 v 
2 0.004 4.02942 2.09933 B m e staggered 0 0 0 v 
2 0.004 4.06879 1.46942 B m e staggered 0 0 0 v 
2 0.004 4.06879 1.70564 B m e staggered 0 0 0 v 
2 0.004 4.06879 1.98122 B m e staggered 0 0 0 v 
2 0.004 4.10816 1.46942 B m e staggered 0 0 0 v 
2 0.004 4.10816 1.50879 B m e staggered 0 0 0 v 
2 0.004 4.10816 1.54816 B m e staggered 0 0 0 v 
2 0.004 4.10816 1.58753 B m e staggered 0 0 0 v 
2 0.004 4.10816 1.6269 B m e staggered 0 0 0 v 
2 0.004 4.10816 1.66627 B m e staggered 0 0 0 v 
2 0.004 4.10816 1.78437 B m e staggered 0 0 0 v 
2 0.004 4.10816 1.86311 B m e staggered 0 0 0 v 
2 0.004 4.14753 1.31193 B m e staggered 0 0 0 v 
2 0.004 4.14753 1.54816 B m e staggered 0 0 0 v 
2 0.004 4.14753 1.6269 B m e staggered 0 0 0 v 
2 0.004 4.14753 1.70564 B m e staggered 0 0 0 v 
2 0.004 4.14753 2.1387 B m e staggered 0 0 0 v 
2 0.004 4.1869 1.58753 B m e staggered 0 0 0 v 
2 0.004 4.1869 1.66627 B m e staggered 0 0 0 v 
2 0.004 4.1869 1.78437 B m e staggered 0 0 0 v 
2 0.004 4.1869 2.02059 B m e staggered 0 0 0 v 
2 0.004 4.22627 1.46942 B m e staggered 0 0 0 v 
2 0.004 4.22627 1.54816 B m e staggered 0 0 0 v 
2 0.004 4.22627 1.6269 B m e staggered 0 0 0 v 
2 0.004 4.22627 1.70564 B m e staggered 0 0 0 v 
2 0.004 4.22627 1.90248 B m e staggered 0 0 0 v 
2 0.004 4.26564 1.3513 B m e staggered 0 0 0 v 
2 0.004 4.26564 1.58753 B m e staggered 0 0 0 v 
2 0.004 4.26564 1.6269 B m e staggered 0 0 0 v 
2 0.004 4.26564 1.66627 B m e staggered 0 0 0 v 
2 0.004 4.34437 1.54816 B m e staggered 0 0 0 v 
2 0.004 4.34437 1.6269 B m e staggered 0 0 0 v 
2 0.004 4.34437 1.66627 B m e staggered 0 0 0 v 
2 0.004 4.34437 1.70564 B m e staggered 0 0 0 v 
2 0.004 4.34437 2.05996 B m e staggered 0 0 0 v 
2 0.004 4.38374 1.50879 B m e staggered 0 0 0 v 
2 0.004 4.38374 1.58753 B m e staggered 0 0 0 v 
2 0.004 4.38374 1.6269 B m e staggered 0 0 0 v 
2 0.004 4.38374 1.66627 B m e staggered 0 0 0 v 
2 0.004 4.38374 1.94185 B m e staggered 0 0 0 v 
2 0.004 4.42311 1.39067 B m e staggered 0 0 0 v 
2 0.004 4.42311 1.54816 B m e staggered 0 0 0 v 
2 0.004 4.42311 1.6269 B m e staggered 0 0 0 v 
2 0.004 4.42311 1.70564 B m e staggered 0 0 0 v 
2 0.004 4.42311 1.82374 B m e staggered 0 0 0 v 
2 0.004 4.46248 1.58753 B m e staggered 0 0 0 v 
2 0.004 4.46248 1.66627 B m e staggered 0 0 0 v 
2 0.004 4.46248 1.78437 B m e staggered 0 0 0 v 
2 0.004 4.46248 2.09933 B m e staggered 0 0 0 v 
2 0.004 4.50185 1.54816 B m e staggered 0 0 0 v 
2 0.004 4.50185 1.6269 B m e staggered 0 0 0 v 
2 0.004 4.50185 1.70564 B m e staggered 0 0 0 v 
2 0.004 4.50185 1.98122 B m e staggered 0 0 0 v 
2 0.004 4.54122 1.43005 B m e staggered 0 0 0 v 
2 0.004 4.54122 1.86311 B m e staggered 0 0 0 v 
2 0.004 4.57844 1.31408 B m e staggered 0 0 0 v 
2 0.004 4.58059 1.66627 B m e staggered 0 0 0 v 
2 0.004 4.58059 2.1387 B m e staggered 0 0 0 v 
2 0.004 4.61996 1.58753 B m e staggered 0 0 0 v 
2 0.004 4.61996 2.02059 B m e staggered 0 0 0 v 
2 0.004 4.65933 1.46942 B m e staggered 0 0 0 v 
2 0.004 4.65933 1.90248 B m e staggered 0 0 0 v 
2 0.004 4.6987 1.3513 B m e staggered 0 0 0 v 
2 0.004 4.6987 1.78437 B m e staggered 0 0 0 v 
2 0.004 4.6987 2.17807 B m e staggered 0 0 0 v 
2 0.004 4.73807 2.05996 B m e staggered 0 0 0 v 
2 0.005 5.6065 0.7045 B m e staggered 0 0 0 v 
2 0.005 1.6615 3.0405 B m e staggered 0 0 0 v 
3 0.005 5.406 2.346 B e e staggered 0 0 0 
3 0 1.534 3.776 T 0.03 0.034 e e staggered 0 0 0 
3 0 3.465 4.202 T 0.03 0.034 e e staggered 0 0 0 
3 0 5.395 2.283 T 0.034 0.03 e e staggered 0 0 0 
3 0 5.479 3.569 T 0.03 0.034 e e staggered 0 0 0 
3 0 5.47929 3.79606 T 0.047 0.012 e e staggered 0 0 0 
3 0 5.47929 3.77637 T 0.047 0.012 e e staggered 0 0 0 
3 0 5.47929 3.75669 T 0.047 0.012 e e staggered 0 0 0 
3 0 5.47929 3.737 T 0.047 0.012 e e staggered 0 0 0 
3 0 5.47929 3.71731 T 0.047 0.012 e e staggered 0 0 0 
3 0 5.47929 3.69763 T 0.047 0.012 e e staggered 0 0 0 
3 0 5.47929 3.67794 T 0.047 0.012 e e staggered 0 0 0 
3 0 5.47929 3.65826 T 0.047 0.012 e e staggered 0 0 0 
3 0 5.762 3.907 T 0.028 0.024 e e staggered 0 0 0 
3 0 5.601 3.96 T 0.028 0.024 e e staggered 0 0 0 
3 0 5.336 3.672 T 0.054 0.038 e e staggered 0 0 0 
3 0 5.254 3.672 T 0.054 0.038 e e staggered 0 0 0 
3 0 1.445 3.746 T 0.024 0.028 e e staggered 0 0 0 
3 0 3.552 4.197 T 0.028 0.024 e e staggered 0 0 0 
3 0 5.331 2.28 T 0.024 0.028 e e staggered 0 0 0 
3 0 5.316 3.69401 D 0.108 0.085 e e staggered 0 0 0 
3 0 5.769 4.075 D 0.028 0.024 e e staggered 0 0 0 
3 0.005 1.45 3.78 B m e staggered 0 0 0 v 
3 0.005 1.485 3.8 B m e staggered 0 0 0 v 
3 0.005 3.46 4.16 B m e staggered 0 0 0 v 
3 0.005 3.495 4.15 B m e staggered 0 0 0 v 
3 0.005 3.5 4.195 B m e staggered 0 0 0 v 
3 0.005 3.53 4.165 B m e staggered 0 0 0 v 
3 0.005 5.34 2.315 B m e staggered 0 0 0 v 
3 0.005 5.375 2.32 B m e staggered 0 0 0 v 
3 0.005 5.39 3.6 B m e staggered 0 0 0 v 
3 0.005 5.39 3.7 B m e staggered 0 0 0 v 
3 0.005 5.393 3.651 B m e staggered 0 0 0 v 
3 0.005 5.43 3.7 B m e staggered 0 0 0 v 
3 0.005 5.433 3.651 B m e staggered 0 0 0 v 
3 0.005 5.769 4.031 B m e staggered 0 0 0 v 
3 0.005 5.803 3.907 B m e staggered 0 0 0 v 
3 0.005 5.43 3.6 B m e staggered 0 0 0 v 
3 0.005 5.644 3.967 B m e staggered 0 0 0 v 
3 0.004 1.485 3.76 B m e staggered 0 0 0 v 
4 0 1.11316 3.578 T 0.012 0.064 e e staggered 0 0 0 
4 0 1.09 3.512 D 0.034 0.03 e e staggered 0 0 0 
4 0 1.085 3.564 D 0.024 0.028 e e staggered 0 0 0 
4 0 1.13 3.564 D 0.024 0.028 e e staggered 0 0 0 
4 0.005 1.14 3.52 B m e staggered 0 0 0 v 
5 0 1.21158 3.578 T 0.012 0.064 e e staggered 0 0 0 
5 0 1.32 3.548 D 0.034 0.03 e e staggered 0 0 0 
5 0 1.22 3.564 D 0.024 0.028 e e staggered 0 0 0 
5 0 1.265 3.564 D 0.024 0.028 e e staggered 0 0 0 
5 0.005 1.245 3.52 B m e staggered 0 0 0 v 
6 0.00985 3.93098 1.4891 T e e staggered 0 0 0 
6 0.00985 3.93098 1.56784 T e e staggered 0 0 0 
6 0.00985 3.93098 1.64658 T e e staggered 0 0 0 
6 0.00985 3.93098 1.72532 T e e staggered 0 0 0 
6 0.00985 3.97035 1.44973 T e e staggered 0 0 0 
6 0.00985 3.97035 1.60721 T e e staggered 0 0 0 
6 0.0125 3.93098 1.64658 D e e staggered 0 0 0 
6 0.0125 3.93098 1.72532 D e e staggered 0 0 0 
6 0.0125 3.93098 1.4891 D e e staggered 0 0 0 
6 0.0125 3.97035 1.44973 D e e staggered 0 0 0 
6 0.0125 3.93098 1.52847 D e e staggered 0 0 0 
6 0 3.672 1.395 D 0.03 0.034 e e staggered 0 0 0 
6 0 3.704 1.72 D 0.028 0.024 e e staggered 0 0 0 
6 0 3.785 1.368 D 0.054 0.038 e e staggered 0 0 0 
6 0 3.8863 1.745 D 0.028 0.024 e e staggered 0 0 0 
6 0.005 3.674 1.744 B m e staggered 0 0 0 v 
6 0.005 3.74 1.41 B m e staggered 0 0 0 v 
6 0.005 3.765 1.41 B m e staggered 0 0 0 v 
6 0.005 3.79 1.41 B m e staggered 0 0 0 v 
6 0.005 3.82 1.42 B m e staggered 0 0 0 v 
6 0.004 3.9113 1.46942 B m e staggered 0 0 0 v 
6 0.004 3.9113 1.54816 B m e staggered 0 0 0 v 
6 0.004 3.9113 1.6269 B m e staggered 0 0 0 v 
6 0.004 3.9113 1.70564 B m e staggered 0 0 0 v 
6 0.004 3.95067 1.43005 B m e staggered 0 0 0 v 
6 0.004 3.95067 1.58753 B m e staggered 0 0 0 v 
7 0 3.672 1.47 T 0.03 0.034 e e staggered 0 0 0 
7 0.00985 4.00973 1.52847 T e e staggered 0 0 0 
7 0.00985 4.00973 1.68595 T e e staggered 0 0 0 
7 0.00985 4.0491 1.60721 T e e staggered 0 0 0 
7 0.00985 4.08847 1.56784 T e e staggered 0 0 0 
7 0.00985 4.08847 1.64658 T e e staggered 0 0 0 
7 0 3.705 1.582 T 0.054 0.038 e e staggered 0 0 0 
7 0.0125 4.00973 1.52847 D e e staggered 0 0 0 
7 0.0125 4.08847 1.56784 D e e staggered 0 0 0 
7 0.0125 4.0491 1.60721 D e e staggered 0 0 0 
7 0.0125 4.08847 1.60721 D e e staggered 0 0 0 
7 0.0125 4.00973 1.4891 D e e staggered 0 0 0 
7 0.0125 4.00973 1.64658 D e e staggered 0 0 0 
7 0.005 3.679 1.54228 B m e staggered 0 0 0 v 
7 0.005 3.714 1.543 B m e staggered 0 0 0 v 
7 0.005 3.749 1.54228 B m e staggered 0 0 0 v 
7 0.005 3.784 1.543 B m e staggered 0 0 0 v 
7 0.004 3.99005 1.50879 B m e staggered 0 0 0 v 
7 0.004 3.99005 1.66627 B m e staggered 0 0 0 v 
7 0.004 4.02942 1.58753 B m e staggered 0 0 0 v 
7 0.004 4.06879 1.54816 B m e staggered 0 0 0 v 
7 0.004 4.06879 1.6269 B m e staggered 0 0 0 v 
8 0 3.682 2.205 T 0.03 0.034 e e staggered 0 0 0 
8 0.00985 4.0491 1.76469 T e e staggered 0 0 0 
8 0.00985 4.16721 1.76469 T e e staggered 0 0 0 
8 0.00985 4.24595 1.68595 T e e staggered 0 0 0 
8 0.00985 4.24595 1.76469 T e e staggered 0 0 0 
8 0.00985 4.32469 1.76469 T e e staggered 0 0 0 
8 0.00985 4.40343 1.76469 T e e staggered 0 0 0 
8 0.00985 4.4428 1.72532 T e e staggered 0 0 0 
8 0.0125 4.0491 1.80406 D e e staggered 0 0 0 
8 0.0125 4.24595 1.80406 D e e staggered 0 0 0 
8 0.0125 4.36406 1.80406 D e e staggered 0 0 0 
8 0.0125 4.20658 1.64658 D e e staggered 0 0 0 
8 0.0125 4.4428 1.68595 D e e staggered 0 0 0 
8 0 4.42311 1.755 D 0.028 0.024 e e staggered 0 0 0 
8 0 4.241 1.75 D 0.028 0.024 e e staggered 0 0 0 
8 0 4.14 1.75 D 0.028 0.024 e e staggered 0 0 0 
8 0 4.365 1.741 D 0.028 0.024 e e staggered 0 0 0 
8 0.005 3.775 2.185 B m e staggered 0 0 0 v 
8 0.005 3.775 2.21 B m e staggered 0 0 0 v 
8 0.005 3.775 2.235 B m e staggered 0 0 0 v 
8 0.005 3.775 2.265 B m e staggered 0 0 0 v 
8 0.004 4.02942 1.78437 B m e staggered 0 0 0 v 
8 0.004 4.14753 1.78437 B m e staggered 0 0 0 v 
8 0.004 4.22627 1.66627 B m e staggered 0 0 0 v 
8 0.004 4.22627 1.78437 B m e staggered 0 0 0 v 
8 0.004 4.34437 1.78437 B m e staggered 0 0 0 v 
8 0.004 4.42311 1.78437 B m e staggered 0 0 0 v 
8 0.004 4.46248 1.70564 B m e staggered 0 0 0 v 
9 0.005 5.445 0.795 B e e staggered 0 0 0 
9 0.0059999 5.56533 0.7183801 T e e staggered 0 0 0 
9 0 5.56533 0.69869 T 0.041 0.012 e e staggered 0 0 0 
9 0.00985 4.67902 1.56784 T e e staggered 0 0 0 
9 0.00985 4.71839 1.44973 T e e staggered 0 0 0 
9 0.00985 3.97035 1.33161 T e e staggered 0 0 0 
9 0.00985 4.08847 1.37098 T e e staggered 0 0 0 
9 0.00985 4.16721 1.52847 T e e staggered 0 0 0 
9 0.00985 4.20658 1.41035 T e e staggered 0 0 0 
9 0.00985 4.32469 1.44973 T e e staggered 0 0 0 
9 0.00985 4.36406 1.33161 T e e staggered 0 0 0 
9 0.00985 4.4428 1.4891 T e e staggered 0 0 0 
9 0.00985 4.48217 1.37098 T e e staggered 0 0 0 
9 0.00985 4.56091 1.52847 T e e staggered 0 0 0 
9 0.00985 4.60028 1.41035 T e e staggered 0 0 0 
9 0 4.53 1.139 T 0.024 0.028 e e staggered 0 0 0 
9 0 4.585 1.139 T 0.024 0.028 e e staggered 0 0 0 
9 0 5.404 0.69 T 0.028 0.024 e e staggered 0 0 0 
9 0 3.732 1.06 T 0.038 0.054 e e staggered 0 0 0 
9 0 4.999 1.264 T 0.038 0.054 e e staggered 0 0 0 
9 0 5.484 0.863 T 0.038 0.054 e e staggered 0 0 0 
9 0 5.527 0.792 T 0.028 0.024 e e staggered 0 0 0 
9 0.0125 4.0491 1.37098 D e e staggered 0 0 0 
9 0.0125 4.20658 1.41035 D e e staggered 0 0 0 
9 0.0125 4.16721 1.52847 D e e staggered 0 0 0 
9 0.0125 4.16721 1.4891 D e e staggered 0 0 0 
9 0.0125 4.309 1.44531 D e e staggered 0 0 0 
9 0.0125 4.36406 1.44973 D e e staggered 0 0 0 
9 0.0125 4.4428 1.44973 D e e staggered 0 0 0 
9 0.0125 4.40343 1.33161 D e e staggered 0 0 0 
9 0.0125 4.67902 1.56784 D e e staggered 0 0 0 
9 0.0125 4.60028 1.41035 D e e staggered 0 0 0 
9 0.0125 4.76666 1.42805 D e e staggered 0 0 0 
9 0.0125 4.52154 1.37097 D e e staggered 0 0 0 
9 0.0125 4.60028 1.52847 D e e staggered 0 0 0 
9 0 3.068 3.21 D 0.028 0.024 e e staggered 0 0 0 
9 0 4.37 1.079 D 0.024 0.028 e e staggered 0 0 0 
9 0 4.415 1.079 D 0.024 0.028 e e staggered 0 0 0 
9 0 5.529 4.07 D 0.028 0.024 e e staggered 0 0 0 
9 0 3.732 1.06 D 0.038 0.054 e e staggered 0 0 0 
9 0 4.999 1.263 D 0.038 0.054 e e staggered 0 0 0 
9 0 3.91829 1.29361 D 0.028 0.024 e e staggered 0 0 0 
9 0.005 3.105 3.21 B m e staggered 0 0 0 v 
9 0.005 3.66 3.5085 B m e staggered 0 0 0 v 
9 0.005 3.69172 1.02828 B m e staggered 0 0 0 v 
9 0.005 3.6931 1.095 B m e staggered 0 0 0 v 
9 0.005 3.795 4.175 B m e staggered 0 0 0 v 
9 0.005 4.485 1.005 B m e staggered 0 0 0 v 
9 0.005 4.625 1.17 B m e staggered 0 0 0 v 
9 0.005 5.0386 1.2415 B m e staggered 0 0 0 v 
9 0.005 5.039 1.2869 B m e staggered 0 0 0 v 
9 0.005 5.443 0.871 B m e staggered 0 0 0 v 
9 0.005 5.49 0.78223 B m e staggered 0 0 0 v 
9 0.005 5.494 0.816 B m e staggered 0 0 0 v 
9 0.005 5.55 4.02 B m e staggered 0 0 0 v 
9 0.005 6.04 3.98 B m e staggered 0 0 0 v 
9 0.004 3.95067 1.31193 B m e staggered 0 0 0 v 
9 0.004 4.06879 1.3513 B m e staggered 0 0 0 v 
9 0.004 4.14753 1.50879 B m e staggered 0 0 0 v 
9 0.004 4.1869 1.39067 B m e staggered 0 0 0 v 
9 0.004 4.34437 1.43005 B m e staggered 0 0 0 v 
9 0.004 4.38374 1.31193 B m e staggered 0 0 0 v 
9 0.004 4.46248 1.46942 B m e staggered 0 0 0 v 
9 0.004 4.50185 1.3513 B m e staggered 0 0 0 v 
9 0.004 4.58059 1.50879 B m e staggered 0 0 0 v 
9 0.004 4.61996 1.39067 B m e staggered 0 0 0 v 
9 0.004 4.6987 1.54816 B m e staggered 0 0 0 v 
9 0.004 4.73807 1.43005 B m e staggered 0 0 0 v 
10 0 5.183 1.725 T 0.03 0.034 e e staggered 0 0 0 
10 0.00985 4.16721 1.60721 T e e staggered 0 0 0 
10 0.00985 4.16721 1.68595 T e e staggered 0 0 0 
10 0.00985 4.20658 1.56784 T e e staggered 0 0 0 
10 0.00985 4.20658 1.64658 T e e staggered 0 0 0 
10 0.00985 4.20658 1.72532 T e e staggered 0 0 0 
10 0.00985 4.24595 1.60721 T e e staggered 0 0 0 
10 0.00985 4.28532 1.56784 T e e staggered 0 0 0 
10 0.00985 4.28532 1.72532 T e e staggered 0 0 0 
10 0.00985 4.32469 1.60721 T e e staggered 0 0 0 
10 0.00985 4.36406 1.56784 T e e staggered 0 0 0 
10 0.00985 4.36406 1.72532 T e e staggered 0 0 0 
10 0.00985 4.40343 1.60721 T e e staggered 0 0 0 
10 0.00985 4.40343 1.68595 T e e staggered 0 0 0 
10 0.00985 4.4428 1.56784 T e e staggered 0 0 0 
10 0.00985 4.4428 1.64658 T e e staggered 0 0 0 
10 0.00985 4.48217 1.60721 T e e staggered 0 0 0 
10 0.00985 4.48217 1.68595 T e e staggered 0 0 0 
10 0 5.1925 1.595 T 0.045 0.104 e e staggered 0 0 0 
10 0 5.1925 1.345 T 0.045 0.104 e e staggered 0 0 0 
10 0 5.1925 1.47 T 0.045 0.104 e e staggered 0 0 0 
10 0 5.207 1.24 T 0.038 0.054 e e staggered 0 0 0 
10 0.0125 4.12784 1.68595 D e e staggered 0 0 0 
10 0.0125 4.16721 1.60721 D e e staggered 0 0 0 
10 0.0125 4.20658 1.56784 D e e staggered 0 0 0 
10 0.0125 4.24595 1.68595 D e e staggered 0 0 0 
10 0.0125 4.16721 1.64658 D e e staggered 0 0 0 
10 0.0125 4.24595 1.60721 D e e staggered 0 0 0 
10 0.0125 4.20658 1.52847 D e e staggered 0 0 0 
10 0.0125 4.36406 1.56784 D e e staggered 0 0 0 
10 0.0125 4.36406 1.60721 D e e staggered 0 0 0 
10 0.0125 4.40343 1.68595 D e e staggered 0 0 0 
10 0.0125 4.4428 1.56784 D e e staggered 0 0 0 
10 0.0125 4.4428 1.64658 D e e staggered 0 0 0 
10 0.0125 4.48217 1.60721 D e e staggered 0 0 0 
10 0.0125 4.52154 1.68595 D e e staggered 0 0 0 
10 0.0125 4.40343 1.60721 D e e staggered 0 0 0 
10 0 4.305 1.549 D 0.024 0.028 e e staggered 0 0 0 
10 0 4.305 1.691 D 0.024 0.028 e e staggered 0 0 0 
10 0.005 5.145 1.48 B m e staggered 0 0 0 v 
10 0.005 5.145 1.51 B m e staggered 0 0 0 v 
10 0.005 5.145 1.54 B m e staggered 0 0 0 v 
10 0.005 5.145 1.57 B m e staggered 0 0 0 v 
10 0.005 5.145 1.44 B m e staggered 0 0 0 v 
10 0.004 4.14753 1.58753 B m e staggered 0 0 0 v 
10 0.004 4.14753 1.66627 B m e staggered 0 0 0 v 
10 0.004 4.1869 1.54816 B m e staggered 0 0 0 v 
10 0.004 4.1869 1.6269 B m e staggered 0 0 0 v 
10 0.004 4.1869 1.70564 B m e staggered 0 0 0 v 
10 0.004 4.22627 1.58753 B m e staggered 0 0 0 v 
10 0.004 4.26564 1.54816 B m e staggered 0 0 0 v 
10 0.004 4.26564 1.70564 B m e staggered 0 0 0 v 
10 0.004 4.34437 1.58753 B m e staggered 0 0 0 v 
10 0.004 4.38374 1.54816 B m e staggered 0 0 0 v 
10 0.004 4.38374 1.70564 B m e staggered 0 0 0 v 
10 0.004 4.42311 1.58753 B m e staggered 0 0 0 v 
10 0.004 4.42311 1.66627 B m e staggered 0 0 0 v 
10 0.004 4.46248 1.54816 B m e staggered 0 0 0 v 
10 0.004 4.46248 1.6269 B m e staggered 0 0 0 v 
10 0.004 4.50185 1.58753 B m e staggered 0 0 0 v 
10 0.004 4.50185 1.66627 B m e staggered 0 0 0 v 
11 0 1.435 4.142 T 0.028 0.024 e e staggered 0 0 0 
11 0 1.385 4.084 T 0.024 0.028 e e staggered 0 0 0 
11 0 1.44557 4.086 T 0.012 0.015 e e staggered 0 0 0 
11 0.005 1.352 4.084 B m e staggered 0 0 0 v 
12 0 1.58104 3.99553 T 0.024 0.01 e e staggered 0 0 0 
12 0 1.477 4.142 T 0.028 0.024 e e staggered 0 0 0 
12 0 1.46643 4.086 T 0.012 0.015 e e staggered 0 0 0 
12 0 1.477 4.142 D 0.028 0.024 e e staggered 0 0 0 
12 0 1.472 4.09 D 0.03 0.034 e e staggered 0 0 0 
12 0.004 1.5153 4.063 B m e staggered 0 0 0 v 
13 0 1.59669 3.27 T 0.02 0.02 e e staggered 0 0 0 
13 0.005 2.25 3.96 B e e staggered 0 0 0 
13 0 5.12 3.853 T 0.034 0.03 e e staggered 0 0 0 
13 0 2.07813 3.976 T 0.096 0.146 e e staggered 0 0 0 
13 0 1.385 4.126 T 0.024 0.028 e e staggered 0 0 0 
13 0 2.186 4.038 T 0.054 0.038 e e staggered 0 0 0 
13 0 2.261 4.038 T 0.054 0.038 e e staggered 0 0 0 
13 0 2.236 3.894 T 0.054 0.038 e e staggered 0 0 0 
13 0 2.176 3.887 T 0.024 0.028 e e staggered 0 0 0 
13 0 5.131 3.775 T 0.028 0.024 e e staggered 0 0 0 
13 0 3.185 2.907 D 0.034 0.03 e e staggered 0 0 0 
13 0 5.675 4.084 D 0.024 0.028 e e staggered 0 0 0 
13 0 3.245 2.901 D 0.024 0.028 e e staggered 0 0 0 
13 0.005 1.351 4.126 B m e staggered 0 0 0 v 
13 0.005 1.56 3.25 B m e staggered 0 0 0 v 
13 0.005 1.56 3.29 B m e staggered 0 0 0 v 
13 0.005 2.155 3.925 B m e staggered 0 0 0 v 
13 0.005 2.165 3.96 B m e staggered 0 0 0 v 
13 0.005 2.19 3.925 B m e staggered 0 0 0 v 
13 0.005 2.2 3.96 B m e staggered 0 0 0 v 
13 0.005 2.47 3.445 B m e staggered 0 0 0 v 
13 0.005 2.51 3.445 B m e staggered 0 0 0 v 
13 0.005 2.55 3.445 B m e staggered 0 0 0 v 
13 0.005 2.59 3.445 B m e staggered 0 0 0 v 
13 0.005 3.175 2.955 B m e staggered 0 0 0 v 
13 0.005 3.21 2.955 B m e staggered 0 0 0 v 
13 0.005 3.245 2.955 B m e staggered 0 0 0 v 
13 0.005 5.14 3.74 B m e staggered 0 0 0 v 
13 0.005 5.175 3.74 B m e staggered 0 0 0 v 
13 0.005 5.18 3.825 B m e staggered 0 0 0 v 
13 0.005 5.675 4.03 B m e staggered 0 0 0 v 
14 0.005 3.655 2.795 B e e staggered 0 0 0 
14 0.0059999 3.8726199 2.88533 T e e staggered 0 0 0 
14 0 3.89231 2.88533 T 0.012 0.041 e e staggered 0 0 0 
14 0 3.816 2.775 T 0.028 0.024 e e staggered 0 0 0 
14 0 3.729 2.804 T 0.054 0.038 e e staggered 0 0 0 
14 0 3.797 2.849 T 0.024 0.028 e e staggered 0 0 0 
14 0 3.618 1.395 D 0.03 0.034 e e staggered 0 0 0 
14 0 3.46 1.378 D 0.054 0.038 e e staggered 0 0 0 
14 0 3.52 1.376 D 0.024 0.028 e e staggered 0 0 0 
14 0.005 3.475 1.415 B m e staggered 0 0 0 v 
14 0.005 3.5 1.415 B m e staggered 0 0 0 v 
14 0.005 3.525 1.415 B m e staggered 0 0 0 v 
14 0.005 3.55 1.415 B m e staggered 0 0 0 v 
14 0.005 3.7 2.76 B m e staggered 0 0 0 v 
14 0.005 3.745 2.76 B m e staggered 0 0 0 v 
14 0.005 3.78 2.81 B m e staggered 0 0 0 v 
14 0.005 3.822 2.81 B m e staggered 0 0 0 v 
15 0 5.597 1.73072 T 0.138 0.116 e e staggered 0 0 0 
15 0.005 5.58 1.615 B e e staggered 0 0 0 
15 0 3.618 1.47 T 0.03 0.034 e e staggered 0 0 0 
15 0 5.237 1.725 T 0.03 0.034 e e staggered 0 0 0 
15 0 5.654 2.4 T 0.028 0.024 e e staggered 0 0 0 
15 0 3.515 1.582 T 0.054 0.038 e e staggered 0 0 0 
15 0 5.657 1.61 T 0.038 0.054 e e staggered 0 0 0 
15 0 5.39 1.663 T 0.054 0.038 e e staggered 0 0 0 
15 0 5.35 1.787 T 0.054 0.038 e e staggered 0 0 0 
15 0 3.575 1.579 T 0.024 0.028 e e staggered 0 0 0 
15 0 5.41 1.794 T 0.024 0.028 e e staggered 0 0 0 
15 0 5.4 1.787 D 0.054 0.038 e e staggered 0 0 0 
15 0 5.39 1.646 D 0.024 0.028 e e staggered 0 0 0 
15 0.005 3.50085 1.543 B m e staggered 0 0 0 v 
15 0.005 3.53482 1.54157 B m e staggered 0 0 0 v 
15 0.005 3.57 1.542 B m e staggered 0 0 0 v 
15 0.005 3.605 1.545 B m e staggered 0 0 0 v 
15 0.005 5.3977 1.699 B m e staggered 0 0 0 v 
15 0.005 5.3977 1.724 B m e staggered 0 0 0 v 
15 0.005 5.3977 1.749 B m e staggered 0 0 0 v 
15 0.005 5.4227 1.699 B m e staggered 0 0 0 v 
15 0.005 5.4227 1.724 B m e staggered 0 0 0 v 
15 0.005 5.4352 1.7497 B m e staggered 0 0 0 v 
15 0.005 5.654 2.447 B m e staggered 0 0 0 v 
16 0 0.95248 2.632 T 0.03 0.034 e e staggered 0 0 0 
16 0.005 5.345 2.536 B e e staggered 0 0 0 
16 0.0059999 5.16767 2.6676199 T e e staggered 0 0 0 
16 0 5.16767 2.68731 T 0.041 0.012 e e staggered 0 0 0 
16 0 3.628 2.205 T 0.03 0.034 e e staggered 0 0 0 
16 0 5.278 2.611 T 0.024 0.028 e e staggered 0 0 0 
16 0 5.228 2.521 T 0.038 0.054 e e staggered 0 0 0 
16 0 0.949 2.58048 T 0.028 0.024 e e staggered 0 0 0 
16 0 5.204 2.592 T 0.028 0.024 e e staggered 0 0 0 
16 0 3.612 2.23 D 0.038 0.054 e e staggered 0 0 0 
16 0 3.609 2.17 D 0.028 0.024 e e staggered 0 0 0 
16 0.005 3.555 2.18 B m e staggered 0 0 0 v 
16 0.005 3.555 2.205 B m e staggered 0 0 0 v 
16 0.005 3.555 2.23 B m e staggered 0 0 0 v 
16 0.005 3.555 2.255 B m e staggered 0 0 0 v 
16 0.005 5.22 2.47 B m e staggered 0 0 0 v 
16 0.005 5.239 2.571 B m e staggered 0 0 0 v 
16 0.005 5.243 2.617 B m e staggered 0 0 0 v 
16 0.005 5.254 2.47 B m e staggered 0 0 0 v 
16 0.005 0.985 2.56661 B m e staggered 0 0 0 v 
16 0.005 0.99 2.60025 B m e staggered 0 0 0 v 
17 0 3.623 3.878 T 0.024 0.028 e e staggered 0 0 0 
17 0 3.564 3.833 T 0.028 0.024 e e staggered 0 0 0 
17 0 3.54843 3.892 T 0.012 0.015 e e staggered 0 0 0 
18 0 3.41796 3.98247 T 0.024 0.01 e e staggered 0 0 0 
18 0 3.536 3.78 T 0.028 0.024 e e staggered 0 0 0 
18 0 3.522 3.833 T 0.028 0.024 e e staggered 0 0 0 
18 0 3.52757 3.892 T 0.012 0.015 e e staggered 0 0 0 
18 0 3.516 3.887 D 0.03 0.034 e e staggered 0 0 0 
18 0.005 3.47 3.912 B m e staggered 0 0 0 v 
19 0.005 4.29 2.74 B e e staggered 0 0 0 
19 0 4.41975 2.82429 T 0.033 0.017 e e staggered 0 0 0 
19 0 4.41975 2.86616 T 0.033 0.012 e e staggered 0 0 0 
19 0 4.356 2.876 T 0.071 0.096 e e staggered 0 0 0 
19 0 4.933 2.466 T 0.034 0.03 e e staggered 0 0 0 
19 0 5.7 0.987 T 0.034 0.03 e e staggered 0 0 0 
19 0 3.654 3.099 T 0.03 0.034 e e staggered 0 0 0 
19 0 3.05 3.74787 T 0.146 0.096 e e staggered 0 0 0 
19 0 0.7826 2.4275 T 0.018 0.06 e e staggered 0 0 0 
19 0 2.595 0.605 T 0.028 0.024 e e staggered 0 0 0 
19 0 3.968 2.68 T 0.028 0.024 e e staggered 0 0 0 
19 0 3.623 3.836 T 0.024 0.028 e e staggered 0 0 0 
19 0 5.27 2.811 T 0.024 0.028 e e staggered 0 0 0 
19 0 5.575 0.998 T 0.054 0.038 e e staggered 0 0 0 
19 0 3.32 3.652 T 0.054 0.038 e e staggered 0 0 0 
19 0 3.48 3.652 T 0.054 0.038 e e staggered 0 0 0 
19 0 4.455 2.738 T 0.054 0.038 e e staggered 0 0 0 
19 0 3.4 3.652 T 0.054 0.038 e e staggered 0 0 0 
19 0 0.715 2.402 T 0.024 0.028 e e staggered 0 0 0 
19 0 5.014 2.474 T 0.028 0.024 e e staggered 0 0 0 
19 0 5.64 0.986 T 0.024 0.028 e e staggered 0 0 0 
19 0 3.255 3.664 T 0.024 0.028 e e staggered 0 0 0 
19 0 4.524 2.895 T 0.028 0.024 e e staggered 0 0 0 
19 0 4.39 2.741 T 0.024 0.028 e e staggered 0 0 0 
19 0 3.662 3.018 T 0.024 0.028 e e staggered 0 0 0 
19 0 3.77 0.863 D 0.034 0.03 e e staggered 0 0 0 
19 0 4.27 0.778 D 0.034 0.03 e e staggered 0 0 0 
19 0 2.26 0.677 D 0.034 0.03 e e staggered 0 0 0 
19 0 1.425 3.851 D 0.028 0.024 e e staggered 0 0 0 
19 0 3.581 4.13 D 0.028 0.024 e e staggered 0 0 0 
19 0 4.566 2.795 D 0.028 0.024 e e staggered 0 0 0 
19 0 5.389 2.275 D 0.028 0.024 e e staggered 0 0 0 
19 0 3.662 3.018 D 0.054 0.038 e e staggered 0 0 0 
19 0 5.014 2.454 D 0.038 0.054 e e staggered 0 0 0 
19 0 3.77 0.811 D 0.024 0.028 e e staggered 0 0 0 
19 0 4.269 0.73 D 0.028 0.024 e e staggered 0 0 0 
19 0.005 1.41 3.795 B m e staggered 0 0 0 v 
19 0.005 2.31 0.68 B m e staggered 0 0 0 v 
19 0.005 2.31 0.715 B m e staggered 0 0 0 v 
19 0.005 2.38 3.45 B m e staggered 0 0 0 v 
19 0.005 2.595 0.547 B m e staggered 0 0 0 v 
19 0.005 3.25 3.63 B m e staggered 0 0 0 v 
19 0.005 3.325 3.613 B m e staggered 0 0 0 v 
19 0.005 3.405 3.613 B m e staggered 0 0 0 v 
19 0.005 3.445 3.613 B m e staggered 0 0 0 v 
19 0.005 3.48418 3.613 B m e staggered 0 0 0 v 
19 0.005 3.614 3.015 B m e staggered 0 0 0 v 
19 0.005 3.614 3.058 B m e staggered 0 0 0 v 
19 0.005 3.614 3.099 B m e staggered 0 0 0 v 
19 0.005 3.645 4.135 B m e staggered 0 0 0 v 
19 0.005 3.655 3.059 B m e staggered 0 0 0 v 
19 0.005 4 2.655 B m e staggered 0 0 0 v 
19 0.005 4.23 0.7295 B m e staggered 0 0 0 v 
19 0.005 4.346 2.783 B m e staggered 0 0 0 v 
19 0.005 4.355 2.745 B m e staggered 0 0 0 v 
19 0.005 4.4 2.785 B m e staggered 0 0 0 v 
19 0.005 4.456 2.783 B m e staggered 0 0 0 v 
19 0.005 4.923 2.408 B m e staggered 0 0 0 v 
19 0.005 4.971 2.447 B m e staggered 0 0 0 v 
19 0.005 4.972 2.406 B m e staggered 0 0 0 v 
19 0.005 5.022 2.407 B m e staggered 0 0 0 v 
19 0.005 5.236 2.811 B m e staggered 0 0 0 v 
19 0.005 5.2871 2.275 B m e staggered 0 0 0 v 
19 0.005 5.62533 1.02001 B m e staggered 0 0 0 v 
19 0.005 5.65933 1.02 B m e staggered 0 0 0 v 
19 0.005 0.68 2.355 B m e staggered 0 0 0 v 
19 0.005 0.96 2.41 B m e staggered 0 0 0 v 
19 0.005 3.365 3.613 B m e staggered 0 0 0 v 
19 0.004 3.804 0.816 B m e staggered 0 0 0 v 
19 0.005 4.3305 2.914 B m e staggered 0 0 0 v 
19 0.005 4.3815 2.838 B m e staggered 0 0 0 v 
20 0 3.93169 3.00467 T 0.012 0.041 e e staggered 0 0 0 
20 0 3.835 3.092 T 0.028 0.024 e e staggered 0 0 0 
20 0 3.891 3.092 T 0.028 0.024 e e staggered 0 0 0 
20 0 3.891 3.092 D 0.028 0.024 e e staggered 0 0 0 
20 0 3.835 3.092 D 0.028 0.024 e e staggered 0 0 0 
20 0.004 3.916 3.048 B m e staggered 0 0 0 v 
21 0 3.89231 3.00467 T 0.012 0.041 e e staggered 0 0 0 
21 0.0059999 3.8726199 3.00467 T e e staggered 0 0 0 
21 0 3.708 3.099 T 0.03 0.034 e e staggered 0 0 0 
21 0 3.732 3.018 T 0.054 0.038 e e staggered 0 0 0 
21 0 3.797 3.011 T 0.024 0.028 e e staggered 0 0 0 
21 0 3.793 3.092 D 0.028 0.024 e e staggered 0 0 0 
21 0.004 3.793 3.05 B m e staggered 0 0 0 v 
22 0 5.04833 2.68731 T 0.041 0.012 e e staggered 0 0 0 
22 0.0059999 5.04833 2.6676199 T e e staggered 0 0 0 
22 0 4.933 2.52 T 0.034 0.03 e e staggered 0 0 0 
22 0 4.96 2.594 T 0.024 0.028 e e staggered 0 0 0 
22 0 5.014 2.534 T 0.038 0.054 e e staggered 0 0 0 
22 0 5.042 2.597 T 0.028 0.024 e e staggered 0 0 0 
22 0.005 5.01 2.635 B m e staggered 0 0 0 v 
23 0 5.04833 2.72669 T 0.041 0.012 e e staggered 0 0 0 
23 0 4.889 2.686 T 0.024 0.028 e e staggered 0 0 0 
23 0 4.96 2.636 T 0.024 0.028 e e staggered 0 0 0 
23 0 4.961 2.686 T 0.024 0.028 e e staggered 0 0 0 
23 0 4.961 2.686 D 0.024 0.028 e e staggered 0 0 0 
23 0.004 5.005 2.711 B m e staggered 0 0 0 v 
24 0 2.34842 0.13781 D 0.028 0.165 e e staggered 0 0 0 
24 0 2.3431 0.5839 D 0.024 0.028 e e staggered 0 0 0 
25 0.00985 4.08847 1.68595 T e e staggered 0 0 0 
25 0.0125 4.08847 1.68595 D e e staggered 0 0 0 
25 0 2.3431 0.6259 D 0.024 0.028 e e staggered 0 0 0 
25 0.004 2.40508 0.731 B m e staggered 0 0 0 v 
25 0.004 4.06879 1.66627 B m e staggered 0 0 0 v 
26 0.0059999 3.9513801 3.00467 T e e staggered 0 0 0 
26 0 3.982 3.07957 T 0.015 0.012 e e staggered 0 0 0 
26 0.005 3.96981 3.04482 B m e staggered 0 0 0 v 
27 0.0059999 5.04833 2.7463801 T e e staggered 0 0 0 
27 0 4.97343 2.777 T 0.012 0.015 e e staggered 0 0 0 
27 0.004 5 2.78799 B m e staggered 0 0 0 v 
28 0 3.93169 2.88533 T 0.012 0.041 e e staggered 0 0 0 
28 0 3.926 2.725 T 0.028 0.024 e e staggered 0 0 0 
28 0 3.926 2.68 T 0.028 0.024 e e staggered 0 0 0 
28 0 3.94157 2.774 T 0.012 0.015 e e staggered 0 0 0 
28 0.005 3.948 2.813 B m e staggered 0 0 0 v 
29 0 5.16767 2.72669 T 0.041 0.012 e e staggered 0 0 0 
29 0 5.315 2.769 T 0.024 0.028 e e staggered 0 0 0 
29 0 5.27 2.769 T 0.024 0.028 e e staggered 0 0 0 
29 0 5.26957 2.725 T 0.012 0.015 e e staggered 0 0 0 
29 0.004 5.226 2.762 B m e staggered 0 0 0 v 
30 0.005 0.978 3.918 B e e staggered 0 0 0 
30 0 0.571 3.899 T 0.034 0.03 e e staggered 0 0 0 
30 0 0.783 4.018 T 0.228 0.244 e e staggered 0 0 0 
30 0 5.533 3.569 T 0.03 0.034 e e staggered 0 0 0 
30 0 5.314 3.902 T 0.03 0.034 e e staggered 0 0 0 
30 0 5.55092 3.306 T 0.094 0.13 e e staggered 0 0 0 
30 0.0064999 5.5163101 3.64025 T e e staggered 0 0 0 
30 0 5.55607 3.63305 T 0.001 0.001 e e staggered 0 0 0 
30 0 5.536 3.69369 T 0.049 0.01 e e staggered 0 0 0 
30 0 5.536 3.72913 T 0.049 0.01 e e staggered 0 0 0 
30 0 5.536 3.76456 T 0.049 0.01 e e staggered 0 0 0 
30 0 5.536 3.79999 T 0.049 0.01 e e staggered 0 0 0 
30 0 5.762 3.467 T 0.028 0.024 e e staggered 0 0 0 
30 0 5.32 3.957 T 0.028 0.024 e e staggered 0 0 0 
30 0 5.595 3.569 T 0.028 0.024 e e staggered 0 0 0 
30 0 5.527 3.206 D 0.038 0.054 e e staggered 0 0 0 
30 0 5.531 3.288 D 0.038 0.054 e e staggered 0 0 0 
30 0 5.531 3.364 D 0.038 0.054 e e staggered 0 0 0 
30 0 5.531 3.441 D 0.038 0.054 e e staggered 0 0 0 
30 0.005 5.275 3.931 B m e staggered 0 0 0 v 
30 0.005 5.321 3.99 B m e staggered 0 0 0 v 
30 0.005 5.567 3.203 B m e staggered 0 0 0 v 
30 0.005 5.62 3.316 B m e staggered 0 0 0 v 
30 0.005 5.625 3.361 B m e staggered 0 0 0 v 
30 0.005 0.603 4.011 B m e staggered 0 0 0 v 
30 0.005 0.603 4.131 B m e staggered 0 0 0 v 
30 0.005 0.643 3.956 B m e staggered 0 0 0 v 
30 0.005 0.643 4.076 B m e staggered 0 0 0 v 
30 0.005 0.713 3.942 B m e staggered 0 0 0 v 
30 0.005 0.713 3.992 B m e staggered 0 0 0 v 
30 0.005 0.713 4.042 B m e staggered 0 0 0 v 
30 0.005 0.713 4.092 B m e staggered 0 0 0 v 
30 0.005 0.76 3.942 B m e staggered 0 0 0 v 
30 0.005 0.76 3.992 B m e staggered 0 0 0 v 
30 0.005 0.76 4.042 B m e staggered 0 0 0 v 
30 0.005 0.76 4.092 B m e staggered 0 0 0 v 
30 0.005 0.807 3.942 B m e staggered 0 0 0 v 
30 0.005 0.807 3.992 B m e staggered 0 0 0 v 
30 0.005 0.807 4.042 B m e staggered 0 0 0 v 
30 0.005 0.807 4.092 B m e staggered 0 0 0 v 
30 0.005 0.854 3.942 B m e staggered 0 0 0 v 
30 0.005 0.854 3.992 B m e staggered 0 0 0 v 
30 0.005 0.854 4.042 B m e staggered 0 0 0 v 
30 0.005 0.854 4.092 B m e staggered 0 0 0 v 
30 0.005 0.928 3.961 B m e staggered 0 0 0 v 
30 0.005 0.928 4.081 B m e staggered 0 0 0 v 
30 0.005 0.968 3.961 B m e staggered 0 0 0 v 
30 0.005 0.968 4.021 B m e staggered 0 0 0 v 
30 0.005 0.968 4.141 B m e staggered 0 0 0 v 
30 0.005 5.275 3.891 B m e staggered 0 0 0 v 
30 0.005 5.275 3.971 B m e staggered 0 0 0 v 
30 0.005 5.6 3.421 B m e staggered 0 0 0 v 
30 0.005 5.617 3.203 B m e staggered 0 0 0 v 
30 0.005 5.625 3.261 B m e staggered 0 0 0 v 
30 0.005 0.603 3.951 B m e staggered 0 0 0 v 
30 0.005 0.603 4.071 B m e staggered 0 0 0 v 
30 0.005 0.643 4.016 B m e staggered 0 0 0 v 
30 0.005 0.643 4.136 B m e staggered 0 0 0 v 
30 0.005 0.928 4.021 B m e staggered 0 0 0 v 
30 0.005 0.928 4.141 B m e staggered 0 0 0 v 
30 0.005 0.968 4.081 B m e staggered 0 0 0 v 
30 0.004 5.52 3.67597 B m e staggered 0 0 0 v 
30 0.004 5.52 3.71141 B m e staggered 0 0 0 v 
30 0.004 5.52 3.74684 B m e staggered 0 0 0 v 
30 0.004 5.52 3.78227 B m e staggered 0 0 0 v 
30 0.004 5.552 3.67597 B m e staggered 0 0 0 v 
30 0.004 5.552 3.71141 B m e staggered 0 0 0 v 
30 0.004 5.552 3.74684 B m e staggered 0 0 0 v 
30 0.004 5.552 3.78227 B m e staggered 0 0 0 v 
30 0.004 5.762 3.425 B m e staggered 0 0 0 v 
31 0 5.68467 0.65931 T 0.041 0.012 e e staggered 0 0 0 
31 0 5.775 0.754 T 0.024 0.028 e e staggered 0 0 0 
31 0 5.772 0.7 T 0.024 0.028 e e staggered 0 0 0 
31 0 5.772 0.7 D 0.024 0.028 e e staggered 0 0 0 
31 0 5.775 0.754 D 0.024 0.028 e e staggered 0 0 0 
31 0 5.825 0.754 D 0.024 0.028 e e staggered 0 0 0 
31 0.004 5.7287 0.6757 B m e staggered 0 0 0 v 
32 0 5.68467 0.69869 T 0.041 0.012 e e staggered 0 0 0 
32 0.0059999 5.68467 0.7183801 T e e staggered 0 0 0 
32 0 5.7 0.933 T 0.034 0.03 e e staggered 0 0 0 
32 0 5.775 0.796 T 0.024 0.028 e e staggered 0 0 0 
32 0 5.698 0.859 T 0.038 0.054 e e staggered 0 0 0 
32 0 5.691 0.792 T 0.028 0.024 e e staggered 0 0 0 
32 0.004 5.686 0.76 B m e staggered 0 0 0 v 
33 0 4.41975 2.84647 T 0.033 0.012 e e staggered 0 0 0 
33 0 4.524 2.845 T 0.028 0.024 e e staggered 0 0 0 
33 0 4.524 2.945 D 0.028 0.024 e e staggered 0 0 0 
33 0 4.524 2.795 D 0.028 0.024 e e staggered 0 0 0 
33 0 4.524 2.895 D 0.028 0.024 e e staggered 0 0 0 
33 0 4.524 2.845 D 0.028 0.024 e e staggered 0 0 0 
33 0.005 4.47 2.83 B m e staggered 0 0 0 v 
34 0 2.38779 0.13781 D 0.028 0.165 e e staggered 0 0 0 
34 0 2.39311 0.584 D 0.024 0.028 e e staggered 0 0 0 
35 0.00985 4.0491 1.68595 T e e staggered 0 0 0 
35 0.0125 4.04909 1.68595 D e e staggered 0 0 0 
35 0 2.39311 0.626 D 0.024 0.028 e e staggered 0 0 0 
35 0.004 2.40508 0.699 B m e staggered 0 0 0 v 
35 0.004 4.02942 1.66627 B m e staggered 0 0 0 v 
36 0.0059999 5.68467 0.6396199 T e e staggered 0 0 0 
36 0 5.75957 0.609 T 0.012 0.015 e e staggered 0 0 0 
36 0.004 5.725 0.60301 B m e staggered 0 0 0 v 
37 0 5.56533 0.65931 T 0.041 0.012 e e staggered 0 0 0 
37 0 5.46043 0.635 T 0.012 0.015 e e staggered 0 0 0 
37 0 5.446 0.64 D 0.028 0.024 e e staggered 0 0 0 
37 0 5.555 0.65 D 0.024 0.028 e e staggered 0 0 0 
37 0.005 5.49 0.635 B m e staggered 0 0 0 v 
38 0 4.41975 2.90553 T 0.033 0.012 e e staggered 0 0 0 
38 0 4.524 2.945 T 0.028 0.024 e e staggered 0 0 0 
38 0.005 4.46 2.94 B m e staggered 0 0 0 v 
39 0 2.46653 0.13781 D 0.028 0.165 e e staggered 0 0 0 
39 0 2.46122 0.584 D 0.024 0.028 e e staggered 0 0 0 
40 0.00985 3.93098 1.44973 T e e staggered 0 0 0 
40 0 2.46122 0.626 D 0.024 0.028 e e staggered 0 0 0 
40 0.004 2.47022 0.763 B m e staggered 0 0 0 v 
40 0.004 3.9113 1.43005 B m e staggered 0 0 0 v 
41 0 4.314 0.90634 T 0.025 0.035 e e staggered 0 0 0 
41 0 4.205 0.921 T 0.024 0.028 e e staggered 0 0 0 
41 0 4.27 0.832 D 0.034 0.03 e e staggered 0 0 0 
41 0 4.275 0.919 D 0.024 0.028 e e staggered 0 0 0 
41 0 4.32 0.919 D 0.024 0.028 e e staggered 0 0 0 
41 0.005 4.25 0.877 B m e staggered 0 0 0 v 
42 0 3.88 0.89783 T 0.055 0.039 e e staggered 0 0 0 
42 0 3.77 0.916 T 0.024 0.028 e e staggered 0 0 0 
42 0 3.811 0.97 T 0.028 0.024 e e staggered 0 0 0 
42 0 3.869 0.97 T 0.028 0.024 e e staggered 0 0 0 
42 0 3.77 0.917 D 0.034 0.03 e e staggered 0 0 0 
42 0.004 3.817 0.924 B m e staggered 0 0 0 v 
43 0 2.5059 0.13781 D 0.028 0.165 e e staggered 0 0 0 
43 0 2.51122 0.584 D 0.024 0.028 e e staggered 0 0 0 
44 0.00985 3.89161 1.44973 T e e staggered 0 0 0 
44 0 2.51122 0.626 D 0.024 0.028 e e staggered 0 0 0 
44 0.004 2.50222 0.763 B m e staggered 0 0 0 v 
44 0.004 3.87193 1.43005 B m e staggered 0 0 0 v 
45 0 3.76 2.426 T 0.024 0.028 e e staggered 0 0 0 
45 0 3.705 2.426 T 0.024 0.028 e e staggered 0 0 0 
45 0 3.6576 2.5135 T 0.02 0.047 e e staggered 0 0 0 
45 0.005 3.655 2.465 B m e staggered 0 0 0 v 
46 0 4.414 0.90634 T 0.025 0.035 e e staggered 0 0 0 
46 0 4.418 0.973 T 0.028 0.024 e e staggered 0 0 0 
46 0 4.414 1.031 T 0.024 0.028 e e staggered 0 0 0 
47 0.00985 4.4428 1.44973 T e e staggered 0 0 0 
47 0 4.4165 1.123 T 0.028 0.024 e e staggered 0 0 0 
47 0 4.414 1.073 T 0.024 0.028 e e staggered 0 0 0 
47 0.0125 4.48217 1.44973 D e e staggered 0 0 0 
47 0 4.415 1.121 D 0.024 0.028 e e staggered 0 0 0 
47 0.004 4.4085 1.16599 B m e staggered 0 0 0 v 
47 0.004 4.46248 1.43005 B m e staggered 0 0 0 v 
48 0 4.364 0.90634 T 0.025 0.035 e e staggered 0 0 0 
48 0 4.364 0.973 T 0.028 0.024 e e staggered 0 0 0 
48 0 4.369 1.031 T 0.024 0.028 e e staggered 0 0 0 
49 0.00985 4.48217 1.44973 T e e staggered 0 0 0 
49 0 4.3665 1.123 T 0.028 0.024 e e staggered 0 0 0 
49 0 4.369 1.073 T 0.024 0.028 e e staggered 0 0 0 
49 0.0125 4.52155 1.44973 D e e staggered 0 0 0 
49 0 4.37 1.121 D 0.024 0.028 e e staggered 0 0 0 
49 0.004 4.3765 1.16599 B m e staggered 0 0 0 v 
49 0.004 4.50185 1.43005 B m e staggered 0 0 0 v 
50 0 4.08 0.89783 T 0.055 0.039 e e staggered 0 0 0 
50 0 4.059 0.97 T 0.028 0.024 e e staggered 0 0 0 
50 0 4.055 1.029 T 0.024 0.028 e e staggered 0 0 0 
51 0.00985 4.08847 1.52847 T e e staggered 0 0 0 
51 0 4.055 1.071 T 0.024 0.028 e e staggered 0 0 0 
51 0.0125 4.08847 1.4891 D e e staggered 0 0 0 
51 0.004 4.0485 1.16099 B m e staggered 0 0 0 v 
51 0.004 4.06879 1.50879 B m e staggered 0 0 0 v 
52 0 3.98 0.89783 T 0.055 0.039 e e staggered 0 0 0 
52 0 4.006 0.97 T 0.028 0.024 e e staggered 0 0 0 
52 0 4.01 1.029 T 0.024 0.028 e e staggered 0 0 0 
53 0.00985 4.0491 1.52847 T e e staggered 0 0 0 
53 0 4.01 1.071 T 0.024 0.028 e e staggered 0 0 0 
53 0.0125 4.04909 1.4891 D e e staggered 0 0 0 
53 0.004 4.0165 1.16099 B m e staggered 0 0 0 v 
53 0.004 4.02942 1.50879 B m e staggered 0 0 0 v 
54 0 5.54547 2.21996 T 0.01 0.024 e e staggered 0 0 0 
54 0 5.555 2.324 T 0.024 0.028 e e staggered 0 0 0 
54 0 5.465 2.324 D 0.024 0.028 e e staggered 0 0 0 
54 0 5.51 2.324 D 0.024 0.028 e e staggered 0 0 0 
54 0 5.555 2.324 D 0.024 0.028 e e staggered 0 0 0 
54 0.004 5.53122 2.27979 B m e staggered 0 0 0 v 
55 0 5.395 2.229 T 0.034 0.03 e e staggered 0 0 0 
55 0 5.52087 2.16878 T 0.045 0.016 e e staggered 0 0 0 
55 0 5.62913 2.16878 T 0.045 0.016 e e staggered 0 0 0 
55 0 5.385 2.123 T 0.054 0.038 e e staggered 0 0 0 
55 0 5.76 2.153 T 0.054 0.038 e e staggered 0 0 0 
55 0 5.7 2.151 T 0.024 0.028 e e staggered 0 0 0 
55 0 5.45 2.131 T 0.024 0.028 e e staggered 0 0 0 
55 0 5.465 2.366 D 0.024 0.028 e e staggered 0 0 0 
55 0.005 5.458 2.165 B m e staggered 0 0 0 v 
55 0.005 5.465 2.405 B m e staggered 0 0 0 v 
55 0.005 5.71 2.179 B m e staggered 0 0 0 v 
55 0.005 5.41 2.164 B m e staggered 0 0 0 v 
55 0.005 5.765 2.197 B m e staggered 0 0 0 v 
56 0 5.52087 2.21996 T 0.02 0.024 e e staggered 0 0 0 
56 0 5.465 2.324 T 0.024 0.028 e e staggered 0 0 0 
56 0 5.51 2.32957 T 0.015 0.012 e e staggered 0 0 0 
56 0 5.431 2.275 D 0.028 0.024 e e staggered 0 0 0 
56 0.004 5.48158 2.28033 B m e staggered 0 0 0 v 
57 0 5.56516 2.21996 T 0.01 0.024 e e staggered 0 0 0 
57 0 5.6 2.324 T 0.024 0.028 e e staggered 0 0 0 
58 0 5.63996 2.1924 T 0.024 0.012 e e staggered 0 0 0 
58 0 5.771 2.245 T 0.028 0.024 e e staggered 0 0 0 
58 0 5.64 2.35043 T 0.015 0.012 e e staggered 0 0 0 
58 0 5.6 2.366 T 0.024 0.028 e e staggered 0 0 0 
58 0 5.64 2.1745 D 0.024 0.005 e e staggered 0 0 0 
58 0 5.7 2.372 D 0.034 0.03 e e staggered 0 0 0 
58 0 5.754 2.366 D 0.024 0.028 e e staggered 0 0 0 
58 0 5.645 2.33457 D 0.015 0.012 e e staggered 0 0 0 
58 0.005 5.6 2.4 B m e staggered 0 0 0 v 
58 0.005 5.6695 2.2 B m e staggered 0 0 0 v 
58 0.005 5.789 2.366 B m e staggered 0 0 0 v 
58 0.004 5.771 2.279 B m e staggered 0 0 0 v 
59 0 2.66338 0.13781 D 0.028 0.165 e e staggered 0 0 0 
59 0 2.65807 0.584 D 0.024 0.028 e e staggered 0 0 0 
60 0.00985 4.00973 1.4891 T e e staggered 0 0 0 
60 0 2.65807 0.626 D 0.024 0.028 e e staggered 0 0 0 
60 0.004 2.66707 0.763 B m e staggered 0 0 0 v 
60 0.004 3.99005 1.46942 B m e staggered 0 0 0 v 
61 0 5.6 2.366 D 0.024 0.028 e e staggered 0 0 0 
61 0 5.645 2.35543 D 0.015 0.012 e e staggered 0 0 0 
61 0.015 5.6435 2.38443 D m e staggered 0 0 0 v t 
62 0 5.58484 2.21996 T 0.01 0.024 e e staggered 0 0 0 
62 0 5.64 2.32957 T 0.015 0.012 e e staggered 0 0 0 
62 0 5.6 2.324 D 0.024 0.028 e e staggered 0 0 0 
62 0.004 5.595 2.28 B m e staggered 0 0 0 v 
63 0 5.51 2.129 D 0.024 0.028 e e staggered 0 0 0 
63 0 5.51 2.066 D 0.024 0.028 e e staggered 0 0 0 
63 0.015 5.47211 2.098 D m e staggered 0 0 0 v t 
64 0 5.597 1.94529 T 0.138 0.116 e e staggered 0 0 0 
64 0 5.5622 2.13138 T 0.008 0.106 e e staggered 0 0 0 
64 0 5.5878 2.13138 T 0.008 0.106 e e staggered 0 0 0 
64 0 5.589 1.98 D 0.028 0.024 e e staggered 0 0 0 
64 0 5.51 2.024 D 0.024 0.028 e e staggered 0 0 0 
64 0.005 5.546 2.024 B m e staggered 0 0 0 v 
64 0.005 5.589 2.025 B m e staggered 0 0 0 v 
65 0 5.687 1.99 D 0.038 0.054 e e staggered 0 0 0 
65 0 5.631 1.98 D 0.028 0.024 e e staggered 0 0 0 
66 0 5.696 2.4 T 0.028 0.024 e e staggered 0 0 0 
66 0 5.754 2.366 T 0.024 0.028 e e staggered 0 0 0 
66 0 5.695 2.35543 T 0.015 0.012 e e staggered 0 0 0 
67 0 5.60453 2.21996 T 0.01 0.024 e e staggered 0 0 0 
67 0 5.754 2.324 T 0.024 0.028 e e staggered 0 0 0 
67 0 5.695 2.33457 T 0.015 0.012 e e staggered 0 0 0 
67 0 5.7 2.318 D 0.034 0.03 e e staggered 0 0 0 
67 0 5.754 2.324 D 0.024 0.028 e e staggered 0 0 0 
67 0.004 5.667 2.275 B m e staggered 0 0 0 v 
68 0 2.70275 0.13781 D 0.028 0.165 e e staggered 0 0 0 
68 0 2.70807 0.584 D 0.024 0.028 e e staggered 0 0 0 
69 0.00985 3.97035 1.4891 T e e staggered 0 0 0 
69 0 2.70807 0.626 D 0.024 0.028 e e staggered 0 0 0 
69 0.004 2.69907 0.763 B m e staggered 0 0 0 v 
69 0.004 3.95067 1.46942 B m e staggered 0 0 0 v 
70 0 4.652 3.86 T 0.03 0.034 e e staggered 0 0 0 
70 0 4.78656 3.90827 T 0.088 0.04 e e staggered 0 0 0 
70 0 4.654 3.927 T 0.038 0.054 e e staggered 0 0 0 
70 0 4.778 3.551 D 0.028 0.024 e e staggered 0 0 0 
70 0 4.656 3.895 D 0.028 0.024 e e staggered 0 0 0 
70 0 4.656 3.94 D 0.028 0.024 e e staggered 0 0 0 
70 0.005 4.705 3.91 B m e staggered 0 0 0 v 
70 0.004 4.705 3.95 B m e staggered 0 0 0 v 
71 0 6.033 2.324 T 0.03 0.034 e e staggered 0 0 0 
71 0 6.01953 2.14382 T 0.012 0.041 e e staggered 0 0 0 
71 0 6.029 2.225 T 0.028 0.024 e e staggered 0 0 0 
71 0 6.029 2.27 T 0.028 0.024 e e staggered 0 0 0 
71 0.005 6.01953 2.18853 B m e staggered 0 0 0 v 
72 0 0.89848 2.632 T 0.03 0.034 e e staggered 0 0 0 
72 0 0.81999 2.68069 T 0.014 0.011 e e staggered 0 0 0 
72 0 0.7826 2.2465 T 0.018 0.06 e e staggered 0 0 0 
72 0 0.64248 2.614 T 0.028 0.024 e e staggered 0 0 0 
72 0 0.76948 2.525 T 0.024 0.028 e e staggered 0 0 0 
72 0 0.68448 2.709 T 0.028 0.024 e e staggered 0 0 0 
72 0 0.80648 2.789 T 0.024 0.028 e e staggered 0 0 0 
72 0 0.90848 2.683 T 0.028 0.024 e e staggered 0 0 0 
72 0 0.909 2.728 T 0.028 0.024 e e staggered 0 0 0 
72 0 0.714 2.294 T 0.024 0.028 e e staggered 0 0 0 
72 0.005 0.64248 2.58 B m e staggered 0 0 0 v 
72 0.005 0.714 2.329 B m e staggered 0 0 0 v 
72 0.005 0.869 2.672 B m e staggered 0 0 0 v 
72 0.004 0.686 2.74 B m e staggered 0 0 0 v 
72 0.004 0.736 2.525 B m e staggered 0 0 0 v 
72 0.004 0.871 2.713 B m e staggered 0 0 0 v 
73 0 2.82086 0.13781 D 0.028 0.165 e e staggered 0 0 0 
73 0 2.80055 0.584 D 0.024 0.028 e e staggered 0 0 0 
74 0.00985 3.93098 1.52847 T e e staggered 0 0 0 
74 0 2.80055 0.626 D 0.024 0.028 e e staggered 0 0 0 
74 0.004 2.81855 0.763 B m e staggered 0 0 0 v 
74 0.004 3.9113 1.50879 B m e staggered 0 0 0 v 
75 0 3.491 2.509 T 0.034 0.03 e e staggered 0 0 0 
75 0 3.39984 2.40504 T 0.01 0.023 e e staggered 0 0 0 
75 0 3.45152 2.3829 T 0.027 0.01 e e staggered 0 0 0 
75 0 3.38484 2.511 T 0.024 0.028 e e staggered 0 0 0 
75 0 3.435 2.511 T 0.024 0.028 e e staggered 0 0 0 
75 0.004 3.429 2.468 B m e staggered 0 0 0 v 
76 0.0395 2.86067 2.64043 B e e staggered 0 0 0 
76 0 2.9715 2.352 D 0.055 0.039 e e staggered 0 0 0 
76 0 3.185 2.853 D 0.034 0.03 e e staggered 0 0 0 
76 0 2.7274 2.3065 D 0.02 0.047 e e staggered 0 0 0 
76 0 2.85 2.343 D 0.054 0.038 e e staggered 0 0 0 
76 0 2.91 2.341 D 0.024 0.028 e e staggered 0 0 0 
76 0 3.035 2.847 D 0.054 0.038 e e staggered 0 0 0 
76 0 3.11 2.847 D 0.054 0.038 e e staggered 0 0 0 
76 0 2.96 2.847 D 0.054 0.038 e e staggered 0 0 0 
76 0 2.855 2.844 D 0.024 0.028 e e staggered 0 0 0 
76 0 2.79 2.338 D 0.024 0.028 e e staggered 0 0 0 
76 0 2.9 2.844 D 0.024 0.028 e e staggered 0 0 0 
77 0 1.68331 3.17 T 0.02 0.02 e e staggered 0 0 0 
77 0 1.68331 3.27 T 0.02 0.02 e e staggered 0 0 0 
77 0 1.76 3.187 T 0.034 0.03 e e staggered 0 0 0 
77 0 1.782 3.26 T 0.038 0.054 e e staggered 0 0 0 
77 0 1.819 3.19 T 0.028 0.024 e e staggered 0 0 0 
77 0.005 1.738 3.241 B m e staggered 0 0 0 v 
78 0 3.32848 2.34353 T 0.027 0.01 e e staggered 0 0 0 
78 0 3.201 2.524 T 0.028 0.024 e e staggered 0 0 0 
78 0.004 3.285 2.38645 B m e staggered 0 0 0 v 
79 0.005 3.69 4.135 B e e staggered 0 0 0 
79 0 3.41796 4.04153 T 0.024 0.01 e e staggered 0 0 0 
79 0 3.522 4.077 T 0.028 0.024 e e staggered 0 0 0 
79 0 3.522 4.032 T 0.028 0.024 e e staggered 0 0 0 
79 0 3.522 4.077 D 0.028 0.024 e e staggered 0 0 0 
79 0 3.522 4.032 D 0.028 0.024 e e staggered 0 0 0 
79 0.005 3.48279 4.05678 B m e staggered 0 0 0 v 
80 0 2.15 0.594 T 0.024 0.028 e e staggered 0 0 0 
80 0 2.105 0.594 T 0.024 0.028 e e staggered 0 0 0 
80 0 2.15157 0.13781 T 0.028 0.165 e e staggered 0 0 0 
80 0 6.025 4.089 D 0.024 0.028 e e staggered 0 0 0 
80 0.005 2.135 0.54 B m e staggered 0 0 0 v 
80 0.005 3.36 0.6106 B m e staggered 0 0 0 v 
80 0.005 5.215 0.6 B m e staggered 0 0 0 v 
80 0.005 6.025 4.04 B m e staggered 0 0 0 v 
81 0 2.1122 0.13781 D 0.028 0.165 e e staggered 0 0 0 
81 0 2.15157 0.13781 D 0.028 0.165 e e staggered 0 0 0 
81 0 2.07283 0.13781 T 0.028 0.165 e e staggered 0 0 0 
81 0 2.26 0.623 D 0.034 0.03 e e staggered 0 0 0 
81 0 5.91 4.089 D 0.024 0.028 e e staggered 0 0 0 
81 0 2.2 0.614 D 0.024 0.028 e e staggered 0 0 0 
81 0 2.155 0.614 D 0.024 0.028 e e staggered 0 0 0 
81 0.005 2.235 0.5825 B m e staggered 0 0 0 v 
81 0.005 3.405 0.635 B m e staggered 0 0 0 v 
81 0.005 5.295 0.605 B m e staggered 0 0 0 v 
81 0.005 5.91 4.04 B m e staggered 0 0 0 v 
81 0.004 2.105 0.305 B m e staggered 0 0 0 v 
82 0 1.58104 3.93647 T 0.024 0.01 e e staggered 0 0 0 
82 0 1.477 3.946 T 0.028 0.024 e e staggered 0 0 0 
82 0 1.54 3.776 D 0.028 0.024 e e staggered 0 0 0 
82 0 1.477 3.946 D 0.028 0.024 e e staggered 0 0 0 
82 0 1.477 3.901 D 0.028 0.024 e e staggered 0 0 0 
82 0.015 1.539 3.822 D m e staggered 0 0 0 v t 
82 0.004 1.535 3.905 B m e staggered 0 0 0 v 
83 0.005 5.66 3.47 B e e staggered 0 0 0 
83 0 5.59271 3.65826 T 0.047 0.012 e e staggered 0 0 0 
83 0 5.72 3.467 T 0.028 0.024 e e staggered 0 0 0 
83 0 5.72 3.517 T 0.028 0.024 e e staggered 0 0 0 
83 0 5.72 3.567 T 0.028 0.024 e e staggered 0 0 0 
83 0.004 5.68 3.567 B m e staggered 0 0 0 v 
84 0 1.588 3.776 T 0.03 0.034 e e staggered 0 0 0 
84 0 1.63222 3.91187 T 0.016 0.045 e e staggered 0 0 0 
84 0 1.63222 4.02013 T 0.016 0.045 e e staggered 0 0 0 
84 0 1.648 4.151 T 0.038 0.054 e e staggered 0 0 0 
84 0 1.678 3.776 T 0.038 0.054 e e staggered 0 0 0 
84 0 1.65 4.091 T 0.028 0.024 e e staggered 0 0 0 
84 0 1.67 3.841 T 0.028 0.024 e e staggered 0 0 0 
84 0 1.582 3.776 D 0.028 0.024 e e staggered 0 0 0 
84 0.005 1.591 3.826 B m e staggered 0 0 0 v 
84 0.005 1.6055 4.134 B m e staggered 0 0 0 v 
84 0.005 1.60582 4.1 B m e staggered 0 0 0 v 
84 0.005 1.636 3.786 B m e staggered 0 0 0 v 
84 0.004 1.606 4.174 B m e staggered 0 0 0 v 
84 0.004 1.633 3.829 B m e staggered 0 0 0 v 
85 0 1.73967 3.03469 T 0.041 0.012 e e staggered 0 0 0 
85 0.0059999 1.73967 3.0543801 T e e staggered 0 0 0 
85 0 1.76 3.133 T 0.034 0.03 e e staggered 0 0 0 
85 0 1.835 2.981 T 0.024 0.028 e e staggered 0 0 0 
85 0 1.822 3.105 T 0.038 0.054 e e staggered 0 0 0 
85 0 1.824 3.04 T 0.028 0.024 e e staggered 0 0 0 
85 0.005 1.78 3.095 B m e staggered 0 0 0 v 
86 0 1.73967 2.99531 T 0.041 0.012 e e staggered 0 0 0 
86 0 1.835 2.939 T 0.024 0.028 e e staggered 0 0 0 
86 0 1.885 2.939 T 0.024 0.028 e e staggered 0 0 0 
86 0 1.885 2.939 D 0.024 0.028 e e staggered 0 0 0 
86 0.005 1.795 2.946 B m e staggered 0 0 0 v 
87 0.0059999 1.73967 2.9756199 T e e staggered 0 0 0 
87 0 1.73543 2.9 T 0.012 0.015 e e staggered 0 0 0 
87 0.005 1.765 2.9 B m e staggered 0 0 0 v 
88 0 0.894 3.43758 T 0.064 0.012 e e staggered 0 0 0 
88 0 0.894 3.22105 T 0.064 0.012 e e staggered 0 0 0 
88 0 1.15253 3.12 T 0.012 0.064 e e staggered 0 0 0 
88 0 1.352 3.22105 T 0.064 0.012 e e staggered 0 0 0 
88 0 1.352 3.33916 T 0.064 0.012 e e staggered 0 0 0 
88 0.005 1.535 3.105 B e e staggered 0 0 0 
88 0.0059999 1.62033 3.0543801 T e e staggered 0 0 0 
88 0 1.62033 3.03469 T 0.041 0.012 e e staggered 0 0 0 
88 0 1.455 3.138 T 0.034 0.03 e e staggered 0 0 0 
88 0 1.175 2.939 T 0.024 0.028 e e staggered 0 0 0 
88 0 1.025 2.981 T 0.024 0.028 e e staggered 0 0 0 
88 0 1.53 3.046 T 0.024 0.028 e e staggered 0 0 0 
88 0 1.46 3.073 T 0.054 0.038 e e staggered 0 0 0 
88 0 1.51 3.164 T 0.024 0.028 e e staggered 0 0 0 
88 0 1.32 3.602 D 0.034 0.03 e e staggered 0 0 0 
88 0 1.09 3.458 D 0.034 0.03 e e staggered 0 0 0 
88 0 1.375 3.601 D 0.024 0.028 e e staggered 0 0 0 
88 0 1.7485 3.438 D 0.065 0.02 e e staggered 0 0 0 
88 0 1.7485 3.538 D 0.065 0.02 e e staggered 0 0 0 
88 0 0.746 3.2 D 0.028 0.024 e e staggered 0 0 0 
88 0 0.746 3.245 D 0.028 0.024 e e staggered 0 0 0 
88 0 0.911 3.455 D 0.028 0.024 e e staggered 0 0 0 
88 0 2.146 3.5 D 0.028 0.024 e e staggered 0 0 0 
88 0 2.146 3.55 D 0.028 0.024 e e staggered 0 0 0 
88 0 2.146 3.36 D 0.028 0.024 e e staggered 0 0 0 
88 0 6.145 4.094 D 0.024 0.028 e e staggered 0 0 0 
88 0 1.381 3.235 D 0.028 0.024 e e staggered 0 0 0 
88 0 1.63 3.546 D 0.024 0.028 e e staggered 0 0 0 
88 0 1.154 3.475 D 0.028 0.024 e e staggered 0 0 0 
88 0.005 1.025 3.02 B m e staggered 0 0 0 v 
88 0.005 1.13 3.445 B m e staggered 0 0 0 v 
88 0.005 1.15253 3.06247 B m e staggered 0 0 0 v 
88 0.005 1.175 2.9 B m e staggered 0 0 0 v 
88 0.005 1.37 3.64 B m e staggered 0 0 0 v 
88 0.005 1.407 3.2 B m e staggered 0 0 0 v 
88 0.005 1.41916 3.33916 B m e staggered 0 0 0 v 
88 0.005 1.495 3.11034 B m e staggered 0 0 0 v 
88 0.005 1.515 3.58 B m e staggered 0 0 0 v 
88 0.005 1.591 3.546 B m e staggered 0 0 0 v 
88 0.005 1.667 3.438 B m e staggered 0 0 0 v 
88 0.005 2.19 3.488 B m e staggered 0 0 0 v 
88 0.005 2.192 3.388 B m e staggered 0 0 0 v 
88 0.005 0.945 3.125 B m e staggered 0 0 0 v 
88 0.005 0.95 3.215 B m e staggered 0 0 0 v 
88 0.005 0.95 3.445 B m e staggered 0 0 0 v 
88 0.005 6.145 4.035 B m e staggered 0 0 0 v 
89 0 1.58104 3.95616 T 0.024 0.01 e e staggered 0 0 0 
89 0 1.477 3.991 T 0.028 0.024 e e staggered 0 0 0 
89 0.004 1.5315 3.9459 B m e staggered 0 0 0 v 
90 0 1.6086 4.03096 T 0.012 0.024 e e staggered 0 0 0 
90 0 1.556 4.162 T 0.024 0.028 e e staggered 0 0 0 
90 0 1.45057 4.031 T 0.012 0.015 e e staggered 0 0 0 
90 0 1.435 3.991 T 0.028 0.024 e e staggered 0 0 0 
90 0 1.6265 4.031 D 0.005 0.024 e e staggered 0 0 0 
90 0 1.435 4.142 D 0.028 0.024 e e staggered 0 0 0 
90 0 1.418 4.09 D 0.03 0.034 e e staggered 0 0 0 
90 0 1.477 4.036 D 0.028 0.024 e e staggered 0 0 0 
90 0.005 1.4 4.01 B m e staggered 0 0 0 v 
90 0.005 1.435 4.18 B m e staggered 0 0 0 v 
90 0.005 1.585 4.052 B m e staggered 0 0 0 v 
90 0.004 1.522 4.163 B m e staggered 0 0 0 v 
91 0 0.48957 1.57 T 0.012 0.015 e e staggered 0 0 0 
91 0 0.53 1.486 D 0.024 0.028 e e staggered 0 0 0 
91 0.005 0.48957 1.53619 B m e staggered 0 0 0 v 
92 0 0.52443 1 T 0.012 0.015 e e staggered 0 0 0 
92 0 0.535 0.926 D 0.024 0.028 e e staggered 0 0 0 
92 0.005 0.575 1.015 B m e staggered 0 0 0 v 
93 0.005 4.3 3.865 B e e staggered 0 0 0 
93 0 4.2406 3.93294 T 0.046 0.012 e e staggered 0 0 0 
93 0 4.354 3.865 T 0.028 0.024 e e staggered 0 0 0 
93 0 4.354 3.865 D 0.028 0.024 e e staggered 0 0 0 
93 0 4.24 3.941 D 0.024 0.028 e e staggered 0 0 0 
94 0 0.51743 2.68 T 0.012 0.015 e e staggered 0 0 0 
94 0 0.53 2.626 D 0.024 0.028 e e staggered 0 0 0 
94 0.005 0.528 2.72 B m e staggered 0 0 0 v 
95 0 0.49557 2.166 T 0.012 0.015 e e staggered 0 0 0 
95 0 0.53 2.091 D 0.024 0.028 e e staggered 0 0 0 
95 0.005 0.496 2.13455 B m e staggered 0 0 0 v 
96 0 2.86023 0.13781 D 0.028 0.165 e e staggered 0 0 0 
96 0 2.85055 0.584 D 0.024 0.028 e e staggered 0 0 0 
97 0.00985 3.89161 1.52847 T e e staggered 0 0 0 
97 0 2.85055 0.626 D 0.024 0.028 e e staggered 0 0 0 
97 0.004 2.85055 0.763 B m e staggered 0 0 0 v 
97 0.004 3.87193 1.50879 B m e staggered 0 0 0 v 
98 0 2.97834 0.13781 D 0.028 0.165 e e staggered 0 0 0 
98 0 2.97303 0.584 D 0.024 0.028 e e staggered 0 0 0 
99 0.00985 4.00973 1.56784 T e e staggered 0 0 0 
99 0 2.97303 0.626 D 0.024 0.028 e e staggered 0 0 0 
99 0.004 3.125 0.875 B m e staggered 0 0 0 v 
99 0.004 3.99005 1.54816 B m e staggered 0 0 0 v 
100 0 3.01771 0.13781 D 0.028 0.165 e e staggered 0 0 0 
100 0 3.02303 0.584 D 0.024 0.028 e e staggered 0 0 0 
101 0.00985 3.97035 1.56784 T e e staggered 0 0 0 
101 0 3.02303 0.626 D 0.024 0.028 e e staggered 0 0 0 
101 0.004 3.14763 0.85237 B m e staggered 0 0 0 v 
101 0.004 3.95067 1.54816 B m e staggered 0 0 0 v 
102 0 2.937 3.206 T 0.028 0.024 e e staggered 0 0 0 
102 0 3.0425 3.22543 T 0.062 0.014 e e staggered 0 0 0 
102 0 3.026 3.21 D 0.028 0.024 e e staggered 0 0 0 
102 0 3.026 3.26 D 0.028 0.024 e e staggered 0 0 0 
102 0.005 3.01 3.17 B m e staggered 0 0 0 v 
102 0.005 2.937 3.173 B m e staggered 0 0 0 v 
103 0 5.59271 3.71731 T 0.047 0.012 e e staggered 0 0 0 
103 0 5.71057 3.712 T 0.012 0.015 e e staggered 0 0 0 
103 0.005 5.68326 3.712 B m e staggered 0 0 0 v 
104 0 1.435 3.991 D 0.028 0.024 e e staggered 0 0 0 
104 0 1.435 4.036 D 0.028 0.024 e e staggered 0 0 0 
105 0 1.58104 3.97584 T 0.024 0.01 e e staggered 0 0 0 
105 0 1.47143 4.031 T 0.012 0.015 e e staggered 0 0 0 
105 0 1.477 3.991 D 0.028 0.024 e e staggered 0 0 0 
105 0.004 1.521 3.993 B m e staggered 0 0 0 v 
106 0 1.666 3.885 D 0.028 0.024 e e staggered 0 0 0 
106 0 1.724 3.91 D 0.028 0.024 e e staggered 0 0 0 
106 0.015 1.678 3.927 D m e staggered 0 0 0 v t 
107 0 1.66962 3.9532 T 0.106 0.008 e e staggered 0 0 0 
107 0 1.66962 3.9788 T 0.106 0.008 e e staggered 0 0 0 
107 0 1.84387 3.976 T 0.096 0.146 e e staggered 0 0 0 
107 0 1.8 4.024 D 0.024 0.028 e e staggered 0 0 0 
107 0 1.766 3.91 D 0.028 0.024 e e staggered 0 0 0 
107 0.005 1.75 3.945 B m e staggered 0 0 0 v 
107 0.005 1.77 3.98 B m e staggered 0 0 0 v 
108 0 1.807 4.13 D 0.038 0.054 e e staggered 0 0 0 
108 0 1.8 4.066 D 0.024 0.028 e e staggered 0 0 0 
109 0 3.45152 2.34353 T 0.027 0.01 e e staggered 0 0 0 
109 0 3.57 2.33243 T 0.055 0.033 e e staggered 0 0 0 
109 0 3.63673 2.34643 T 0.015 0.012 e e staggered 0 0 0 
109 0 3.47 2.334 D 0.024 0.028 e e staggered 0 0 0 
109 0.005 3.51 2.33243 B m e staggered 0 0 0 v 
110 0 3.411 4.202 T 0.03 0.034 e e staggered 0 0 0 
110 0 3.36678 4.06613 T 0.016 0.045 e e staggered 0 0 0 
110 0 3.36678 3.95787 T 0.016 0.045 e e staggered 0 0 0 
110 0 3.351 3.827 T 0.038 0.054 e e staggered 0 0 0 
110 0 3.321 4.202 T 0.038 0.054 e e staggered 0 0 0 
110 0 3.349 3.887 T 0.028 0.024 e e staggered 0 0 0 
110 0 3.329 4.137 T 0.028 0.024 e e staggered 0 0 0 
110 0 3.564 4.077 D 0.028 0.024 e e staggered 0 0 0 
110 0.005 3.363 4.152 B m e staggered 0 0 0 v 
110 0.005 3.363 4.192 B m e staggered 0 0 0 v 
110 0.005 3.392 3.803 B m e staggered 0 0 0 v 
110 0.005 3.393 3.84 B m e staggered 0 0 0 v 
110 0.005 3.393 3.877 B m e staggered 0 0 0 v 
110 0.005 3.408 4.152 B m e staggered 0 0 0 v 
110 0.005 3.607 4.062 B m e staggered 0 0 0 v 
110 0.005 3.363 4.232 B m e staggered 0 0 0 v 
111 0 3.41796 4.02184 T 0.024 0.01 e e staggered 0 0 0 
111 0 3.522 3.987 T 0.028 0.024 e e staggered 0 0 0 
112 0 3.3904 3.94704 T 0.012 0.024 e e staggered 0 0 0 
112 0 3.443 3.816 T 0.024 0.028 e e staggered 0 0 0 
112 0 3.494 3.78 T 0.028 0.024 e e staggered 0 0 0 
112 0 3.54843 3.947 T 0.012 0.015 e e staggered 0 0 0 
112 0 3.564 3.987 T 0.028 0.024 e e staggered 0 0 0 
112 0 3.3725 3.947 D 0.005 0.024 e e staggered 0 0 0 
112 0 3.57 3.887 D 0.03 0.034 e e staggered 0 0 0 
112 0 3.522 3.942 D 0.028 0.024 e e staggered 0 0 0 
112 0.005 3.405 3.916 B m e staggered 0 0 0 v 
112 0.005 3.598 3.977 B m e staggered 0 0 0 v 
112 0.005 3.477 3.816 B m e staggered 0 0 0 v 
113 0 5.59271 3.75669 T 0.047 0.012 e e staggered 0 0 0 
113 0 5.72 3.807 T 0.028 0.024 e e staggered 0 0 0 
113 0.005 5.686 3.807 B m e staggered 0 0 0 v 
114 0 3.45152 2.36321 T 0.027 0.01 e e staggered 0 0 0 
114 0 3.57 2.38557 T 0.055 0.033 e e staggered 0 0 0 
114 0 3.63673 2.39157 T 0.015 0.012 e e staggered 0 0 0 
114 0 3.47 2.376 D 0.024 0.028 e e staggered 0 0 0 
114 0.005 3.51 2.37 B m e staggered 0 0 0 v 
115 0 3.564 3.987 D 0.028 0.024 e e staggered 0 0 0 
115 0 3.564 3.942 D 0.028 0.024 e e staggered 0 0 0 
116 0 3.41796 4.00216 T 0.024 0.01 e e staggered 0 0 0 
116 0 3.52757 3.947 T 0.012 0.015 e e staggered 0 0 0 
116 0 3.522 3.987 D 0.028 0.024 e e staggered 0 0 0 
116 0.005 3.476 3.988 B m e staggered 0 0 0 v 
117 0 3.344 4.095 D 0.028 0.024 e e staggered 0 0 0 
117 0 3.286 4.07 D 0.028 0.024 e e staggered 0 0 0 
117 0.015 3.3 4.113 D m e staggered 0 0 0 v t 
118 0 3.32938 4.0248 T 0.106 0.008 e e staggered 0 0 0 
118 0 3.32938 3.9992 T 0.106 0.008 e e staggered 0 0 0 
118 0 3.05 3.98213 T 0.146 0.096 e e staggered 0 0 0 
118 0 3.185 3.921 D 0.024 0.028 e e staggered 0 0 0 
118 0 3.244 4.07 D 0.028 0.024 e e staggered 0 0 0 
118 0.005 3.2 3.985 B m e staggered 0 0 0 v 
118 0.005 3.23 4.015 B m e staggered 0 0 0 v 
119 0 3.185 3.823 D 0.054 0.038 e e staggered 0 0 0 
119 0 3.185 3.879 D 0.024 0.028 e e staggered 0 0 0 
120 0 5.368 3.902 T 0.03 0.034 e e staggered 0 0 0 
120 0 5.47929 3.81574 T 0.047 0.012 e e staggered 0 0 0 
120 0 5.364 3.827 T 0.038 0.054 e e staggered 0 0 0 
120 0.005 5.406 3.863 B m e staggered 0 0 0 v 
121 0 6.225 2.03674 T 0.054 0.038 e e staggered 0 0 0 
121 0 6.289 2.01274 T 0.024 0.028 e e staggered 0 0 0 
121 0 6.26989 2.20184 T 0.02 0.047 e e staggered 0 0 0 
121 0 6.4105 2.05906 T 0.053 0.016 e e staggered 0 0 0 
121 0 6.3 2.00974 D 0.024 0.028 e e staggered 0 0 0 
121 0.005 6.275 2.05374 B m e staggered 0 0 0 v 
121 0.004 6.258 2.15874 B m e staggered 0 0 0 v 
121 0.004 6.335 2.05906 B m e staggered 0 0 0 v 
122 0 2.92734 1.88963 T 0.071 0.01 e e staggered 0 0 0 
122 0 2.7274 2.1935 D 0.02 0.047 e e staggered 0 0 0 
122 0 2.845 2.168 D 0.034 0.03 e e staggered 0 0 0 
122 0 3.002 1.945 D 0.038 0.054 e e staggered 0 0 0 
122 0 2.999 2.005 D 0.028 0.024 e e staggered 0 0 0 
122 0 2.999 2.05 D 0.028 0.024 e e staggered 0 0 0 
122 0 2.79 2.164 D 0.024 0.028 e e staggered 0 0 0 
122 0.015 2.875 2.035 D m e staggered 0 0 0 v t 
122 0.005 2.97772 1.88694 B m e staggered 0 0 0 v 
122 0.005 3.00995 1.87611 B m e staggered 0 0 0 v 
123 0 3.0535 2.217 D 0.055 0.039 e e staggered 0 0 0 
123 0 2.6526 2.3065 D 0.02 0.047 e e staggered 0 0 0 
123 0 2.54 2.306 D 0.024 0.028 e e staggered 0 0 0 
123 0 2.59 2.306 D 0.024 0.028 e e staggered 0 0 0 
123 0 2.41441 2.287 D 0.013 0.038 e e staggered 0 0 0 
123 0.015 2.665 2.065 D m e staggered 0 0 0 v t 
124 0 5.59271 3.79606 T 0.047 0.012 e e staggered 0 0 0 
124 0 5.72 3.857 T 0.028 0.024 e e staggered 0 0 0 
124 0 5.72 3.857 D 0.028 0.024 e e staggered 0 0 0 
124 0.005 5.675 3.865 B m e staggered 0 0 0 v 
125 0 5.12 3.907 T 0.034 0.03 e e staggered 0 0 0 
125 0 4.91549 3.90827 T 0.088 0.04 e e staggered 0 0 0 
125 0 5.05 3.903 T 0.054 0.038 e e staggered 0 0 0 
125 0 5.035 3.896 D 0.024 0.028 e e staggered 0 0 0 
125 0 5.085 3.896 D 0.024 0.028 e e staggered 0 0 0 
125 0.005 5.075 3.945 B m e staggered 0 0 0 v 
125 0.005 5.035 3.945 B m e staggered 0 0 0 v 
126 0 1.58104 3.91187 T 0.024 0.02 e e staggered 0 0 0 
126 0 1.467 3.851 T 0.028 0.024 e e staggered 0 0 0 
126 0 1.47143 3.901 T 0.012 0.015 e e staggered 0 0 0 
126 0 1.467 3.851 D 0.028 0.024 e e staggered 0 0 0 
126 0.004 1.511 3.863 B m e staggered 0 0 0 v 
127 0 3.41796 4.06613 T 0.024 0.02 e e staggered 0 0 0 
127 0 3.52657 4.121 T 0.012 0.015 e e staggered 0 0 0 
127 0 3.539 4.13 D 0.028 0.024 e e staggered 0 0 0 
127 0 3.552 4.197 D 0.028 0.024 e e staggered 0 0 0 
127 0.005 3.48863 4.105 B m e staggered 0 0 0 v 
128 0 5.51631 3.83456 T 0.013 0.044 e e staggered 0 0 0 
128 0 5.362 3.957 T 0.028 0.024 e e staggered 0 0 0 
128 0 5.50643 3.967 T 0.028 0.024 e e staggered 0 0 0 
128 0 5.50643 3.912 T 0.012 0.015 e e staggered 0 0 0 
128 0.004 5.50643 4.009 B m e staggered 0 0 0 v 
129 0 1.25095 3.578 T 0.012 0.064 e e staggered 0 0 0 
129 0 1.271 3.75 T 0.028 0.024 e e staggered 0 0 0 
129 0 1.26957 3.79 T 0.012 0.015 e e staggered 0 0 0 
129 0 1.29831 3.91846 T 0.055 0.047 e e staggered 0 0 0 
130 0 1.23127 3.578 T 0.012 0.064 e e staggered 0 0 0 
130 0 1.229 3.75 T 0.028 0.024 e e staggered 0 0 0 
130 0 1.23543 3.79 T 0.012 0.015 e e staggered 0 0 0 
130 0 1.21169 3.85154 T 0.055 0.047 e e staggered 0 0 0 
131 0 1.0541 3.578 T 0.012 0.064 e e staggered 0 0 0 
131 0 1.0541 3.12 T 0.012 0.064 e e staggered 0 0 0 
131 0 1.352 3.20136 T 0.064 0.012 e e staggered 0 0 0 
131 0 1.352 3.49664 T 0.064 0.012 e e staggered 0 0 0 
131 0 1.035 3.136 D 0.024 0.028 e e staggered 0 0 0 
131 0 1.334 3.5 D 0.028 0.024 e e staggered 0 0 0 
131 0.005 1.04019 3.47425 B m e staggered 0 0 0 v 
131 0.005 1.29 3.215 B m e staggered 0 0 0 v 
131 0.005 1.3 3.49664 B m e staggered 0 0 0 v 
131 0.005 1.0541 3.185 B m e staggered 0 0 0 v 
132 0.008 0.2815 3.4315 B e e staggered 0 0 0 
132 0.008 0.42326 3.4315 B e e staggered 0 0 0 
132 0.008 0.40554 3.4008 B e e staggered 0 0 0 
132 0.008 0.26378 3.4008 B e e staggered 0 0 0 
132 0 1.59669 3.17 T 0.02 0.02 e e staggered 0 0 0 
132 0.005 0.71 3.305 B e e staggered 0 0 0 
132 0 0.72 3.5065 T 0.02 0.047 e e staggered 0 0 0 
132 0 1.055 3.731 D 0.024 0.028 e e staggered 0 0 0 
132 0 0.7 3.426 D 0.024 0.028 e e staggered 0 0 0 
132 0.005 1.56 3.165 B m e staggered 0 0 0 v 
132 0.005 0.72 3.463 B m e staggered 0 0 0 v 
132 0.005 1.45 3.59 B m e staggered 0 0 0 v 
132 0.005 1.56 3.205 B m e staggered 0 0 0 v 
133 0 0.571 3.845 T 0.034 0.03 e e staggered 0 0 0 
133 0 0.693 3.736 T 0.063 0.118 e e staggered 0 0 0 
133 0 1.83661 0.13781 D 0.028 0.165 e e staggered 0 0 0 
133 0 1.87598 0.13781 D 0.028 0.165 e e staggered 0 0 0 
133 0 1.79724 0.13781 T 0.028 0.165 e e staggered 0 0 0 
133 0 1.83661 0.13781 T 0.028 0.165 e e staggered 0 0 0 
133 0 1.87598 0.13781 T 0.028 0.165 e e staggered 0 0 0 
133 0.005 0.625 3.65 B m e staggered 0 0 0 v 
133 0.005 0.625 3.69 B m e staggered 0 0 0 v 
133 0.005 0.625 3.82 B m e staggered 0 0 0 v 
133 0.005 0.66 3.65 B m e staggered 0 0 0 v 
133 0.005 0.665 3.82 B m e staggered 0 0 0 v 
133 0.005 0.695 3.65 B m e staggered 0 0 0 v 
133 0.005 0.705 3.82 B m e staggered 0 0 0 v 
133 0.005 0.73 3.65 B m e staggered 0 0 0 v 
133 0.005 0.625 3.73 B m e staggered 0 0 0 v 
133 0.005 0.625 3.78 B m e staggered 0 0 0 v 
133 0.004 1.86 0.33 B m e staggered 0 0 0 v 
133 0.004 1.87598 0.289 B m e staggered 0 0 0 v 
133 0.004 1.87598 0.369 B m e staggered 0 0 0 v 
133 0.004 1.895 0.33 B m e staggered 0 0 0 v 
134 0.038 6.05315 3.67519 B e e staggered 0 0 0 
134 0.038 6.05315 3.50984 B e e staggered 0 0 0 
134 0.038 6.05315 3.34449 B e e staggered 0 0 0 
134 0 0.873 3.736 T 0.063 0.118 e e staggered 0 0 0 
134 0.005 0.828 3.646 B m e staggered 0 0 0 v 
134 0.005 0.828 3.846 B m e staggered 0 0 0 v 
134 0.005 0.865 3.645 B m e staggered 0 0 0 v 
134 0.005 0.865 3.845 B m e staggered 0 0 0 v 
134 0.005 0.905 3.645 B m e staggered 0 0 0 v 
134 0.005 0.905 3.845 B m e staggered 0 0 0 v 
134 0.005 0.94 3.845 B m e staggered 0 0 0 v 
134 0.005 0.945 3.645 B m e staggered 0 0 0 v 
134 0.005 0.945 3.69 B m e staggered 0 0 0 v 
134 0.005 0.945 3.73 B m e staggered 0 0 0 v 
134 0.005 0.945 3.765 B m e staggered 0 0 0 v 
134 0.005 0.945 3.805 B m e staggered 0 0 0 v 
135 0.0295 0.16039 1.85433 B e e staggered 0 0 0 
135 0 0.455 1.781 T 0.024 0.028 e e staggered 0 0 0 
135 0 0.2725 2.0965 T 0.039 0.057 e e staggered 0 0 0 
135 0.005 0.455 1.825 B m e staggered 0 0 0 v 
136 0.0295 0.16039 2.4252 B e e staggered 0 0 0 
136 0 0.46452 2.233 T 0.024 0.028 e e staggered 0 0 0 
136 0 0.2725 2.1835 T 0.039 0.057 e e staggered 0 0 0 
136 0.005 0.46 2.195 B m e staggered 0 0 0 v 
137 0.0295 0.16039 0.7126 B e e staggered 0 0 0 
137 0 0.2725 0.9565 T 0.039 0.057 e e staggered 0 0 0 
137 0 0.53 0.697 D 0.024 0.028 e e staggered 0 0 0 
137 0.005 0.445 0.735 B m e staggered 0 0 0 v 
138 0.0295 0.16039 1.28346 B e e staggered 0 0 0 
138 0 0.455 1.0839 T 0.024 0.028 e e staggered 0 0 0 
138 0 0.2725 1.0435 T 0.039 0.057 e e staggered 0 0 0 
138 0.005 0.455 1.0439 B m e staggered 0 0 0 v 
139 0 4.2745 3.71339 T 0.062 0.014 e e staggered 0 0 0 
139 0 5.71056 2.821 T 0.14 0.05 e e staggered 0 0 0 
139 0 5.544 2.9225 D 0.028 0.024 e e staggered 0 0 0 
139 0 5.6705 2.9225 D 0.039 0.057 e e staggered 0 0 0 
139 0.005 4.205 3.81 B m e staggered 0 0 0 v 
139 0.004 5.814 2.821 B m e staggered 0 0 0 v 
140 0 4.0355 3.6622 T 0.062 0.014 e e staggered 0 0 0 
140 0 5.71056 3.021 T 0.14 0.05 e e staggered 0 0 0 
140 0 5.546 3.02 D 0.028 0.024 e e staggered 0 0 0 
140 0 5.6705 3.0095 D 0.039 0.057 e e staggered 0 0 0 
140 0.005 3.895 3.7 B m e staggered 0 0 0 v 
140 0.004 5.815 3.021 B m e staggered 0 0 0 v 
141 0 4.0355 3.73898 T 0.062 0.014 e e staggered 0 0 0 
141 0 5.71056 2.621 T 0.14 0.05 e e staggered 0 0 0 
141 0 5.546 2.64 D 0.028 0.024 e e staggered 0 0 0 
141 0 5.6755 2.6375 D 0.039 0.057 e e staggered 0 0 0 
141 0.005 4.135 3.735 B m e staggered 0 0 0 v 
141 0.004 5.814 2.621 B m e staggered 0 0 0 v 
142 0 4.2745 3.63661 T 0.062 0.014 e e staggered 0 0 0 
142 0 5.71056 2.721 T 0.14 0.05 e e staggered 0 0 0 
142 0 5.546 2.77 D 0.028 0.024 e e staggered 0 0 0 
142 0 5.6755 2.7245 D 0.039 0.057 e e staggered 0 0 0 
142 0.005 4.19 3.735 B m e staggered 0 0 0 v 
142 0.004 5.814 2.721 B m e staggered 0 0 0 v 
143 0 5.43504 4.27558 T 0.031 0.031 e e staggered 0 0 0 
143 0 5.435 4.261 D 0.024 0.028 e e staggered 0 0 0 
143 0.005 5.38558 4.27558 B m e staggered 0 0 0 v 
144 0.00985 4.00973 1.8828 T e e staggered 0 0 0 
144 0 5.43504 4.21654 T 0.031 0.031 e e staggered 0 0 0 
144 0.005 5.48829 4.16329 B m e staggered 0 0 0 v 
144 0.004 3.99005 1.90248 B m e staggered 0 0 0 v 
145 0 6.02559 4.27558 T 0.031 0.031 e e staggered 0 0 0 
145 0 6.027 4.261 D 0.024 0.028 e e staggered 0 0 0 
145 0.005 5.97613 4.27558 B m e staggered 0 0 0 v 
146 0.00985 3.89161 1.80406 T e e staggered 0 0 0 
146 0 6.02559 4.21654 T 0.031 0.031 e e staggered 0 0 0 
146 0.005 6.02559 4.175 B m e staggered 0 0 0 v 
146 0.004 3.83128 1.78372 B m e staggered 0 0 0 v 
147 0 6.1437 4.27558 T 0.031 0.031 e e staggered 0 0 0 
147 0 6.14 4.261 D 0.024 0.028 e e staggered 0 0 0 
147 0.005 6.09424 4.27558 B m e staggered 0 0 0 v 
148 0.00985 3.89161 1.84343 T e e staggered 0 0 0 
148 0 6.1437 4.21654 T 0.031 0.031 e e staggered 0 0 0 
148 0.005 6.1437 4.175 B m e staggered 0 0 0 v 
148 0.004 3.87193 1.86311 B m e staggered 0 0 0 v 
149 0 6.1437 4.13779 T 0.031 0.031 e e staggered 0 0 0 
149 0 6.145 4.136 D 0.024 0.028 e e staggered 0 0 0 
149 0.005 6.09424 4.13779 B m e staggered 0 0 0 v 
150 0 0.06874 1.4872 T 0.035 0.033 e e staggered 0 0 0 
150 0 0.191 1.56898 T 0.024 0.028 e e staggered 0 0 0 
150 0 0.236 1.56898 T 0.024 0.028 e e staggered 0 0 0 
150 0.005 0.1362 1.4872 B m e staggered 0 0 0 v 
151 0 0.08252 1.5561 T 0.02 0.018 e e staggered 0 0 0 
151 0 0.281 1.56898 T 0.024 0.028 e e staggered 0 0 0 
151 0 0.326 1.56898 T 0.024 0.028 e e staggered 0 0 0 
151 0.005 0.13 1.57 B m e staggered 0 0 0 v 
152 0 0.06874 1.59154 T 0.035 0.033 e e staggered 0 0 0 
152 0 0.416 1.56898 T 0.024 0.028 e e staggered 0 0 0 
152 0 0.371 1.56898 T 0.024 0.028 e e staggered 0 0 0 
152 0.005 0.125 1.62 B m e staggered 0 0 0 v 
153 0 0.06874 0.91633 T 0.035 0.033 e e staggered 0 0 0 
153 0 0.779 1.05 T 0.028 0.024 e e staggered 0 0 0 
153 0 0.779 1.1 T 0.028 0.024 e e staggered 0 0 0 
153 0.005 0.675 1.145 B m e staggered 0 0 0 v 
153 0.005 0.125 0.91 B m e staggered 0 0 0 v 
154 0 0.08252 0.98523 T 0.02 0.018 e e staggered 0 0 0 
154 0 0.779 1.15 T 0.028 0.024 e e staggered 0 0 0 
154 0 0.779 1.2 T 0.028 0.024 e e staggered 0 0 0 
154 0.005 0.68 1.19 B m e staggered 0 0 0 v 
154 0.005 0.125 1.01 B m e staggered 0 0 0 v 
155 0 0.06874 1.02067 T 0.035 0.033 e e staggered 0 0 0 
155 0 0.779 1.3 T 0.028 0.024 e e staggered 0 0 0 
155 0 0.779 1.25 T 0.028 0.024 e e staggered 0 0 0 
155 0.005 0.735 1.19 B m e staggered 0 0 0 v 
155 0.005 0.125 1.06 B m e staggered 0 0 0 v 
156 0 0.06874 2.62893 T 0.035 0.033 e e staggered 0 0 0 
156 0 0.197 2.70608 T 0.024 0.028 e e staggered 0 0 0 
156 0 0.242 2.70608 T 0.024 0.028 e e staggered 0 0 0 
156 0.005 0.125 2.615 B m e staggered 0 0 0 v 
157 0 0.08252 2.69783 T 0.02 0.018 e e staggered 0 0 0 
157 0 0.287 2.70608 T 0.024 0.028 e e staggered 0 0 0 
157 0 0.332 2.70608 T 0.024 0.028 e e staggered 0 0 0 
157 0.005 0.287 2.743 B m e staggered 0 0 0 v 
158 0 0.06874 2.73327 T 0.035 0.033 e e staggered 0 0 0 
158 0 0.422 2.70608 T 0.024 0.028 e e staggered 0 0 0 
158 0 0.377 2.70608 T 0.024 0.028 e e staggered 0 0 0 
158 0.005 0.13 2.73327 B m e staggered 0 0 0 v 
159 0 0.06874 2.05807 T 0.035 0.033 e e staggered 0 0 0 
159 0 0.74547 1.75 T 0.028 0.024 e e staggered 0 0 0 
159 0 0.74547 1.795 T 0.028 0.024 e e staggered 0 0 0 
159 0.005 0.69 1.875 B m e staggered 0 0 0 v 
159 0.005 0.125 2.045 B m e staggered 0 0 0 v 
160 0 0.08252 2.12697 T 0.02 0.018 e e staggered 0 0 0 
160 0 0.74547 1.84 T 0.028 0.024 e e staggered 0 0 0 
160 0 0.74547 1.885 T 0.028 0.024 e e staggered 0 0 0 
160 0.005 0.69 1.93 B m e staggered 0 0 0 v 
160 0.005 0.125 2.145 B m e staggered 0 0 0 v 
161 0 0.06874 2.16241 T 0.035 0.033 e e staggered 0 0 0 
161 0 0.74547 1.975 T 0.028 0.024 e e staggered 0 0 0 
161 0 0.74547 1.93 T 0.028 0.024 e e staggered 0 0 0 
161 0.005 0.69023 1.98524 B m e staggered 0 0 0 v 
161 0.005 0.125 2.195 B m e staggered 0 0 0 v 
162 0 0.06874 3.1998 T 0.035 0.033 e e staggered 0 0 0 
162 0 0.23 3.231 T 0.024 0.028 e e staggered 0 0 0 
162 0 0.18 3.231 T 0.024 0.028 e e staggered 0 0 0 
162 0.005 0.13 3.187 B m e staggered 0 0 0 v 
163 0 0.08252 3.2687 T 0.02 0.018 e e staggered 0 0 0 
163 0 0.33 3.231 T 0.024 0.028 e e staggered 0 0 0 
163 0 0.28 3.231 T 0.024 0.028 e e staggered 0 0 0 
163 0.005 0.28 3.27 B m e staggered 0 0 0 v 
164 0 0.06874 3.30414 T 0.035 0.033 e e staggered 0 0 0 
164 0 0.38 3.231 T 0.024 0.028 e e staggered 0 0 0 
164 0 0.43 3.231 T 0.024 0.028 e e staggered 0 0 0 
164 0.005 0.355 3.27 B m e staggered 0 0 0 v 
165 0 5.90748 4.13779 T 0.031 0.031 e e staggered 0 0 0 
165 0 5.91 4.131 D 0.024 0.028 e e staggered 0 0 0 
165 0.005 5.90748 4.18725 B m e staggered 0 0 0 v 
166 0 5.55315 4.27558 T 0.031 0.031 e e staggered 0 0 0 
166 0 5.555 4.261 D 0.024 0.028 e e staggered 0 0 0 
166 0.005 5.50369 4.27558 B m e staggered 0 0 0 v 
167 0.00985 4.00973 1.84343 T e e staggered 0 0 0 
167 0 5.55315 4.21654 T 0.031 0.031 e e staggered 0 0 0 
167 0.005 5.55315 4.175 B m e staggered 0 0 0 v 
167 0.004 3.99005 1.86311 B m e staggered 0 0 0 v 
168 0 6.02559 4.13779 T 0.031 0.031 e e staggered 0 0 0 
168 0 6.025 4.131 D 0.024 0.028 e e staggered 0 0 0 
168 0.005 5.97613 4.13779 B m e staggered 0 0 0 v 
169 0 5.67126 4.27558 T 0.031 0.031 e e staggered 0 0 0 
169 0 5.67 4.261 D 0.024 0.028 e e staggered 0 0 0 
169 0.005 5.6218 4.27558 B m e staggered 0 0 0 v 
170 0.00985 3.97035 1.80406 T e e staggered 0 0 0 
170 0 5.67126 4.21654 T 0.031 0.031 e e staggered 0 0 0 
170 0.005 5.67126 4.175 B m e staggered 0 0 0 v 
170 0.004 3.95067 1.82374 B m e staggered 0 0 0 v 
171 0 5.78937 4.27558 T 0.031 0.031 e e staggered 0 0 0 
171 0 5.79 4.261 D 0.024 0.028 e e staggered 0 0 0 
171 0.005 5.73991 4.27558 B m e staggered 0 0 0 v 
172 0.00985 3.93098 1.80406 T e e staggered 0 0 0 
172 0 5.78937 4.21654 T 0.031 0.031 e e staggered 0 0 0 
172 0.005 5.78937 4.175 B m e staggered 0 0 0 v 
172 0.004 3.9113 1.82374 B m e staggered 0 0 0 v 
173 0 5.78937 4.13779 T 0.031 0.031 e e staggered 0 0 0 
173 0 5.769 4.12 D 0.028 0.024 e e staggered 0 0 0 
173 0.005 5.725 4.135 B m e staggered 0 0 0 v 
174 0 5.43504 4.13779 T 0.031 0.031 e e staggered 0 0 0 
174 0 5.435 4.124 D 0.024 0.028 e e staggered 0 0 0 
174 0.005 5.38558 4.13779 B m e staggered 0 0 0 v 
175 0 5.55315 4.13779 T 0.031 0.031 e e staggered 0 0 0 
175 0 5.529 4.115 D 0.028 0.024 e e staggered 0 0 0 
175 0.005 5.485 4.11 B m e staggered 0 0 0 v 
176 0 5.67126 4.13779 T 0.031 0.031 e e staggered 0 0 0 
176 0 5.675 4.126 D 0.024 0.028 e e staggered 0 0 0 
176 0.005 5.6218 4.13779 B m e staggered 0 0 0 v 
177 0 5.283 4.20953 T 0.031 0.031 e e staggered 0 0 0 
177 0 5.323 4.20101 D 0.024 0.028 e e staggered 0 0 0 
177 0.004 5.323 4.257 B m e staggered 0 0 0 v 
178 0 3.0585 2.315 D 0.055 0.039 e e staggered 0 0 0 
178 0 2.845 2.222 D 0.034 0.03 e e staggered 0 0 0 
178 0 2.85 2.277 D 0.054 0.038 e e staggered 0 0 0 
178 0.015 2.95 2.13 D m e staggered 0 0 0 v t 
179 0 2.51122 0.626 T 0.024 0.028 e e staggered 0 0 0 
179 0 1.79724 0.15731 D 0.028 0.126 e e staggered 0 0 0 
179 0 1.8646 0.6022 D 0.024 0.028 e e staggered 0 0 0 
179 0.005 1.889 0.5496 B m e staggered 0 0 0 v 
179 0.004 2.435 0.4865 B m e staggered 0 0 0 v 
180 0 1.95472 0.13781 D 0.028 0.165 e e staggered 0 0 0 
180 0 5.546 2.595 D 0.028 0.024 e e staggered 0 0 0 
180 0.015 1.924 0.45786 D m e staggered 0 0 0 v t 
180 0.005 5.08 1.055 B m e staggered 0 0 0 v 
180 0.004 2.0788 0.7874 B m e staggered 0 0 0 v 
181 0 1.99409 0.13781 D 0.028 0.165 e e staggered 0 0 0 
181 0 5.546 3.065 D 0.028 0.024 e e staggered 0 0 0 
181 0.015 1.98 0.495 D m e staggered 0 0 0 v t 
181 0.005 5.08 1.155 B m e staggered 0 0 0 v 
181 0.004 2.03 0.75 B m e staggered 0 0 0 v 
182 0 2.03346 0.13781 D 0.028 0.165 e e staggered 0 0 0 
182 0 5.546 2.815 D 0.028 0.024 e e staggered 0 0 0 
182 0.015 2.0137 0.43 D m e staggered 0 0 0 v t 
182 0.005 2.0816 0.7399 B m e staggered 0 0 0 v 
182 0.005 5.132 0.66 B m e staggered 0 0 0 v 
182 0.005 5.225 1.145 B m e staggered 0 0 0 v 
183 0 2.07283 0.13781 D 0.028 0.165 e e staggered 0 0 0 
183 0 5.454 2.87 D 0.028 0.024 e e staggered 0 0 0 
183 0.015 2.08295 0.525 D m e staggered 0 0 0 v t 
183 0.005 5.08 1.105 B m e staggered 0 0 0 v 
183 0.004 2.1481 0.7881 B m e staggered 0 0 0 v 
184 0 2.637 0.655 T 0.028 0.024 e e staggered 0 0 0 
184 0 2.637 0.605 T 0.028 0.024 e e staggered 0 0 0 
184 0 2.754 0.605 T 0.038 0.013 e e staggered 0 0 0 
184 0 2.19094 0.13781 D 0.028 0.165 e e staggered 0 0 0 
184 0.005 2.29582 0.48918 B e e staggered 0 0 0 
184 0.004 2.633 0.522 B m e staggered 0 0 0 v 
185 0 1.8832 0.69 T 0.065 0.02 e e staggered 0 0 0 
185 0 1.95472 0.13781 T 0.028 0.165 e e staggered 0 0 0 
185 0.004 1.91535 0.412 B m e staggered 0 0 0 v 
185 0.004 1.8039 0.7072 B m e staggered 0 0 0 v 
186 0 1.6622 0.69 T 0.065 0.02 e e staggered 0 0 0 
186 0 1.99409 0.13781 T 0.028 0.165 e e staggered 0 0 0 
186 0.005 1.7317 0.7084 B m e staggered 0 0 0 v 
186 0.004 1.98135 0.365 B m e staggered 0 0 0 v 
187 0.00985 3.93098 1.60721 T e e staggered 0 0 0 
187 0 2.38779 0.13781 T 0.028 0.165 e e staggered 0 0 0 
187 0.004 2.95835 0.481 B m e staggered 0 0 0 v 
187 0.004 3.9113 1.58753 B m e staggered 0 0 0 v 
188 0.00985 3.89161 1.60721 T e e staggered 0 0 0 
188 0 2.42716 0.13781 T 0.028 0.165 e e staggered 0 0 0 
188 0.004 2.95835 0.449 B m e staggered 0 0 0 v 
188 0.004 3.87193 1.58753 B m e staggered 0 0 0 v 
189 0 2.51122 0.584 T 0.024 0.028 e e staggered 0 0 0 
189 0 2.5059 0.13781 T 0.028 0.165 e e staggered 0 0 0 
189 0.004 2.54527 0.339 B m e staggered 0 0 0 v 
189 0.004 2.527 0.44 B m e staggered 0 0 0 v 
190 0.00985 4.00973 1.72532 T e e staggered 0 0 0 
190 0 2.58464 0.13781 T 0.028 0.165 e e staggered 0 0 0 
190 0.004 2.64339 0.385 B m e staggered 0 0 0 v 
190 0.004 3.99005 1.70564 B m e staggered 0 0 0 v 
191 0.00985 3.97035 1.72532 T e e staggered 0 0 0 
191 0 2.62401 0.13781 T 0.028 0.165 e e staggered 0 0 0 
191 0.004 3.95067 1.70564 B m e staggered 0 0 0 v 
191 0.004 2.64339 0.353 B m e staggered 0 0 0 v 
192 0.00985 3.93098 1.68595 T e e staggered 0 0 0 
192 0 2.74212 0.13781 T 0.028 0.165 e e staggered 0 0 0 
192 0.004 2.80087 0.385 B m e staggered 0 0 0 v 
192 0.004 3.9113 1.66627 B m e staggered 0 0 0 v 
193 0.00985 3.89161 1.68595 T e e staggered 0 0 0 
193 0 2.78149 0.13781 T 0.028 0.165 e e staggered 0 0 0 
193 0.004 2.80087 0.353 B m e staggered 0 0 0 v 
193 0.004 3.87193 1.66627 B m e staggered 0 0 0 v 
194 0.00985 4.00973 1.64658 T e e staggered 0 0 0 
194 0 2.8996 0.13781 T 0.028 0.165 e e staggered 0 0 0 
194 0.004 2.95835 0.385 B m e staggered 0 0 0 v 
194 0.004 3.99005 1.6269 B m e staggered 0 0 0 v 
195 0.00985 3.97035 1.64658 T e e staggered 0 0 0 
195 0 2.93897 0.13781 T 0.028 0.165 e e staggered 0 0 0 
195 0.004 2.95835 0.353 B m e staggered 0 0 0 v 
195 0.004 3.95067 1.6269 B m e staggered 0 0 0 v 
196 0 3.05708 0.15731 T 0.028 0.126 e e staggered 0 0 0 
196 0 1.8646 0.6442 D 0.024 0.028 e e staggered 0 0 0 
196 0.004 1.8062 0.7789 B m e staggered 0 0 0 v 
196 0.004 3.073 0.613 B m e staggered 0 0 0 v 
197 0 6.22356 2.615 T 0.14 0.05 e e staggered 0 0 0 
197 0 6.22356 2.715 T 0.14 0.05 e e staggered 0 0 0 
197 0 1.28 3.094 D 0.024 0.028 e e staggered 0 0 0 
197 0.005 1.35 3.12 B m e staggered 0 0 0 v 
197 0.005 2.3 3.475 B m e staggered 0 0 0 v 
197 0.005 5.045 3.405 B m e staggered 0 0 0 v 
197 0.004 6.33 2.67 B m e staggered 0 0 0 v 
198 0 6.01844 2.615 T 0.14 0.05 e e staggered 0 0 0 
198 0 5.994 2.615 D 0.028 0.024 e e staggered 0 0 0 
198 0.004 5.91 2.615 B m e staggered 0 0 0 v 
199 0 4.885 3.504 T 0.024 0.028 e e staggered 0 0 0 
199 0 6.01844 2.715 T 0.14 0.05 e e staggered 0 0 0 
199 0.005 5.91 2.715 B m e staggered 0 0 0 v 
200 0 6.22356 2.815 T 0.14 0.05 e e staggered 0 0 0 
200 0 6.22356 2.915 T 0.14 0.05 e e staggered 0 0 0 
200 0 1.381 3.28 D 0.028 0.024 e e staggered 0 0 0 
200 0.005 1.46 3.34 B m e staggered 0 0 0 v 
200 0.005 2.255 3.475 B m e staggered 0 0 0 v 
200 0.005 5.09 3.405 B m e staggered 0 0 0 v 
200 0.005 6.33 2.865 B m e staggered 0 0 0 v 
201 0 6.01844 2.815 T 0.14 0.05 e e staggered 0 0 0 
201 0 5.994 2.79 D 0.028 0.024 e e staggered 0 0 0 
201 0.005 5.91 2.785 B m e staggered 0 0 0 v 
202 0 4.985 3.504 T 0.024 0.028 e e staggered 0 0 0 
202 0 6.01844 2.915 T 0.14 0.05 e e staggered 0 0 0 
202 0.005 5.91 2.915 B m e staggered 0 0 0 v 
203 0.005 5.41 0.96 B e e staggered 0 0 0 
203 0.00985 4.52154 1.76469 T e e staggered 0 0 0 
203 0 1.425 3.851 T 0.028 0.024 e e staggered 0 0 0 
203 0 4.566 2.995 T 0.028 0.024 e e staggered 0 0 0 
203 0 6.01844 3.015 T 0.14 0.05 e e staggered 0 0 0 
203 0 4.884 1.765 D 0.028 0.024 e e staggered 0 0 0 
203 0 5.404 0.64 D 0.028 0.024 e e staggered 0 0 0 
203 0.005 4.565 3.055 B m e staggered 0 0 0 v 
203 0.005 4.85033 1.74934 B m e staggered 0 0 0 v 
203 0.005 5.26 2.955 B m e staggered 0 0 0 v 
203 0.005 4.3 3.81 B m e staggered 0 0 0 v 
203 0.004 1.3825 3.7225 B m e staggered 0 0 0 v 
203 0.004 5.905 3.015 B m e staggered 0 0 0 v 
203 0.004 4.54122 1.78437 B m e staggered 0 0 0 v 
204 0 3.58207 1.93911 T 0.037 0.008 e e staggered 0 0 0 
204 0 6.23249 2.20184 T 0.02 0.047 e e staggered 0 0 0 
204 0 6.4105 2.08465 T 0.053 0.016 e e staggered 0 0 0 
204 0.004 3.657 0.92 B m e staggered 0 0 0 v 
204 0.004 6.19961 2.24474 B m e staggered 0 0 0 v 
205 0 3.58207 1.92336 T 0.037 0.008 e e staggered 0 0 0 
205 0 6.30729 2.20184 T 0.02 0.047 e e staggered 0 0 0 
205 0 6.4105 2.11024 T 0.053 0.016 e e staggered 0 0 0 
205 0.004 3.625 0.92 B m e staggered 0 0 0 v 
205 0.004 6.19961 2.27674 B m e staggered 0 0 0 v 
206 0.008 0.31694 3.4315 B e e staggered 0 0 0 
206 0 0.595 3.554 T 0.024 0.028 e e staggered 0 0 0 
206 0.005 0.55 3.554 B m e staggered 0 0 0 v 
207 0.008 0.35238 3.4315 B e e staggered 0 0 0 
207 0.008 0.33466 3.4008 B e e staggered 0 0 0 
207 0 1.105 3.731 T 0.024 0.028 e e staggered 0 0 0 
207 0 0.6826 3.5065 T 0.02 0.047 e e staggered 0 0 0 
207 0.004 1.073 3.825 B m e staggered 0 0 0 v 
207 0.004 0.703 3.575 B m e staggered 0 0 0 v 
208 0.008 0.38782 3.4315 B e e staggered 0 0 0 
208 0.008 0.29922 3.4008 B e e staggered 0 0 0 
208 0 1.155 3.731 T 0.024 0.028 e e staggered 0 0 0 
208 0 0.7574 3.5065 T 0.02 0.047 e e staggered 0 0 0 
208 0.004 1.105 3.825 B m e staggered 0 0 0 v 
208 0.004 0.735 3.575 B m e staggered 0 0 0 v 
209 0.008 0.3701 3.4008 B e e staggered 0 0 0 
209 0 0.589 3.29 T 0.028 0.024 e e staggered 0 0 0 
209 0.005 0.55 3.36 B m e staggered 0 0 0 v 
210 0 5.50544 2.721 T 0.14 0.05 e e staggered 0 0 0 
210 0 5.502 2.721 D 0.028 0.024 e e staggered 0 0 0 
210 0.004 5.40318 2.70436 B m e staggered 0 0 0 v 
211 0.005 3.445 2.65 B e e staggered 0 0 0 
211 0 3.44256 2.765 T 0.14 0.05 e e staggered 0 0 0 
211 0 1.0705 0.7284 T 0.047 0.02 e e staggered 0 0 0 
211 0 1.1737 0.7536 T 0.028 0.024 e e staggered 0 0 0 
211 0 1.08 0.718 D 0.028 0.024 e e staggered 0 0 0 
211 0 1.1737 0.7086 D 0.028 0.024 e e staggered 0 0 0 
211 0.005 3.035 1.64 B m e staggered 0 0 0 v 
211 0.004 1.1288 0.7302 B m e staggered 0 0 0 v 
212 0 0.7878 0.7085 T 0.014 0.062 e e staggered 0 0 0 
212 0.005 0.755 0.62 B e e staggered 0 0 0 
212 0 3.44256 2.865 T 0.14 0.05 e e staggered 0 0 0 
212 0 0.799 0.711 D 0.024 0.028 e e staggered 0 0 0 
212 0 0.809 0.665 D 0.028 0.024 e e staggered 0 0 0 
212 0 0.847 0.71 D 0.028 0.024 e e staggered 0 0 0 
212 0.005 3.075 1.605 B m e staggered 0 0 0 v 
212 0.004 3.365 2.95 B m e staggered 0 0 0 v 
213 0 0.804 2.15104 T 0.039 0.041 e e staggered 0 0 0 
213 0 0.908 2.789 D 0.024 0.028 e e staggered 0 0 0 
213 0.005 0.959 2.789 B m e staggered 0 0 0 v 
213 0.005 0.845 2.18 B m e staggered 0 0 0 v 
214 0 6.14648 1.77063 T 0.092 0.056 e e staggered 0 0 0 
214 0 6.155 1.769 D 0.024 0.028 e e staggered 0 0 0 
214 0.005 6.22 1.755 B m e staggered 0 0 0 v 
215 0 5.9945 1.77063 T 0.088 0.056 e e staggered 0 0 0 
215 0 5.98 1.781 D 0.024 0.028 e e staggered 0 0 0 
215 0.005 5.92 1.78 B m e staggered 0 0 0 v 
216 0 6.14648 1.67063 T 0.092 0.056 e e staggered 0 0 0 
216 0 6.17 1.676 D 0.024 0.028 e e staggered 0 0 0 
216 0.005 6.22035 1.67063 B m e staggered 0 0 0 v 
217 0 5.9945 1.67063 T 0.088 0.056 e e staggered 0 0 0 
217 0 5.98 1.676 D 0.024 0.028 e e staggered 0 0 0 
217 0.005 5.92 1.68 B m e staggered 0 0 0 v 
218 0 6.14648 1.57063 T 0.092 0.056 e e staggered 0 0 0 
218 0 6.17 1.576 D 0.024 0.028 e e staggered 0 0 0 
218 0.005 6.22 1.57 B m e staggered 0 0 0 v 
219 0 5.9945 1.57063 T 0.088 0.056 e e staggered 0 0 0 
219 0 5.98 1.581 D 0.024 0.028 e e staggered 0 0 0 
219 0.005 5.92 1.57063 B m e staggered 0 0 0 v 
220 0 6.14648 1.47063 T 0.092 0.056 e e staggered 0 0 0 
220 0 6.17 1.476 D 0.024 0.028 e e staggered 0 0 0 
220 0.005 6.22 1.465 B m e staggered 0 0 0 v 
221 0 5.9945 1.47063 T 0.088 0.056 e e staggered 0 0 0 
221 0 5.98 1.461 D 0.024 0.028 e e staggered 0 0 0 
221 0.005 5.92 1.46 B m e staggered 0 0 0 v 
222 0 0.805 1.62756 T 0.05 0.14 e e staggered 0 0 0 
222 0 0.85 1.684 D 0.028 0.024 e e staggered 0 0 0 
222 0.005 0.835 1.73 B m e staggered 0 0 0 v 
223 0 0.805 1.42244 T 0.05 0.14 e e staggered 0 0 0 
223 0 1.3085 0.613 T 0.028 0.024 e e staggered 0 0 0 
223 0 1.3085 0.658 T 0.028 0.024 e e staggered 0 0 0 
223 0 1.2157 0.6586 T 0.028 0.024 e e staggered 0 0 0 
223 0 1.3085 0.658 D 0.028 0.024 e e staggered 0 0 0 
223 0 1.2158 0.6587 D 0.028 0.024 e e staggered 0 0 0 
223 0 0.721 0.859 D 0.024 0.028 e e staggered 0 0 0 
223 0.005 0.74 1.3 B m e staggered 0 0 0 v 
223 0.005 0.785 0.8225 B m e staggered 0 0 0 v 
223 0.004 1.26 0.62 B m e staggered 0 0 0 v 
224 0 0.705 1.62756 T 0.05 0.14 e e staggered 0 0 0 
224 0 0.674 1.495 D 0.028 0.024 e e staggered 0 0 0 
224 0.005 0.606 1.57 B m e staggered 0 0 0 v 
225 0 0.76221 0.7085 T 0.014 0.062 e e staggered 0 0 0 
225 0 0.705 1.42244 T 0.05 0.14 e e staggered 0 0 0 
225 0 0.9575 0.7284 T 0.047 0.02 e e staggered 0 0 0 
225 0 1.3087 0.753 T 0.028 0.024 e e staggered 0 0 0 
225 0 1.3087 0.708 T 0.028 0.024 e e staggered 0 0 0 
225 0 1.1737 0.7086 T 0.028 0.024 e e staggered 0 0 0 
225 0 1.3087 0.708 D 0.028 0.024 e e staggered 0 0 0 
225 0.005 0.695 1.3 B m e staggered 0 0 0 v 
225 0.005 0.76321 0.783 B m e staggered 0 0 0 v 
225 0.004 1.26 0.67 B m e staggered 0 0 0 v 
226 0.0395 1.26067 2.64043 B e e staggered 0 0 0 
226 0 0.908 2.831 D 0.024 0.028 e e staggered 0 0 0 
227 0.0395 1.26067 1.04043 B e e staggered 0 0 0 
227 0 4.926 1.855 D 0.028 0.024 e e staggered 0 0 0 
227 0.005 4.9806 1.855 B m e staggered 0 0 0 v 
228 0.005 4.97 1.54 B e e staggered 0 0 0 
228 0.0395 2.77867 0.93443 B e e staggered 0 0 0 
228 0 4.926 1.63 T 0.028 0.024 e e staggered 0 0 0 
229 0.0395 2.65967 0.93443 B e e staggered 0 0 0 
229 0 4.926 1.975 T 0.028 0.024 e e staggered 0 0 0 
229 0 6.036 2.79 D 0.028 0.024 e e staggered 0 0 0 
229 0.005 5.07 1.885 B m e staggered 0 0 0 v 
229 0.005 6.095 2.545 B m e staggered 0 0 0 v 
229 0.004 5.33 0.995 B m e staggered 0 0 0 v 
229 0.004 3.49 0.825 B m e staggered 0 0 0 v 
230 0.0395 2.53967 0.93443 B e e staggered 0 0 0 
230 0 4.926 2.025 T 0.028 0.024 e e staggered 0 0 0 
230 0 4.926 2.025 D 0.028 0.024 e e staggered 0 0 0 
230 0 6.036 2.615 D 0.028 0.024 e e staggered 0 0 0 
230 0.005 3.54 0.825 B m e staggered 0 0 0 v 
230 0.005 5.07 1.925 B m e staggered 0 0 0 v 
230 0.005 6.04 2.545 B m e staggered 0 0 0 v 
230 0.004 5.33 0.95 B m e staggered 0 0 0 v 
231 0 2.76986 1.929 T 0.071 0.01 e e staggered 0 0 0 
231 0 3.168 2.11 T 0.028 0.024 e e staggered 0 0 0 
231 0 2.7965 1.945 D 0.028 0.024 e e staggered 0 0 0 
231 0.004 2.802 1.987 B m e staggered 0 0 0 v 
232 0 2.92734 1.929 T 0.071 0.01 e e staggered 0 0 0 
232 0 3.119 1.895 T 0.028 0.024 e e staggered 0 0 0 
233 0 2.76986 1.90932 T 0.071 0.01 e e staggered 0 0 0 
233 0 3.168 2.06 T 0.028 0.024 e e staggered 0 0 0 
233 0 2.8385 1.945 D 0.028 0.024 e e staggered 0 0 0 
233 0.004 2.834 1.987 B m e staggered 0 0 0 v 
234 0 2.92734 1.90932 T 0.071 0.01 e e staggered 0 0 0 
234 0 3.119 1.85 T 0.028 0.024 e e staggered 0 0 0 
235 0 2.76986 1.88963 T 0.071 0.01 e e staggered 0 0 0 
235 0 3.168 2.015 T 0.028 0.024 e e staggered 0 0 0 
235 0 2.795 1.88 D 0.024 0.028 e e staggered 0 0 0 
235 0.004 2.845 1.875 B m e staggered 0 0 0 v 
236 0 2.76986 1.86995 T 0.071 0.01 e e staggered 0 0 0 
236 0 3.168 1.965 T 0.028 0.024 e e staggered 0 0 0 
236 0 2.795 1.838 D 0.024 0.028 e e staggered 0 0 0 
236 0.004 2.845 1.843 B m e staggered 0 0 0 v 
237 0 2.76986 1.77152 T 0.071 0.01 e e staggered 0 0 0 
237 0 3.123 1.8 T 0.028 0.024 e e staggered 0 0 0 
238 0 2.76986 1.75184 T 0.071 0.01 e e staggered 0 0 0 
238 0 3.123 1.75 T 0.028 0.024 e e staggered 0 0 0 
239 0 2.92734 1.75184 T 0.071 0.01 e e staggered 0 0 0 
239 0 3.124 1.695 T 0.028 0.024 e e staggered 0 0 0 
239 0.005 3.065 1.695 B e e staggered 0 0 0 
239 0.005 2.98284 1.75184 B m e staggered 0 0 0 v 
240 0 4.91549 3.82953 T 0.088 0.04 e e staggered 0 0 0 
240 0 4.985 3.546 T 0.024 0.028 e e staggered 0 0 0 
240 0 4.985 3.546 D 0.024 0.028 e e staggered 0 0 0 
240 0.004 5.03 3.546 B m e staggered 0 0 0 v 
241 0.005 4.67 3.555 B e e staggered 0 0 0 
241 0 4.78656 3.82953 T 0.088 0.04 e e staggered 0 0 0 
241 0 4.785 3.546 T 0.024 0.028 e e staggered 0 0 0 
241 0 4.735 3.546 T 0.024 0.028 e e staggered 0 0 0 
241 0 4.736 3.551 D 0.028 0.024 e e staggered 0 0 0 
242 0 4.91549 3.75079 T 0.088 0.04 e e staggered 0 0 0 
242 0 4.935 3.546 T 0.024 0.028 e e staggered 0 0 0 
242 0 4.885 3.546 T 0.024 0.028 e e staggered 0 0 0 
242 0 4.935 3.546 D 0.024 0.028 e e staggered 0 0 0 
242 0.004 4.935 3.59 B m e staggered 0 0 0 v 
243 0 4.78656 3.75079 T 0.088 0.04 e e staggered 0 0 0 
243 0 4.835 3.546 T 0.024 0.028 e e staggered 0 0 0 
243 0.004 4.70462 3.69462 B m e staggered 0 0 0 v 
244 0 4.91549 3.67205 T 0.088 0.04 e e staggered 0 0 0 
244 0 4.885 3.546 D 0.024 0.028 e e staggered 0 0 0 
244 0.004 4.885 3.59 B m e staggered 0 0 0 v 
245 0 4.398 3.5315 T 0.039 0.055 e e staggered 0 0 0 
245 0.005 0.995 3.7 B e e staggered 0 0 0 
245 0 1.055 3.689 T 0.024 0.028 e e staggered 0 0 0 
245 0 4.34 3.496 T 0.024 0.028 e e staggered 0 0 0 
245 0 1.04 3.606 D 0.024 0.028 e e staggered 0 0 0 
245 0 0.995 3.606 D 0.024 0.028 e e staggered 0 0 0 
245 0 1.055 3.689 D 0.024 0.028 e e staggered 0 0 0 
245 0.005 4.285 3.46 B m e staggered 0 0 0 v 
246 0 4.2745 3.73898 T 0.062 0.014 e e staggered 0 0 0 
246 0 4.435 3.6185 T 0.039 0.055 e e staggered 0 0 0 
246 0 4.384 3.7 T 0.028 0.024 e e staggered 0 0 0 
246 0 4.384 3.745 T 0.028 0.024 e e staggered 0 0 0 
246 0.005 4.385 3.645 B m e staggered 0 0 0 v 
247 0 2.9665 2.18 D 0.055 0.039 e e staggered 0 0 0 
247 0 2.9715 2.278 D 0.055 0.039 e e staggered 0 0 0 
247 0 2.91 2.299 D 0.024 0.028 e e staggered 0 0 0 
247 0.015 2.925 2.2285 D m e staggered 0 0 0 v t 
248 0.00985 4.67902 1.80406 T e e staggered 0 0 0 
248 0 1.2157 0.7086 D 0.028 0.024 e e staggered 0 0 0 
248 0.005 1.26 0.72 B m e staggered 0 0 0 v 
248 0.004 4.6987 1.82374 B m e staggered 0 0 0 v 
249 0.00985 4.56091 1.8828 T e e staggered 0 0 0 
249 0 2.54 2.216 D 0.024 0.028 e e staggered 0 0 0 
249 0 2.54 2.264 D 0.024 0.028 e e staggered 0 0 0 
249 0 2.46559 2.193 D 0.013 0.038 e e staggered 0 0 0 
249 0.015 2.49499 2.04 D m e staggered 0 0 0 v t 
249 0.005 3.445 1.815 B m e staggered 0 0 0 v 
249 0.004 4.58059 1.90248 B m e staggered 0 0 0 v 
250 0 3.53614 1.88543 T 0.008 0.053 e e staggered 0 0 0 
250 0 3.554 1.78749 T 0.024 0.028 e e staggered 0 0 0 
250 0 6.3 1.96774 D 0.024 0.028 e e staggered 0 0 0 
250 0 6.255 1.96774 D 0.024 0.028 e e staggered 0 0 0 
250 0 2.44 2.193 D 0.013 0.038 e e staggered 0 0 0 
250 0.005 3.465 1.74 B m e staggered 0 0 0 v 
250 0.005 6.285 1.895 B m e staggered 0 0 0 v 
250 0.005 3.44 1.03 B m e staggered 0 0 0 v 
251 0 6.255 2.00974 D 0.024 0.028 e e staggered 0 0 0 
251 0 6.21 2.00974 D 0.024 0.028 e e staggered 0 0 0 
251 0.015 6.23 2.05375 D m e staggered 0 0 0 v t 
252 0 3.55189 1.88543 T 0.008 0.053 e e staggered 0 0 0 
252 0 3.604 1.78749 T 0.024 0.028 e e staggered 0 0 0 
252 0.004 3.584 1.827 B m e staggered 0 0 0 v 
253 0 3.50595 1.92336 T 0.037 0.008 e e staggered 0 0 0 
253 0 3.161 1.85 T 0.028 0.024 e e staggered 0 0 0 
253 0 3.533 1.93149 D 0.028 0.024 e e staggered 0 0 0 
253 0.004 3.2591 1.90299 B m e staggered 0 0 0 v 
253 0.004 3.45301 1.93099 B m e staggered 0 0 0 v 
254 0.00985 4.4428 1.84343 T e e staggered 0 0 0 
254 0 3.58207 1.90762 T 0.037 0.008 e e staggered 0 0 0 
254 0.0125 4.48217 1.84343 D e e staggered 0 0 0 
254 0 3.575 1.93149 D 0.028 0.024 e e staggered 0 0 0 
254 0.004 3.65101 1.91559 B m e staggered 0 0 0 v 
254 0.004 4.46248 1.86311 B m e staggered 0 0 0 v 
255 0 3.50595 1.90762 T 0.037 0.008 e e staggered 0 0 0 
255 0 3.161 1.895 T 0.028 0.024 e e staggered 0 0 0 
255 0 3.533 1.88649 D 0.028 0.024 e e staggered 0 0 0 
255 0.004 3.2271 1.90299 B m e staggered 0 0 0 v 
255 0.004 3.45301 1.89899 B m e staggered 0 0 0 v 
256 0.00985 4.40343 1.84343 T e e staggered 0 0 0 
256 0 3.58207 1.89187 T 0.037 0.008 e e staggered 0 0 0 
256 0.0125 4.4428 1.84343 D e e staggered 0 0 0 
256 0 3.575 1.88649 D 0.028 0.024 e e staggered 0 0 0 
256 0.004 3.65101 1.88359 B m e staggered 0 0 0 v 
256 0.004 4.42311 1.86311 B m e staggered 0 0 0 v 
257 0.00985 4.32469 1.8828 T e e staggered 0 0 0 
257 0 2.599 2.375 D 0.028 0.024 e e staggered 0 0 0 
257 0 2.551 2.375 D 0.028 0.024 e e staggered 0 0 0 
257 0.005 2.554 2.901 B m e staggered 0 0 0 v 
257 0.004 4.34437 1.90248 B m e staggered 0 0 0 v 
258 0 5.571 4.115 D 0.028 0.024 e e staggered 0 0 0 
258 0 5.571 4.07 D 0.028 0.024 e e staggered 0 0 0 
258 0.015 5.61731 4.085 D m e staggered 0 0 0 v t 
259 0.00985 4.36406 1.8828 T e e staggered 0 0 0 
259 0 5.031 3.455 D 0.028 0.024 e e staggered 0 0 0 
259 0 4.985 3.504 D 0.024 0.028 e e staggered 0 0 0 
259 0.005 4.97 3.41 B m e staggered 0 0 0 v 
259 0.004 4.38374 1.90248 B m e staggered 0 0 0 v 
260 0.00985 4.40343 2.07965 T e e staggered 0 0 0 
260 0 4.935 3.504 D 0.024 0.028 e e staggered 0 0 0 
260 0.005 4.81 3.41 B m e staggered 0 0 0 v 
260 0.004 4.42311 2.09933 B m e staggered 0 0 0 v 
261 0.00985 4.63965 1.84343 T e e staggered 0 0 0 
261 0.0125 4.67902 1.88281 D e e staggered 0 0 0 
261 0 4.885 3.504 D 0.024 0.028 e e staggered 0 0 0 
261 0.005 4.885 3.46 B m e staggered 0 0 0 v 
261 0.005 4.815 1.93 B m e staggered 0 0 0 v 
261 0.004 4.65933 1.86311 B m e staggered 0 0 0 v 
262 0.00985 4.63965 1.92217 T e e staggered 0 0 0 
262 0 4.785 3.504 T 0.024 0.028 e e staggered 0 0 0 
262 0.005 4.785 3.46 B m e staggered 0 0 0 v 
262 0.004 4.65933 1.94185 B m e staggered 0 0 0 v 
263 0.00985 4.60028 1.84343 T e e staggered 0 0 0 
263 0 4.835 3.504 T 0.024 0.028 e e staggered 0 0 0 
263 0.0125 4.60029 1.8828 D e e staggered 0 0 0 
263 0.005 4.83501 3.46 B m e staggered 0 0 0 v 
263 0.004 4.61996 1.86311 B m e staggered 0 0 0 v 
264 0.00985 4.56091 1.68595 T e e staggered 0 0 0 
264 0 0.53 2.626 T 0.024 0.028 e e staggered 0 0 0 
264 0.005 0.48232 2.6453 B m e staggered 0 0 0 v 
264 0.005 0.735 1.125 B m e staggered 0 0 0 v 
264 0.004 4.5806 1.70564 B m e staggered 0 0 0 v 
265 0 0.55708 2.49174 T 0.012 0.038 e e staggered 0 0 0 
265 0 0.53 2.584 T 0.024 0.028 e e staggered 0 0 0 
265 0 0.53 2.584 D 0.024 0.028 e e staggered 0 0 0 
265 0.005 0.552 2.535 B m e staggered 0 0 0 v 
266 0.00985 4.60028 1.68595 T e e staggered 0 0 0 
266 0 0.53 2.091 T 0.024 0.028 e e staggered 0 0 0 
266 0.005 0.54 2.135 B m e staggered 0 0 0 v 
266 0.005 0.67 1.09 B m e staggered 0 0 0 v 
266 0.004 4.61996 1.66627 B m e staggered 0 0 0 v 
267 0 0.55708 1.92087 T 0.012 0.038 e e staggered 0 0 0 
267 0 0.53 2.049 T 0.024 0.028 e e staggered 0 0 0 
267 0 0.53 2.049 D 0.024 0.028 e e staggered 0 0 0 
267 0.005 0.53 2.005 B m e staggered 0 0 0 v 
268 0 0.51772 1.21692 T 0.012 0.038 e e staggered 0 0 0 
268 0 0.5374 1.21692 T 0.012 0.038 e e staggered 0 0 0 
268 0 0.455 1.178 T 0.024 0.028 e e staggered 0 0 0 
268 0 0.455 1.1259 T 0.024 0.028 e e staggered 0 0 0 
268 0.005 0.5374 1.26 B m e staggered 0 0 0 v 
269 0 0.51772 0.64606 T 0.012 0.038 e e staggered 0 0 0 
269 0 0.5374 0.64606 T 0.012 0.038 e e staggered 0 0 0 
269 0 0.443 0.647 T 0.024 0.028 e e staggered 0 0 0 
269 0 0.53 0.655 D 0.024 0.028 e e staggered 0 0 0 
269 0.005 0.505 0.60228 B m e staggered 0 0 0 v 
270 0.00985 4.08847 1.80406 T e e staggered 0 0 0 
270 0 0.236 1.52698 T 0.024 0.028 e e staggered 0 0 0 
270 0.005 0.236 1.48798 B m e staggered 0 0 0 v 
270 0.005 0.985 1.59 B m e staggered 0 0 0 v 
270 0.004 4.06879 1.82374 B m e staggered 0 0 0 v 
271 0.00985 4.08847 1.84343 T e e staggered 0 0 0 
271 0 0.371 1.52698 T 0.024 0.028 e e staggered 0 0 0 
271 0.005 0.371 1.48798 B m e staggered 0 0 0 v 
271 0.005 0.985 1.655 B m e staggered 0 0 0 v 
271 0.004 4.06879 1.86311 B m e staggered 0 0 0 v 
272 0 0.51772 1.78779 T 0.012 0.038 e e staggered 0 0 0 
272 0 0.5374 1.78779 T 0.012 0.038 e e staggered 0 0 0 
272 0 0.455 1.686 T 0.024 0.028 e e staggered 0 0 0 
272 0 0.455 1.739 T 0.024 0.028 e e staggered 0 0 0 
272 0.005 0.535 1.835 B m e staggered 0 0 0 v 
273 0 0.51772 2.35866 T 0.012 0.038 e e staggered 0 0 0 
273 0 0.5374 2.35866 T 0.012 0.038 e e staggered 0 0 0 
273 0 0.452 2.326 T 0.024 0.028 e e staggered 0 0 0 
273 0 0.46452 2.275 T 0.024 0.028 e e staggered 0 0 0 
273 0.005 0.532 2.40187 B m e staggered 0 0 0 v 
274 0 1.15253 3.578 T 0.012 0.064 e e staggered 0 0 0 
274 0 1.155 3.689 T 0.024 0.028 e e staggered 0 0 0 
275 0 1.13284 3.578 T 0.012 0.064 e e staggered 0 0 0 
275 0 1.105 3.689 T 0.024 0.028 e e staggered 0 0 0 
276 0.005 5.6 4.01 B e e staggered 0 0 0 
276 0 5.55569 3.83456 T 0.013 0.044 e e staggered 0 0 0 
276 0 5.559 3.96 T 0.028 0.024 e e staggered 0 0 0 
276 0 5.559 3.915 T 0.028 0.024 e e staggered 0 0 0 
276 0.004 5.55569 3.88051 B m e staggered 0 0 0 v 
277 0 1.27064 3.12 T 0.012 0.064 e e staggered 0 0 0 
277 0 1.28 3.136 D 0.024 0.028 e e staggered 0 0 0 
277 0.005 1.26 3.18 B m e staggered 0 0 0 v 
278 0 1.352 3.26042 T 0.064 0.012 e e staggered 0 0 0 
278 0 1.339 3.235 D 0.028 0.024 e e staggered 0 0 0 
278 0 1.339 3.28 D 0.028 0.024 e e staggered 0 0 0 
278 0.005 1.295 3.28 B m e staggered 0 0 0 v 
279 0.00985 4.56091 1.76469 T e e staggered 0 0 0 
279 0 5.504 2.595 D 0.028 0.024 e e staggered 0 0 0 
279 0 5.504 2.64 D 0.028 0.024 e e staggered 0 0 0 
279 0 5.4525 2.6375 D 0.024 0.028 e e staggered 0 0 0 
279 0.004 5.4525 2.563 B m e staggered 0 0 0 v 
279 0.004 4.58059 1.78437 B m e staggered 0 0 0 v 
280 0 5.504 2.815 D 0.028 0.024 e e staggered 0 0 0 
280 0 4.926 1.81 D 0.028 0.024 e e staggered 0 0 0 
280 0 5.504 2.77 D 0.028 0.024 e e staggered 0 0 0 
280 0 5.452 2.771 D 0.024 0.028 e e staggered 0 0 0 
280 0.005 5.015 1.925 B m e staggered 0 0 0 v 
280 0.004 5.39977 2.75124 B m e staggered 0 0 0 v 
281 0.00985 4.48217 1.80406 T e e staggered 0 0 0 
281 0 5.496 2.87 D 0.028 0.024 e e staggered 0 0 0 
281 0 5.502 2.9225 D 0.028 0.024 e e staggered 0 0 0 
281 0 5.452 2.9225 D 0.024 0.028 e e staggered 0 0 0 
281 0.005 5.395 2.92 B m e staggered 0 0 0 v 
281 0.004 4.50185 1.82374 B m e staggered 0 0 0 v 
282 0.00985 4.4428 1.80406 T e e staggered 0 0 0 
282 0 5.504 3.065 D 0.028 0.024 e e staggered 0 0 0 
282 0 5.504 3.02 D 0.028 0.024 e e staggered 0 0 0 
282 0 5.452 3.019 D 0.024 0.028 e e staggered 0 0 0 
282 0.004 5.375 2.96607 B m e staggered 0 0 0 v 
282 0.004 4.46248 1.82374 B m e staggered 0 0 0 v 
283 0.005 5.76 2.465 B e e staggered 0 0 0 
283 0 3.793 3.092 T 0.028 0.024 e e staggered 0 0 0 
283 0 5.465 2.366 T 0.024 0.028 e e staggered 0 0 0 
283 0.005 3.755 3.092 B m e staggered 0 0 0 v 
283 0.004 4.2136 3.5997 B m e staggered 0 0 0 v 
284 0.005 4.831 2.728 B e e staggered 0 0 0 
284 0 3.968 2.725 T 0.028 0.024 e e staggered 0 0 0 
284 0 4.889 2.728 T 0.024 0.028 e e staggered 0 0 0 
285 0.005 5.765 0.98 B e e staggered 0 0 0 
285 0 5.315 2.811 T 0.024 0.028 e e staggered 0 0 0 
285 0 1.435 3.901 D 0.028 0.024 e e staggered 0 0 0 
285 0 5.775 0.796 D 0.024 0.028 e e staggered 0 0 0 
285 0 4.566 2.945 D 0.028 0.024 e e staggered 0 0 0 
285 0.005 4.25 3.81 B m e staggered 0 0 0 v 
285 0.005 4.608 2.942 B m e staggered 0 0 0 v 
285 0.005 5.31 2.855 B m e staggered 0 0 0 v 
285 0.004 1.385 3.875 B m e staggered 0 0 0 v 
286 0 4.41975 2.92521 T 0.033 0.012 e e staggered 0 0 0 
286 0 4.524 2.995 T 0.028 0.024 e e staggered 0 0 0 
286 0 4.366 2.975 D 0.028 0.024 e e staggered 0 0 0 
286 0.004 4.415 2.975 B m e staggered 0 0 0 v 
287 0 4.8855 0.8428 T 0.062 0.014 e e staggered 0 0 0 
287 0 0.676 1.599 D 0.028 0.024 e e staggered 0 0 0 
287 0.005 3.455 0.87 B m e staggered 0 0 0 v 
287 0.005 0.8825 1.7725 B m e staggered 0 0 0 v 
287 0.005 0.9225 0.9775 B m e staggered 0 0 0 v 
287 0.005 4.82 0.835 B m e staggered 0 0 0 v 
288 0 2.937 3.259 T 0.028 0.024 e e staggered 0 0 0 
288 0 3.0425 3.25102 T 0.062 0.014 e e staggered 0 0 0 
288 0 0.718 1.599 D 0.028 0.024 e e staggered 0 0 0 
288 0 0.808 1.594 D 0.028 0.024 e e staggered 0 0 0 
288 0 0.808 1.639 D 0.028 0.024 e e staggered 0 0 0 
288 0 0.808 1.684 D 0.028 0.024 e e staggered 0 0 0 
288 0.004 2.987 3.235 B m e staggered 0 0 0 v 
288 0.004 0.7595 1.642 B m e staggered 0 0 0 v 
289 0 4.8855 0.76602 T 0.062 0.014 e e staggered 0 0 0 
289 0 0.675 1.544 D 0.028 0.024 e e staggered 0 0 0 
289 0.005 3.405 0.87 B m e staggered 0 0 0 v 
289 0.005 4.78 0.78 B m e staggered 0 0 0 v 
289 0.005 0.965 0.98 B m e staggered 0 0 0 v 
289 0.005 0.91 1.815 B m e staggered 0 0 0 v 
290 0 2.938 3.332 T 0.028 0.024 e e staggered 0 0 0 
290 0 3.0425 3.27661 T 0.062 0.014 e e staggered 0 0 0 
290 0 0.808 1.549 D 0.028 0.024 e e staggered 0 0 0 
290 0 0.716 1.495 D 0.028 0.024 e e staggered 0 0 0 
290 0 0.804 1.5 D 0.028 0.024 e e staggered 0 0 0 
290 0 0.717 1.544 D 0.028 0.024 e e staggered 0 0 0 
290 0.004 2.987 3.27 B m e staggered 0 0 0 v 
290 0.004 0.761 1.544 B m e staggered 0 0 0 v 
291 0.005 3.37 3.44 B e e staggered 0 0 0 
291 0 3.2815 3.27661 T 0.062 0.014 e e staggered 0 0 0 
291 0 3.298 3.43 D 0.028 0.024 e e staggered 0 0 0 
291 0 3.298 3.385 D 0.028 0.024 e e staggered 0 0 0 
291 0 3.298 3.475 D 0.028 0.024 e e staggered 0 0 0 
291 0.004 3.36525 3.305 B m e staggered 0 0 0 v 
292 0 3.2815 3.22543 T 0.062 0.014 e e staggered 0 0 0 
292 0 3.298 3.205 D 0.028 0.024 e e staggered 0 0 0 
292 0 3.298 3.25 D 0.028 0.024 e e staggered 0 0 0 
292 0.004 3.36525 3.205 B m e staggered 0 0 0 v 
293 0.005 5.718 3.965 B e e staggered 0 0 0 
293 0 5.59271 3.81574 T 0.047 0.012 e e staggered 0 0 0 
293 0 5.72 3.907 T 0.028 0.024 e e staggered 0 0 0 
293 0 5.72 3.907 D 0.028 0.024 e e staggered 0 0 0 
294 0 3.2815 3.25102 T 0.062 0.014 e e staggered 0 0 0 
294 0 3.298 3.34 D 0.028 0.024 e e staggered 0 0 0 
294 0 3.298 3.295 D 0.028 0.024 e e staggered 0 0 0 
294 0.004 3.36525 3.255 B m e staggered 0 0 0 v 
295 0 3.0425 3.3022 T 0.062 0.014 e e staggered 0 0 0 
295 0 3.026 3.35 D 0.028 0.024 e e staggered 0 0 0 
295 0 3.026 3.305 D 0.028 0.024 e e staggered 0 0 0 
295 0.004 2.977 3.351 B m e staggered 0 0 0 v 
296 0.00985 4.60028 1.72532 T e e staggered 0 0 0 
296 0 0.53 1.486 T 0.024 0.028 e e staggered 0 0 0 
296 0.005 0.625 1.005 B m e staggered 0 0 0 v 
296 0.005 0.5413 1.525 B m e staggered 0 0 0 v 
296 0.004 4.61996 1.70564 B m e staggered 0 0 0 v 
297 0 0.55708 1.35 T 0.012 0.038 e e staggered 0 0 0 
297 0 0.53 1.444 T 0.024 0.028 e e staggered 0 0 0 
297 0 0.53 1.444 D 0.024 0.028 e e staggered 0 0 0 
297 0.005 0.55922 1.40543 B m e staggered 0 0 0 v 
298 0.00985 4.60028 1.76469 T e e staggered 0 0 0 
298 0 0.535 0.926 T 0.024 0.028 e e staggered 0 0 0 
298 0.005 4.175 0.75 B m e staggered 0 0 0 v 
298 0.005 4.6 0.76 B m e staggered 0 0 0 v 
298 0.005 0.905 1.05 B m e staggered 0 0 0 v 
298 0.004 0.51765 0.966 B m e staggered 0 0 0 v 
298 0.004 4.61996 1.78437 B m e staggered 0 0 0 v 
299 0 0.55708 0.77914 T 0.012 0.038 e e staggered 0 0 0 
299 0 0.535 0.884 T 0.024 0.028 e e staggered 0 0 0 
299 0 0.535 0.884 D 0.024 0.028 e e staggered 0 0 0 
299 0.005 0.57 0.835 B m e staggered 0 0 0 v 
300 0 0.81339 0.9475 T 0.014 0.062 e e staggered 0 0 0 
300 0 0.878 0.953 D 0.024 0.028 e e staggered 0 0 0 
300 0 1.351 0.753 D 0.028 0.024 e e staggered 0 0 0 
300 0.005 0.84 1.005 B m e staggered 0 0 0 v 
301 0 0.7878 0.9475 T 0.014 0.062 e e staggered 0 0 0 
301 0 0.833 0.953 D 0.024 0.028 e e staggered 0 0 0 
301 0 0.788 0.953 D 0.024 0.028 e e staggered 0 0 0 
301 0.005 0.79 1.005 B m e staggered 0 0 0 v 
302 0 0.76221 0.9475 T 0.014 0.062 e e staggered 0 0 0 
302 0 0.698 0.953 D 0.024 0.028 e e staggered 0 0 0 
302 0 0.743 0.953 D 0.024 0.028 e e staggered 0 0 0 
302 0.005 0.74 1.005 B m e staggered 0 0 0 v 
303 0.00985 4.20658 2.07965 T e e staggered 0 0 0 
303 0 3.731 2.71 T 0.028 0.024 e e staggered 0 0 0 
303 0 3.7324 2.6265 T 0.02 0.047 e e staggered 0 0 0 
303 0.005 3.765 2.69 B m e staggered 0 0 0 v 
303 0.004 4.1869 2.09933 B m e staggered 0 0 0 v 
304 0.00985 4.20658 2.15839 T e e staggered 0 0 0 
304 0 3.978 2.51 T 0.024 0.028 e e staggered 0 0 0 
304 0 5.98 1.739 D 0.024 0.028 e e staggered 0 0 0 
304 0 3.978 2.51 D 0.024 0.028 e e staggered 0 0 0 
304 0.005 3.978 2.468 B m e staggered 0 0 0 v 
304 0.005 5.13 2.105 B m e staggered 0 0 0 v 
304 0.005 5.92 1.73 B m e staggered 0 0 0 v 
305 0.00985 4.16721 2.15839 T e e staggered 0 0 0 
305 0 3.919 2.51 T 0.024 0.028 e e staggered 0 0 0 
305 0 5.98 1.634 D 0.024 0.028 e e staggered 0 0 0 
305 0 3.919 2.51 D 0.024 0.028 e e staggered 0 0 0 
305 0.005 3.919 2.468 B m e staggered 0 0 0 v 
305 0.005 5.115 2.065 B m e staggered 0 0 0 v 
305 0.005 5.92 1.63 B m e staggered 0 0 0 v 
306 0 1.6622 0.64 T 0.065 0.02 e e staggered 0 0 0 
306 0 1.3505 0.658 D 0.028 0.024 e e staggered 0 0 0 
306 0 0.85 1.594 D 0.028 0.024 e e staggered 0 0 0 
306 0.005 1.512 0.75191 B m e staggered 0 0 0 v 
306 0.005 0.955 1.455 B m e staggered 0 0 0 v 
307 0 1.8832 0.64 T 0.065 0.02 e e staggered 0 0 0 
307 0 0.846 1.5 D 0.028 0.024 e e staggered 0 0 0 
307 0 1.3507 0.708 D 0.028 0.024 e e staggered 0 0 0 
307 0.005 0.905 1.445 B m e staggered 0 0 0 v 
307 0.004 1.459 0.752 B m e staggered 0 0 0 v 
307 0.004 1.8091 0.6339 B m e staggered 0 0 0 v 
308 0 5.1245 0.74043 T 0.062 0.014 e e staggered 0 0 0 
308 0 1.3505 0.613 T 0.028 0.024 e e staggered 0 0 0 
308 0.005 3.545 0.6092 B m e staggered 0 0 0 v 
308 0.005 5.085 0.645 B m e staggered 0 0 0 v 
308 0.004 1.395 0.625 B m e staggered 0 0 0 v 
309 0 5.1245 0.8172 T 0.062 0.014 e e staggered 0 0 0 
309 0 1.3507 0.708 T 0.028 0.024 e e staggered 0 0 0 
309 0.005 3.495 0.61 B m e staggered 0 0 0 v 
309 0.005 5.04 0.645 B m e staggered 0 0 0 v 
309 0.004 1.485 0.625 B m e staggered 0 0 0 v 
310 0 3.912 2.88533 T 0.012 0.041 e e staggered 0 0 0 
310 0 3.858 2.725 T 0.028 0.024 e e staggered 0 0 0 
310 0 3.858 2.68 T 0.028 0.024 e e staggered 0 0 0 
310 0 3.858 2.775 T 0.028 0.024 e e staggered 0 0 0 
310 0.005 3.894 2.811 B m e staggered 0 0 0 v 
311 0 5.16767 2.707 T 0.041 0.012 e e staggered 0 0 0 
311 0 5.328 2.653 T 0.024 0.028 e e staggered 0 0 0 
311 0 5.278 2.653 T 0.024 0.028 e e staggered 0 0 0 
311 0 5.278 2.653 D 0.024 0.028 e e staggered 0 0 0 
311 0.004 5.224 2.707 B m e staggered 0 0 0 v 
312 0 4.4085 3.1432 T 0.062 0.014 e e staggered 0 0 0 
312 0 3.769 3.235 T 0.072 0.02 e e staggered 0 0 0 
312 0 3.786 3.235 D 0.028 0.024 e e staggered 0 0 0 
312 0.005 4.33 3.1432 B m e staggered 0 0 0 v 
312 0.005 3.83 3.235 B m e staggered 0 0 0 v 
313 0 4.1695 3.1688 T 0.062 0.014 e e staggered 0 0 0 
313 0 3.481 3.335 T 0.072 0.02 e e staggered 0 0 0 
313 0 3.464 3.325 D 0.028 0.024 e e staggered 0 0 0 
313 0.005 4.085 3.165 B m e staggered 0 0 0 v 
313 0.004 3.415 3.335 B m e staggered 0 0 0 v 
314 0.005 4.82 2.125 B e e staggered 0 0 0 
314 0.00985 4.36406 1.76469 T e e staggered 0 0 0 
314 0 4.884 2.07 T 0.028 0.024 e e staggered 0 0 0 
314 0 4.884 2.115 T 0.028 0.024 e e staggered 0 0 0 
314 0.004 4.38374 1.78437 B m e staggered 0 0 0 v 
315 0.00985 4.52154 1.60721 T e e staggered 0 0 0 
315 0 4.959 1.335 T 0.028 0.024 e e staggered 0 0 0 
315 0.004 4.9097 1.335 B m e staggered 0 0 0 v 
315 0.004 4.54122 1.58753 B m e staggered 0 0 0 v 
316 0.00985 4.52154 1.80406 T e e staggered 0 0 0 
316 0 4.884 1.81 D 0.028 0.024 e e staggered 0 0 0 
316 0.005 4.79246 1.78464 B m e staggered 0 0 0 v 
316 0.004 4.54122 1.82374 B m e staggered 0 0 0 v 
317 0.00985 4.08847 1.60721 T e e staggered 0 0 0 
317 0.005 3.746 1.782 B e e staggered 0 0 0 
317 0 3.746 1.72 D 0.028 0.024 e e staggered 0 0 0 
317 0.004 4.06879 1.58753 B m e staggered 0 0 0 v 
318 0 3.481 3.385 T 0.072 0.02 e e staggered 0 0 0 
318 0 3.464 3.415 D 0.028 0.024 e e staggered 0 0 0 
318 0 3.464 3.37 D 0.028 0.024 e e staggered 0 0 0 
318 0.004 3.415 3.385 B m e staggered 0 0 0 v 
319 0.00985 4.71839 1.80406 T e e staggered 0 0 0 
319 0 0.799 0.753 D 0.024 0.028 e e staggered 0 0 0 
319 0.005 0.842 0.75 B m e staggered 0 0 0 v 
319 0.004 4.73807 1.82374 B m e staggered 0 0 0 v 
320 0 5.914 1.125 T 0.028 0.024 e e staggered 0 0 0 
320 0 2.2628 3.245 T 0.024 0.028 e e staggered 0 0 0 
320 0 5.914 1.08 T 0.028 0.024 e e staggered 0 0 0 
320 0 3.2815 3.3022 T 0.062 0.014 e e staggered 0 0 0 
320 0 0.66 3.056 D 0.024 0.028 e e staggered 0 0 0 
320 0.005 2.225 3.245 B m e staggered 0 0 0 v 
320 0.005 4.025 3.08 B m e staggered 0 0 0 v 
320 0.005 4.595 2.62 B m e staggered 0 0 0 v 
320 0.005 0.62 3.07 B m e staggered 0 0 0 v 
320 0.005 5.865 1.125 B m e staggered 0 0 0 v 
321 0 3.769 3.285 T 0.072 0.02 e e staggered 0 0 0 
321 0 3.786 3.325 D 0.028 0.024 e e staggered 0 0 0 
321 0 3.786 3.28 D 0.028 0.024 e e staggered 0 0 0 
321 0.004 3.83 3.285 B m e staggered 0 0 0 v 
322 0 3.769 3.335 T 0.072 0.02 e e staggered 0 0 0 
322 0 3.786 3.37 D 0.028 0.024 e e staggered 0 0 0 
322 0 3.786 3.415 D 0.028 0.024 e e staggered 0 0 0 
322 0.004 3.83 3.335 B m e staggered 0 0 0 v 
323 0 3.481 3.285 T 0.072 0.02 e e staggered 0 0 0 
323 0 3.464 3.235 D 0.028 0.024 e e staggered 0 0 0 
323 0 3.464 3.28 D 0.028 0.024 e e staggered 0 0 0 
323 0.004 3.415 3.285 B m e staggered 0 0 0 v 
324 0 4.1695 3.09202 T 0.062 0.014 e e staggered 0 0 0 
324 0 3.506 3.415 D 0.028 0.024 e e staggered 0 0 0 
324 0.004 3.5825 3.4005 B m e staggered 0 0 0 v 
325 0 4.4085 3.06643 T 0.062 0.014 e e staggered 0 0 0 
325 0 3.744 3.325 D 0.028 0.024 e e staggered 0 0 0 
325 0.005 4.35143 3.06643 B m e staggered 0 0 0 v 
325 0.005 3.7 3.325 B m e staggered 0 0 0 v 
326 0 3.95441 3.4804 T 0.017 0.024 e e staggered 0 0 0 
326 0 3.87 3.466 T 0.024 0.028 e e staggered 0 0 0 
326 0 3.744 3.415 D 0.028 0.024 e e staggered 0 0 0 
326 0.004 3.83 3.466 B m e staggered 0 0 0 v 
327 0 4.14941 3.4824 T 0.017 0.024 e e staggered 0 0 0 
327 0 4.08 3.471 T 0.024 0.028 e e staggered 0 0 0 
327 0 3.506 3.235 D 0.028 0.024 e e staggered 0 0 0 
327 0.005 4.0661 3.5341 B m e staggered 0 0 0 v 
328 0.00985 4.28532 1.76469 T e e staggered 0 0 0 
328 0 4.35 2.419 D 0.024 0.028 e e staggered 0 0 0 
328 0.005 4.365 2.375 B m e staggered 0 0 0 v 
328 0.004 4.26564 1.78437 B m e staggered 0 0 0 v 
329 0 4.1695 3.21998 T 0.062 0.014 e e staggered 0 0 0 
329 0 4.35 2.461 D 0.024 0.028 e e staggered 0 0 0 
329 0.005 4.35 2.505 B m e staggered 0 0 0 v 
329 0.005 4.085 3.21998 B m e staggered 0 0 0 v 
330 0.005 5.3 4.065 B e e staggered 0 0 0 
330 0.00985 4.12784 1.72532 T e e staggered 0 0 0 
330 0 5.323 4.15901 D 0.024 0.028 e e staggered 0 0 0 
330 0 5.273 4.15901 D 0.024 0.028 e e staggered 0 0 0 
330 0.004 4.10816 1.70564 B m e staggered 0 0 0 v 
331 0 2.1478 3.2655 T 0.018 0.06 e e staggered 0 0 0 
331 0 6.0845 1.0578 T 0.06 0.018 e e staggered 0 0 0 
331 0 5.956 1.025 T 0.028 0.024 e e staggered 0 0 0 
331 0 3.2815 3.3278 T 0.062 0.014 e e staggered 0 0 0 
331 0 0.5505 3.0028 D 0.06 0.018 e e staggered 0 0 0 
331 0.005 2.265 3.34 B m e staggered 0 0 0 v 
331 0.005 4.02 3.03 B m e staggered 0 0 0 v 
331 0.005 4.57 2.585 B m e staggered 0 0 0 v 
331 0.005 0.645 2.9675 B m e staggered 0 0 0 v 
331 0.005 5.865 1.07 B m e staggered 0 0 0 v 
332 0.00985 4.52154 1.72532 T e e staggered 0 0 0 
332 0 4.884 1.72 T 0.028 0.024 e e staggered 0 0 0 
332 0 4.884 1.765 T 0.028 0.024 e e staggered 0 0 0 
332 0.005 4.81 1.725 B m e staggered 0 0 0 v 
333 0.00985 4.36406 2.00091 T e e staggered 0 0 0 
333 0 4.44 2.419 T 0.024 0.028 e e staggered 0 0 0 
333 0 4.395 2.419 T 0.024 0.028 e e staggered 0 0 0 
333 0.005 4.365 2.33 B m e staggered 0 0 0 v 
333 0.004 4.38374 2.02059 B m e staggered 0 0 0 v 
334 0.00985 4.36406 2.04028 T e e staggered 0 0 0 
334 0 4.53 2.419 D 0.024 0.028 e e staggered 0 0 0 
334 0 4.485 2.419 D 0.024 0.028 e e staggered 0 0 0 
334 0.005 4.485 2.375 B m e staggered 0 0 0 v 
334 0.004 4.38374 2.05996 B m e staggered 0 0 0 v 
335 0.00985 4.52154 1.68595 T e e staggered 0 0 0 
335 0 4.884 1.675 D 0.028 0.024 e e staggered 0 0 0 
335 0 4.884 1.63 D 0.028 0.024 e e staggered 0 0 0 
335 0.005 4.84 1.66 B m e staggered 0 0 0 v 
335 0.004 4.54122 1.66627 B m e staggered 0 0 0 v 
336 0.00985 4.36406 2.07965 T e e staggered 0 0 0 
336 0 4.395 2.419 D 0.024 0.028 e e staggered 0 0 0 
336 0 4.44 2.419 D 0.024 0.028 e e staggered 0 0 0 
336 0.015 4.36749 2.25 D m e staggered 0 0 0 v t 
336 0.004 4.38374 2.09933 B m e staggered 0 0 0 v 
337 0.00985 4.52154 1.64658 T e e staggered 0 0 0 
337 0 4.959 1.43 T 0.028 0.024 e e staggered 0 0 0 
337 0 4.959 1.385 T 0.028 0.024 e e staggered 0 0 0 
337 0.004 4.9097 1.385 B m e staggered 0 0 0 v 
337 0.004 4.54122 1.6269 B m e staggered 0 0 0 v 
338 0.00985 4.52154 2.15839 T e e staggered 0 0 0 
338 0 4.575 2.419 D 0.024 0.028 e e staggered 0 0 0 
338 0 4.62 2.419 D 0.024 0.028 e e staggered 0 0 0 
338 0.004 4.54122 2.17807 B m e staggered 0 0 0 v 
339 0 5.56533 0.679 T 0.041 0.012 e e staggered 0 0 0 
339 0 5.446 0.69 T 0.028 0.024 e e staggered 0 0 0 
339 0 5.446 0.69 D 0.028 0.024 e e staggered 0 0 0 
339 0 5.557 0.705 D 0.024 0.028 e e staggered 0 0 0 
339 0.004 5.495 0.694 B m e staggered 0 0 0 v 
340 0.00985 4.40343 2.15839 T e e staggered 0 0 0 
340 0 4.485 2.419 T 0.024 0.028 e e staggered 0 0 0 
340 0.005 4.435 2.365 B m e staggered 0 0 0 v 
341 0 4.1695 3.1432 T 0.062 0.014 e e staggered 0 0 0 
341 0 4.485 2.461 T 0.024 0.028 e e staggered 0 0 0 
341 0.005 4.485 2.5 B m e staggered 0 0 0 v 
341 0.005 4.29442 3.10075 B m e staggered 0 0 0 v 
342 0.005 4.205 0.82 B e e staggered 0 0 0 
342 0 4.314 0.82366 T 0.025 0.035 e e staggered 0 0 0 
342 0 4.205 0.879 T 0.024 0.028 e e staggered 0 0 0 
343 0 3.88 0.75217 T 0.055 0.039 e e staggered 0 0 0 
343 0 3.77 0.874 T 0.024 0.028 e e staggered 0 0 0 
343 0.005 3.705 0.84 B e e staggered 0 0 0 
343 0.005 3.82286 0.86214 B m e staggered 0 0 0 v 
344 0.00985 4.4428 2.15839 T e e staggered 0 0 0 
344 0 4.535 2.324 T 0.024 0.028 e e staggered 0 0 0 
344 0.005 4.49 2.325 B m e staggered 0 0 0 v 
345 0 4.4085 3.11761 T 0.062 0.014 e e staggered 0 0 0 
345 0 4.535 2.366 T 0.024 0.028 e e staggered 0 0 0 
345 0 4.575 2.419 T 0.024 0.028 e e staggered 0 0 0 
345 0.005 4.575 2.374 B m e staggered 0 0 0 v 
345 0.005 4.485 3.115 B m e staggered 0 0 0 v 
346 0.005 3.745 4.185 B e e staggered 0 0 0 
346 0 3.594 4.197 D 0.028 0.024 e e staggered 0 0 0 
346 0 5.51 2.366 D 0.024 0.028 e e staggered 0 0 0 
346 0.005 5.9065 2.4568 B m e staggered 0 0 0 v 
347 0 5.62913 2.21996 T 0.02 0.024 e e staggered 0 0 0 
347 0 5.729 2.245 T 0.028 0.024 e e staggered 0 0 0 
347 0.005 5.69943 2.233 B m e staggered 0 0 0 v 
348 0 1.8832 0.59 T 0.065 0.02 e e staggered 0 0 0 
348 0 2.0477 0.59 T 0.024 0.028 e e staggered 0 0 0 
348 0 1.9977 0.59 T 0.024 0.028 e e staggered 0 0 0 
348 0.004 1.95 0.5455 B m e staggered 0 0 0 v 
349 0 5.51004 2.1924 T 0.024 0.012 e e staggered 0 0 0 
349 0 5.51 2.171 D 0.024 0.028 e e staggered 0 0 0 
349 0.005 5.483 2.226 B m e staggered 0 0 0 v 
350 0 5.811 4.075 D 0.028 0.024 e e staggered 0 0 0 
350 0 5.811 4.12 D 0.028 0.024 e e staggered 0 0 0 
350 0.015 5.855 4.095 D m e staggered 0 0 0 v t 
351 0.00985 4.71839 2.00091 T e e staggered 0 0 0 
351 0 4.884 1.975 T 0.028 0.024 e e staggered 0 0 0 
351 0 4.884 1.975 D 0.028 0.024 e e staggered 0 0 0 
351 0.005 4.83871 1.98241 B m e staggered 0 0 0 v 
352 0.00985 4.32469 1.92217 T e e staggered 0 0 0 
352 0 3.554 1.74549 T 0.024 0.028 e e staggered 0 0 0 
352 0.004 3.523 1.75 B m e staggered 0 0 0 v 
352 0.004 3.18 2.685 B m e staggered 0 0 0 v 
352 0.004 4.34437 1.94185 B m e staggered 0 0 0 v 
353 0 2.6526 2.1935 D 0.02 0.047 e e staggered 0 0 0 
353 0 2.641 2.375 D 0.028 0.024 e e staggered 0 0 0 
353 0.015 2.645 2.14 D m e staggered 0 0 0 v t 
354 0.00985 4.08847 1.92217 T e e staggered 0 0 0 
354 0 0.281 1.52698 T 0.024 0.028 e e staggered 0 0 0 
354 0.005 0.281 1.48798 B m e staggered 0 0 0 v 
354 0.005 0.92 1.73 B m e staggered 0 0 0 v 
354 0.004 4.06879 1.94185 B m e staggered 0 0 0 v 
355 0.00985 3.97035 1.84343 T e e staggered 0 0 0 
355 0 0.821 1.1 T 0.028 0.024 e e staggered 0 0 0 
355 0.005 0.935 1.25 B m e staggered 0 0 0 v 
355 0.004 3.95067 1.86311 B m e staggered 0 0 0 v 
356 0.00985 3.97035 1.8828 T e e staggered 0 0 0 
356 0 0.821 1.25 T 0.028 0.024 e e staggered 0 0 0 
356 0.005 0.87 1.255 B m e staggered 0 0 0 v 
356 0.004 3.95067 1.90248 B m e staggered 0 0 0 v 
357 0.00985 4.60028 1.33161 T e e staggered 0 0 0 
357 0 3.165 1.8 T 0.028 0.024 e e staggered 0 0 0 
357 0 4.53 1.181 T 0.024 0.028 e e staggered 0 0 0 
357 0.0125 4.60027 1.29224 D e e staggered 0 0 0 
357 0 4.53 1.181 D 0.024 0.028 e e staggered 0 0 0 
357 0.004 4.5413 1.22167 B m e staggered 0 0 0 v 
357 0.004 3.375 1.194 B m e staggered 0 0 0 v 
357 0.004 4.61996 1.31193 B m e staggered 0 0 0 v 
358 0.00985 4.63965 1.33161 T e e staggered 0 0 0 
358 0 3.165 1.75 T 0.028 0.024 e e staggered 0 0 0 
358 0 4.585 1.181 T 0.024 0.028 e e staggered 0 0 0 
358 0.0125 4.63965 1.29224 D e e staggered 0 0 0 
358 0 4.585 1.181 D 0.024 0.028 e e staggered 0 0 0 
358 0.004 4.5733 1.22167 B m e staggered 0 0 0 v 
358 0.004 3.375 1.162 B m e staggered 0 0 0 v 
358 0.004 4.65933 1.31193 B m e staggered 0 0 0 v 
359 0.00985 4.71839 1.41035 T e e staggered 0 0 0 
359 0 3.21 2.015 T 0.028 0.024 e e staggered 0 0 0 
359 0 3.259 2.011 T 0.024 0.028 e e staggered 0 0 0 
359 0.004 3.44999 1.085 B m e staggered 0 0 0 v 
359 0.004 4.73807 1.39067 B m e staggered 0 0 0 v 
360 0.00985 4.71839 1.37098 T e e staggered 0 0 0 
360 0 3.259 1.969 T 0.024 0.028 e e staggered 0 0 0 
360 0 3.21 1.965 T 0.028 0.024 e e staggered 0 0 0 
360 0.004 3.41799 1.085 B m e staggered 0 0 0 v 
360 0.004 4.73807 1.3513 B m e staggered 0 0 0 v 
361 0.00985 4.67902 1.4891 T e e staggered 0 0 0 
361 0 3.21 2.11 T 0.028 0.024 e e staggered 0 0 0 
361 0 3.259 2.106 T 0.024 0.028 e e staggered 0 0 0 
361 0.004 3.54664 1.04707 B m e staggered 0 0 0 v 
361 0.004 4.6987 1.46942 B m e staggered 0 0 0 v 
362 0.00985 4.71839 1.4891 T e e staggered 0 0 0 
362 0 3.259 2.064 T 0.024 0.028 e e staggered 0 0 0 
362 0 3.21 2.06 T 0.028 0.024 e e staggered 0 0 0 
362 0.004 3.51464 1.04707 B m e staggered 0 0 0 v 
362 0.004 4.73807 1.46942 B m e staggered 0 0 0 v 
363 0 0.8338 2.4275 T 0.018 0.06 e e staggered 0 0 0 
363 0 3.0425 3.40457 T 0.062 0.014 e e staggered 0 0 0 
363 0 0.85 2.444 D 0.024 0.028 e e staggered 0 0 0 
363 0 0.805 2.444 D 0.024 0.028 e e staggered 0 0 0 
363 0.005 3.28 3.065 B m e staggered 0 0 0 v 
363 0.004 0.846 2.489 B m e staggered 0 0 0 v 
364 0 0.8082 2.4275 T 0.018 0.06 e e staggered 0 0 0 
364 0 3.0425 3.37898 T 0.062 0.014 e e staggered 0 0 0 
364 0 0.715 2.444 D 0.024 0.028 e e staggered 0 0 0 
364 0 0.76 2.444 D 0.024 0.028 e e staggered 0 0 0 
364 0.005 3.325 3.065 B m e staggered 0 0 0 v 
364 0.004 0.796 2.489 B m e staggered 0 0 0 v 
365 0.00985 4.16721 2.07965 T e e staggered 0 0 0 
365 0 3.86 2.51 T 0.024 0.028 e e staggered 0 0 0 
365 0 3.86 2.51 D 0.024 0.028 e e staggered 0 0 0 
365 0 5.98 1.539 D 0.024 0.028 e e staggered 0 0 0 
365 0.005 3.86 2.468 B m e staggered 0 0 0 v 
365 0.005 5.135 2.155 B m e staggered 0 0 0 v 
365 0.005 5.92 1.515 B m e staggered 0 0 0 v 
365 0.004 4.14753 2.09933 B m e staggered 0 0 0 v 
366 0.00985 4.12784 2.07965 T e e staggered 0 0 0 
366 0 3.801 2.51 T 0.024 0.028 e e staggered 0 0 0 
366 0 3.801 2.51 D 0.024 0.028 e e staggered 0 0 0 
366 0 5.98 1.419 D 0.024 0.028 e e staggered 0 0 0 
366 0.005 3.801 2.468 B m e staggered 0 0 0 v 
366 0.005 5.09 2.155 B m e staggered 0 0 0 v 
366 0.005 5.92 1.41 B m e staggered 0 0 0 v 
366 0.004 4.10816 2.09933 B m e staggered 0 0 0 v 
367 0.00985 4.71839 1.68595 T e e staggered 0 0 0 
367 0 3.166 1.695 T 0.028 0.024 e e staggered 0 0 0 
367 0 3.166 1.645 T 0.028 0.024 e e staggered 0 0 0 
367 0.005 4.775 1.705 B m e staggered 0 0 0 v 
367 0.005 3.205 1.7 B m e staggered 0 0 0 v 
368 0.00985 4.67902 1.64658 T e e staggered 0 0 0 
368 0 4.884 1.63 T 0.028 0.024 e e staggered 0 0 0 
368 0 4.884 1.675 T 0.028 0.024 e e staggered 0 0 0 
368 0.004 4.75 1.63 B m e staggered 0 0 0 v 
369 0.00985 4.28532 1.84343 T e e staggered 0 0 0 
369 0 3.159 2.254 T 0.028 0.024 e e staggered 0 0 0 
369 0 3.159 2.209 T 0.028 0.024 e e staggered 0 0 0 
369 0.005 3.12 2.69 B m e staggered 0 0 0 v 
369 0.005 3.125 2.254 B m e staggered 0 0 0 v 
369 0.004 4.26564 1.86311 B m e staggered 0 0 0 v 
370 0 1.58104 4.02013 T 0.024 0.02 e e staggered 0 0 0 
370 0 1.556 4.12 T 0.024 0.028 e e staggered 0 0 0 
370 0.005 1.517 4.113 B m e staggered 0 0 0 v 
371 0 3.38016 2.22296 T 0.01 0.023 e e staggered 0 0 0 
371 0 3.201 2.164 T 0.028 0.024 e e staggered 0 0 0 
371 0 3.296 2.165 T 0.028 0.024 e e staggered 0 0 0 
371 0.005 3.3255 2.1355 B m e staggered 0 0 0 v 
372 0.005 3.235 2.63 B e e staggered 0 0 0 
372 0 3.32848 2.30416 T 0.027 0.01 e e staggered 0 0 0 
372 0 3.201 2.389 T 0.028 0.024 e e staggered 0 0 0 
372 0 3.201 2.299 T 0.028 0.024 e e staggered 0 0 0 
372 0 3.201 2.344 T 0.028 0.024 e e staggered 0 0 0 
372 0.004 3.275 2.32 B m e staggered 0 0 0 v 
373 0.00985 4.24595 2.11902 T e e staggered 0 0 0 
373 0 4.037 2.51 T 0.024 0.028 e e staggered 0 0 0 
373 0 6.155 1.811 D 0.024 0.028 e e staggered 0 0 0 
373 0 4.037 2.51 D 0.024 0.028 e e staggered 0 0 0 
373 0.005 4.037 2.468 B m e staggered 0 0 0 v 
373 0.005 4.925 2.26 B m e staggered 0 0 0 v 
373 0.005 6.22 1.815 B m e staggered 0 0 0 v 
374 0.005 5.955 2.39 B e e staggered 0 0 0 
374 0 5.99984 2.14382 T 0.012 0.041 e e staggered 0 0 0 
374 0 5.94153 2.33 T 0.028 0.024 e e staggered 0 0 0 
374 0 5.94153 2.28402 T 0.028 0.024 e e staggered 0 0 0 
374 0 5.94153 2.239 T 0.028 0.024 e e staggered 0 0 0 
374 0.004 5.94153 2.205 B m e staggered 0 0 0 v 
375 0.00985 4.16721 2.04028 T e e staggered 0 0 0 
375 0 5.89953 2.33 T 0.028 0.024 e e staggered 0 0 0 
375 0.005 5.83 2.97 B m e staggered 0 0 0 v 
375 0.004 4.14753 2.05996 B m e staggered 0 0 0 v 
375 0.004 5.89953 2.366 B m e staggered 0 0 0 v 
376 0.005 5.87 1.84 B e e staggered 0 0 0 
376 0 5.99984 2.04418 T 0.012 0.041 e e staggered 0 0 0 
376 0 6.01902 1.95065 T 0.024 0.028 e e staggered 0 0 0 
376 0.004 6.01902 2.001 B m e staggered 0 0 0 v 
377 0.00985 4.20658 2.04028 T e e staggered 0 0 0 
377 0 6.01902 1.90865 T 0.024 0.028 e e staggered 0 0 0 
377 0 6.01902 1.90865 D 0.024 0.028 e e staggered 0 0 0 
377 0.005 5.155 2.01 B m e staggered 0 0 0 v 
377 0.005 6.025 1.83 B m e staggered 0 0 0 v 
377 0.004 4.1869 2.05996 B m e staggered 0 0 0 v 
378 0 3.36047 2.40504 T 0.01 0.023 e e staggered 0 0 0 
378 0 3.285 2.511 T 0.024 0.028 e e staggered 0 0 0 
378 0.004 3.278 2.468 B m e staggered 0 0 0 v 
379 0.005 3.375 2.65 B e e staggered 0 0 0 
379 0 3.38016 2.40504 T 0.01 0.023 e e staggered 0 0 0 
379 0 3.335 2.511 T 0.024 0.028 e e staggered 0 0 0 
379 0 3.335 2.511 D 0.024 0.028 e e staggered 0 0 0 
379 0.004 3.326 2.466 B m e staggered 0 0 0 v 
380 0 3.32848 2.40258 T 0.027 0.01 e e staggered 0 0 0 
380 0 3.201 2.569 T 0.028 0.024 e e staggered 0 0 0 
380 0.004 3.243 2.547 B m e staggered 0 0 0 v 
381 0 3.32848 2.32384 T 0.027 0.01 e e staggered 0 0 0 
381 0 3.201 2.434 T 0.028 0.024 e e staggered 0 0 0 
381 0 3.201 2.479 T 0.028 0.024 e e staggered 0 0 0 
381 0.004 3.24 2.36 B m e staggered 0 0 0 v 
382 0.00985 4.24595 2.15839 T e e staggered 0 0 0 
382 0 4.093 2.51 T 0.024 0.028 e e staggered 0 0 0 
382 0 4.093 2.51 D 0.024 0.028 e e staggered 0 0 0 
382 0 6.17 1.634 D 0.024 0.028 e e staggered 0 0 0 
382 0.005 4.093 2.468 B m e staggered 0 0 0 v 
382 0.005 4.975 2.26 B m e staggered 0 0 0 v 
382 0.005 6.22 1.62 B m e staggered 0 0 0 v 
383 0 1.6086 3.90104 T 0.012 0.024 e e staggered 0 0 0 
383 0 1.624 3.885 D 0.028 0.024 e e staggered 0 0 0 
383 0.005 1.579 3.874 B m e staggered 0 0 0 v 
384 0 4.396 4.065 T 0.028 0.024 e e staggered 0 0 0 
384 0 1.3505 0.658 T 0.028 0.024 e e staggered 0 0 0 
384 0 2.895 3.259 T 0.028 0.024 e e staggered 0 0 0 
384 0.005 0.915 1.4 B m e staggered 0 0 0 v 
384 0.005 4.5 4.115 B m e staggered 0 0 0 v 
384 0.004 1.315 2.905 B m e staggered 0 0 0 v 
384 0.004 2.932 3.295 B m e staggered 0 0 0 v 
384 0.004 1.42 0.69535 B m e staggered 0 0 0 v 
385 0 4.396 4.115 T 0.028 0.024 e e staggered 0 0 0 
385 0 1.3507 0.753 T 0.028 0.024 e e staggered 0 0 0 
385 0 2.896 3.332 T 0.028 0.024 e e staggered 0 0 0 
385 0.005 0.965 1.4 B m e staggered 0 0 0 v 
385 0.005 4.5 4.165 B m e staggered 0 0 0 v 
385 0.004 1.36 2.905 B m e staggered 0 0 0 v 
385 0.004 2.896 3.301 B m e staggered 0 0 0 v 
385 0.004 1.4207 0.779 B m e staggered 0 0 0 v 
386 0 0.8594 2.4275 T 0.018 0.06 e e staggered 0 0 0 
386 0 0.896 2.444 D 0.024 0.028 e e staggered 0 0 0 
386 0.004 0.896 2.489 B m e staggered 0 0 0 v 
387 0 0.8082 2.2465 T 0.018 0.06 e e staggered 0 0 0 
387 0 0.80648 2.831 T 0.024 0.028 e e staggered 0 0 0 
387 0 0.756 2.79 T 0.028 0.024 e e staggered 0 0 0 
387 0 0.76 2.402 D 0.024 0.028 e e staggered 0 0 0 
387 0.004 0.755 2.825 B m e staggered 0 0 0 v 
387 0.004 0.795 2.345 B m e staggered 0 0 0 v 
388 0 0.8338 2.2465 T 0.018 0.06 e e staggered 0 0 0 
388 0 0.64248 2.709 T 0.028 0.024 e e staggered 0 0 0 
388 0 0.64248 2.664 T 0.028 0.024 e e staggered 0 0 0 
388 0 0.805 2.402 D 0.024 0.028 e e staggered 0 0 0 
388 0.004 0.638 2.74 B m e staggered 0 0 0 v 
388 0.004 0.825 2.305 B m e staggered 0 0 0 v 
389 0 4.2391 4.03137 T 0.049 0.012 e e staggered 0 0 0 
389 0 4.354 4.065 T 0.028 0.024 e e staggered 0 0 0 
389 0 4.266 4.065 D 0.028 0.024 e e staggered 0 0 0 
389 0 4.354 4.065 D 0.028 0.024 e e staggered 0 0 0 
389 0.005 4.31 4.065 B m e staggered 0 0 0 v 
390 0 4.2406 4.05106 T 0.046 0.012 e e staggered 0 0 0 
390 0 4.354 4.115 T 0.028 0.024 e e staggered 0 0 0 
390 0 4.266 4.115 D 0.028 0.024 e e staggered 0 0 0 
390 0 4.354 4.115 D 0.028 0.024 e e staggered 0 0 0 
390 0.005 4.31 4.115 B m e staggered 0 0 0 v 
391 0.00985 4.63965 2.00091 T e e staggered 0 0 0 
391 0 4.396 3.865 D 0.028 0.024 e e staggered 0 0 0 
391 0.005 4.33 3.535 B m e staggered 0 0 0 v 
391 0.004 4.65933 2.02059 B m e staggered 0 0 0 v 
392 0.00985 4.60028 2.04028 T e e staggered 0 0 0 
392 0 4.396 4.065 D 0.028 0.024 e e staggered 0 0 0 
392 0.004 4.395 3.415 B m e staggered 0 0 0 v 
392 0.004 4.61996 2.05996 B m e staggered 0 0 0 v 
392 0.004 4.44 4.065 B m e staggered 0 0 0 v 
393 0.00985 4.60028 2.07965 T e e staggered 0 0 0 
393 0 4.396 4.115 D 0.028 0.024 e e staggered 0 0 0 
393 0.004 4.425 3.36089 B m e staggered 0 0 0 v 
393 0.004 4.61996 2.09933 B m e staggered 0 0 0 v 
393 0.004 4.44 4.115 B m e staggered 0 0 0 v 
394 0 4.2391 4.01169 T 0.049 0.012 e e staggered 0 0 0 
394 0 4.354 4.015 T 0.028 0.024 e e staggered 0 0 0 
394 0.004 4.31169 4.01169 B m e staggered 0 0 0 v 
395 0 4.2391 3.95263 T 0.049 0.012 e e staggered 0 0 0 
395 0 4.354 3.915 T 0.028 0.024 e e staggered 0 0 0 
395 0.004 4.319 3.922 B m e staggered 0 0 0 v 
396 0.00985 4.32469 2.11902 T e e staggered 0 0 0 
396 0 4.209 2.51 T 0.024 0.028 e e staggered 0 0 0 
396 0 4.209 2.51 D 0.024 0.028 e e staggered 0 0 0 
396 0 6.17 1.534 D 0.024 0.028 e e staggered 0 0 0 
396 0.005 4.209 2.468 B m e staggered 0 0 0 v 
396 0.005 4.685 2.7 B m e staggered 0 0 0 v 
396 0.005 6.22 1.516 B m e staggered 0 0 0 v 
396 0.004 4.34437 2.1387 B m e staggered 0 0 0 v 
397 0.00985 4.28532 2.11902 T e e staggered 0 0 0 
397 0 4.15 2.51 T 0.024 0.028 e e staggered 0 0 0 
397 0 4.15 2.51 D 0.024 0.028 e e staggered 0 0 0 
397 0 6.17 1.434 D 0.024 0.028 e e staggered 0 0 0 
397 0.005 4.15 2.468 B m e staggered 0 0 0 v 
397 0.005 4.615 2.68409 B m e staggered 0 0 0 v 
397 0.005 6.22 1.415 B m e staggered 0 0 0 v 
398 0 3.36047 2.22296 T 0.01 0.023 e e staggered 0 0 0 
398 0 3.44 2.906 D 0.024 0.028 e e staggered 0 0 0 
398 0.005 3.35153 2.17875 B m e staggered 0 0 0 v 
398 0.004 3.44 2.95 B m e staggered 0 0 0 v 
399 0.005 3.32 3.015 B e e staggered 0 0 0 
399 0 3.485 2.864 D 0.024 0.028 e e staggered 0 0 0 
399 0 3.44 2.864 D 0.024 0.028 e e staggered 0 0 0 
400 0.005 0.62 1.995 B e e staggered 0 0 0 
400 0 0.57676 1.92087 T 0.012 0.038 e e staggered 0 0 0 
400 0.00985 4.32469 1.80406 T e e staggered 0 0 0 
400 0 0.575 2.049 T 0.024 0.028 e e staggered 0 0 0 
400 0.005 0.75 1.417 B m e staggered 0 0 0 v 
400 0.004 4.34437 1.82374 B m e staggered 0 0 0 v 
401 0 0.5505 3.0284 D 0.06 0.018 e e staggered 0 0 0 
401 0 0.66 3.014 D 0.024 0.028 e e staggered 0 0 0 
401 0.015 0.618 3.025 D m e staggered 0 0 0 v t 
402 0 0.3695 2.9516 D 0.06 0.018 e e staggered 0 0 0 
402 0 0.29 2.871 D 0.024 0.028 e e staggered 0 0 0 
402 0 0.335 2.871 D 0.024 0.028 e e staggered 0 0 0 
402 0.005 0.29 2.915 B m e staggered 0 0 0 v 
403 0 0.3695 2.9772 D 0.06 0.018 e e staggered 0 0 0 
403 0 0.241 2.875 D 0.028 0.024 e e staggered 0 0 0 
403 0 0.241 2.925 D 0.028 0.024 e e staggered 0 0 0 
403 0.005 0.28 2.965 B m e staggered 0 0 0 v 
404 0 0.3695 3.0028 D 0.06 0.018 e e staggered 0 0 0 
404 0 0.241 3.025 D 0.028 0.024 e e staggered 0 0 0 
404 0 0.241 2.975 D 0.028 0.024 e e staggered 0 0 0 
404 0.005 0.285 3.02 B m e staggered 0 0 0 v 
405 0.00985 4.40343 2.11902 T e e staggered 0 0 0 
405 0 4.53 2.419 T 0.024 0.028 e e staggered 0 0 0 
405 0.005 4.435 2.315 B m e staggered 0 0 0 v 
406 0 3.95441 3.4056 T 0.017 0.024 e e staggered 0 0 0 
406 0 4.53 2.461 T 0.024 0.028 e e staggered 0 0 0 
406 0 3.87 3.424 T 0.024 0.028 e e staggered 0 0 0 
406 0.005 4.53 2.5 B m e staggered 0 0 0 v 
406 0.005 3.9 3.385 B m e staggered 0 0 0 v 
407 0.005 0.636 2.915 B e e staggered 0 0 0 
407 0.00985 4.36406 2.15839 T e e staggered 0 0 0 
407 0 0.5505 2.9772 D 0.06 0.018 e e staggered 0 0 0 
407 0 0.699 2.915 D 0.028 0.024 e e staggered 0 0 0 
407 0.005 2.97 3.105 B m e staggered 0 0 0 v 
407 0.004 4.38374 2.17807 B m e staggered 0 0 0 v 
408 0.005 3.24 3.01 B e e staggered 0 0 0 
408 0 3.395 2.906 D 0.024 0.028 e e staggered 0 0 0 
408 0 3.35 2.906 D 0.024 0.028 e e staggered 0 0 0 
409 0 0.79932 2.69151 T 0.011 0.014 e e staggered 0 0 0 
409 0 0.858 2.789 D 0.024 0.028 e e staggered 0 0 0 
409 0.004 0.825 2.732 B m e staggered 0 0 0 v 
410 0 0.9575 0.6536 T 0.047 0.02 e e staggered 0 0 0 
410 0 1.1737 0.6586 T 0.028 0.024 e e staggered 0 0 0 
410 0.004 1.128 0.666 B m e staggered 0 0 0 v 
411 0 0.75897 2.68069 T 0.014 0.011 e e staggered 0 0 0 
411 0 0.661 2.79 T 0.028 0.024 e e staggered 0 0 0 
411 0.004 0.72 2.714 B m e staggered 0 0 0 v 
412 0 0.75897 2.64131 T 0.014 0.011 e e staggered 0 0 0 
412 0 0.68448 2.614 T 0.028 0.024 e e staggered 0 0 0 
412 0.005 0.695 2.578 B m e staggered 0 0 0 v 
413 0.00985 4.4428 2.11902 T e e staggered 0 0 0 
413 0 4.62 2.419 T 0.024 0.028 e e staggered 0 0 0 
413 0.005 4.49 2.275 B m e staggered 0 0 0 v 
414 0 4.14941 3.4076 T 0.017 0.024 e e staggered 0 0 0 
414 0 4.62 2.461 T 0.024 0.028 e e staggered 0 0 0 
414 0 4.08 3.429 T 0.024 0.028 e e staggered 0 0 0 
414 0.005 4.685 2.645 B m e staggered 0 0 0 v 
414 0.005 4.1 3.38 B m e staggered 0 0 0 v 
415 0 3.41796 3.95787 T 0.024 0.02 e e staggered 0 0 0 
415 0 3.443 3.858 T 0.024 0.028 e e staggered 0 0 0 
416 0 0.77964 2.63049 T 0.011 0.014 e e staggered 0 0 0 
416 0 0.76948 2.567 T 0.024 0.028 e e staggered 0 0 0 
416 0.004 0.77964 2.601 B m e staggered 0 0 0 v 
417 0 0.79932 2.63049 T 0.011 0.014 e e staggered 0 0 0 
417 0 0.835 2.566 T 0.024 0.028 e e staggered 0 0 0 
417 0.005 0.832 2.603 B m e staggered 0 0 0 v 
418 0 1.09347 3.12 T 0.012 0.064 e e staggered 0 0 0 
418 0 1.175 2.981 T 0.024 0.028 e e staggered 0 0 0 
418 0 1.125 2.981 T 0.024 0.028 e e staggered 0 0 0 
418 0.005 1.125 3.02 B m e staggered 0 0 0 v 
419 0.00985 4.40343 1.8828 T e e staggered 0 0 0 
419 0 1.125 2.939 T 0.024 0.028 e e staggered 0 0 0 
419 0.005 1.125 2.9 B m e staggered 0 0 0 v 
419 0.005 3.46 3.065 B m e staggered 0 0 0 v 
419 0.004 4.42311 1.90248 B m e staggered 0 0 0 v 
420 0 1.07379 3.12 T 0.012 0.064 e e staggered 0 0 0 
420 0 1.075 2.981 T 0.024 0.028 e e staggered 0 0 0 
420 0.005 1.075 3.02 B m e staggered 0 0 0 v 
421 0.00985 4.40343 1.92217 T e e staggered 0 0 0 
421 0 1.025 2.939 T 0.024 0.028 e e staggered 0 0 0 
421 0 1.075 2.939 T 0.024 0.028 e e staggered 0 0 0 
421 0.005 1.025 2.9 B m e staggered 0 0 0 v 
421 0.005 3.51 3.08 B m e staggered 0 0 0 v 
421 0.004 4.42311 1.94185 B m e staggered 0 0 0 v 
422 0.00985 4.24595 1.92217 T e e staggered 0 0 0 
422 0 1.9977 0.632 T 0.024 0.028 e e staggered 0 0 0 
422 0.004 1.96497 0.76502 B m e staggered 0 0 0 v 
422 0.004 4.22627 1.94185 B m e staggered 0 0 0 v 
423 0 2.954 0.57441 T 0.028 0.024 e e staggered 0 0 0 
423 0 4.926 2.07 T 0.028 0.024 e e staggered 0 0 0 
423 0 2.848 0.57941 T 0.038 0.013 e e staggered 0 0 0 
423 0.005 4.975 2.14 B m e staggered 0 0 0 v 
423 0.005 5.03005 0.99494 B m e staggered 0 0 0 v 
424 0.005 0.647 2.517 B e e staggered 0 0 0 
424 0 0.57676 2.49174 T 0.012 0.038 e e staggered 0 0 0 
424 0.00985 4.24595 1.80406 T e e staggered 0 0 0 
424 0 0.578 2.569 T 0.024 0.028 e e staggered 0 0 0 
424 0.005 0.939 1.552 B m e staggered 0 0 0 v 
424 0.004 4.22627 1.82374 B m e staggered 0 0 0 v 
425 0.00985 4.48217 2.04028 T e e staggered 0 0 0 
425 0 4.65 2.299 T 0.024 0.028 e e staggered 0 0 0 
425 0.005 4.61 2.3 B m e staggered 0 0 0 v 
425 0.004 4.50185 2.05996 B m e staggered 0 0 0 v 
426 0 4.4085 3.19439 T 0.062 0.014 e e staggered 0 0 0 
426 0 4.65 2.341 T 0.024 0.028 e e staggered 0 0 0 
426 0.005 4.61 2.345 B m e staggered 0 0 0 v 
426 0.005 4.54 3.125 B m e staggered 0 0 0 v 
427 0 3.32848 2.22542 T 0.027 0.01 e e staggered 0 0 0 
427 0 3.35 2.864 D 0.024 0.028 e e staggered 0 0 0 
427 0.005 3.27923 2.21577 B m e staggered 0 0 0 v 
427 0.004 3.3435 2.82 B m e staggered 0 0 0 v 
428 0.005 0.645 1.295 B e e staggered 0 0 0 
428 0 0.57676 1.35 T 0.012 0.038 e e staggered 0 0 0 
428 0.00985 4.20658 1.8828 T e e staggered 0 0 0 
428 0 0.58 1.444 T 0.024 0.028 e e staggered 0 0 0 
428 0.005 0.955 1.92 B m e staggered 0 0 0 v 
428 0.004 4.1869 1.90248 B m e staggered 0 0 0 v 
429 0 0.5374 1.35 T 0.012 0.038 e e staggered 0 0 0 
429 0 0.48 1.444 T 0.024 0.028 e e staggered 0 0 0 
429 0.005 0.475 1.405 B m e staggered 0 0 0 v 
430 0.00985 4.63965 1.72532 T e e staggered 0 0 0 
430 0 0.48 1.486 T 0.024 0.028 e e staggered 0 0 0 
430 0.0125 4.67901 1.68595 D e e staggered 0 0 0 
430 0.005 0.4839 1.28312 B m e staggered 0 0 0 v 
430 0.005 0.935 1.105 B m e staggered 0 0 0 v 
430 0.004 4.65933 1.70564 B m e staggered 0 0 0 v 
431 0.005 0.635 0.845 B e e staggered 0 0 0 
431 0 0.57676 0.77914 T 0.012 0.038 e e staggered 0 0 0 
431 0.00985 4.16721 1.84343 T e e staggered 0 0 0 
431 0 0.58 0.884 T 0.024 0.028 e e staggered 0 0 0 
431 0.005 0.945 1.63 B m e staggered 0 0 0 v 
431 0.004 4.14753 1.86311 B m e staggered 0 0 0 v 
432 0 3.3904 4.07696 T 0.012 0.024 e e staggered 0 0 0 
432 0 3.386 4.095 D 0.028 0.024 e e staggered 0 0 0 
432 0.005 3.437 4.099 B m e staggered 0 0 0 v 
433 0 0.5374 0.77914 T 0.012 0.038 e e staggered 0 0 0 
433 0 0.485 0.884 T 0.024 0.028 e e staggered 0 0 0 
433 0.005 0.515 0.835 B m e staggered 0 0 0 v 
434 0.00985 4.63965 1.76469 T e e staggered 0 0 0 
434 0 0.485 0.926 T 0.024 0.028 e e staggered 0 0 0 
434 0 4.639 1.755 D 0.028 0.024 e e staggered 0 0 0 
434 0.005 2.078 0.8301 B m e staggered 0 0 0 v 
434 0.004 0.46 0.82 B m e staggered 0 0 0 v 
434 0.004 4.65933 1.78437 B m e staggered 0 0 0 v 
435 0 0.5374 2.49174 T 0.012 0.038 e e staggered 0 0 0 
435 0 0.478 2.569 T 0.024 0.028 e e staggered 0 0 0 
435 0.005 0.485 2.525 B m e staggered 0 0 0 v 
436 0.00985 4.67902 2.11902 T e e staggered 0 0 0 
436 0 0.478 2.611 T 0.024 0.028 e e staggered 0 0 0 
436 0.0125 4.71839 2.11902 D e e staggered 0 0 0 
436 0.015 1.005 2.8473 D m e staggered 0 0 0 v t 
436 0.005 0.525 2.78 B m e staggered 0 0 0 v 
436 0.004 3.755 3.505 B m e staggered 0 0 0 v 
436 0.004 4.6987 2.1387 B m e staggered 0 0 0 v 
437 0 0.5374 1.92087 T 0.012 0.038 e e staggered 0 0 0 
437 0 0.48 2.049 T 0.024 0.028 e e staggered 0 0 0 
437 0.005 0.48 2.005 B m e staggered 0 0 0 v 
438 0.00985 4.67902 2.07965 T e e staggered 0 0 0 
438 0 0.48 2.091 T 0.024 0.028 e e staggered 0 0 0 
438 0.0125 4.67902 2.07965 D e e staggered 0 0 0 
438 0.005 0.45 2.13 B m e staggered 0 0 0 v 
438 0.005 0.965 2.355 B m e staggered 0 0 0 v 
438 0.004 4.6987 2.09933 B m e staggered 0 0 0 v 
439 0.00985 4.0491 1.80406 T e e staggered 0 0 0 
439 0 0.821 1.15 T 0.028 0.024 e e staggered 0 0 0 
439 0.005 0.935 1.3 B m e staggered 0 0 0 v 
439 0.004 4.02942 1.82374 B m e staggered 0 0 0 v 
440 0.00985 4.00973 1.96154 T e e staggered 0 0 0 
440 0 0.242 2.66408 T 0.024 0.028 e e staggered 0 0 0 
440 0.005 0.63 2.06 B m e staggered 0 0 0 v 
440 0.005 0.99 1.975 B m e staggered 0 0 0 v 
440 0.005 0.242 2.62508 B m e staggered 0 0 0 v 
440 0.004 3.99005 1.98122 B m e staggered 0 0 0 v 
441 0.00985 3.97035 1.96154 T e e staggered 0 0 0 
441 0 0.422 2.66408 T 0.024 0.028 e e staggered 0 0 0 
441 0.005 0.63 2.105 B m e staggered 0 0 0 v 
441 0.005 0.99 2.015 B m e staggered 0 0 0 v 
441 0.005 0.43 2.555 B m e staggered 0 0 0 v 
441 0.004 3.95067 1.98122 B m e staggered 0 0 0 v 
442 0.00985 3.97035 2.00091 T e e staggered 0 0 0 
442 0 0.287 2.66408 T 0.024 0.028 e e staggered 0 0 0 
442 0.005 0.287 2.62508 B m e staggered 0 0 0 v 
442 0.005 0.63 2.15 B m e staggered 0 0 0 v 
442 0.005 0.985 2.185 B m e staggered 0 0 0 v 
442 0.004 3.95067 2.02059 B m e staggered 0 0 0 v 
443 0.005 0.565 1.13 B e e staggered 0 0 0 
443 0 0.55708 1.21692 T 0.012 0.038 e e staggered 0 0 0 
443 0.00985 4.16721 1.8828 T e e staggered 0 0 0 
443 0 0.505 1.1259 T 0.024 0.028 e e staggered 0 0 0 
443 0.005 0.99 1.755 B m e staggered 0 0 0 v 
443 0.005 0.885 1.49 B m e staggered 0 0 0 v 
443 0.004 4.14753 1.90248 B m e staggered 0 0 0 v 
444 0.005 0.644 0.7 B e e staggered 0 0 0 
444 0 0.55708 0.64606 T 0.012 0.038 e e staggered 0 0 0 
444 0.00985 4.20658 1.84343 T e e staggered 0 0 0 
444 0 0.577 0.655 D 0.024 0.028 e e staggered 0 0 0 
444 0.005 0.975 1.72 B m e staggered 0 0 0 v 
444 0.005 0.555 0.59 B m e staggered 0 0 0 v 
444 0.004 4.1869 1.86311 B m e staggered 0 0 0 v 
445 0.005 0.575 2.265 B e e staggered 0 0 0 
445 0 0.55708 2.35866 T 0.012 0.038 e e staggered 0 0 0 
445 0.00985 4.24595 1.84343 T e e staggered 0 0 0 
445 0 0.51452 2.275 T 0.024 0.028 e e staggered 0 0 0 
445 0.005 0.957 2.275 B m e staggered 0 0 0 v 
445 0.004 4.22627 1.86311 B m e staggered 0 0 0 v 
446 0.005 0.545 1.71 B e e staggered 0 0 0 
446 0 0.55708 1.78779 T 0.012 0.038 e e staggered 0 0 0 
446 0.00985 4.28532 1.80406 T e e staggered 0 0 0 
446 0 0.556 1.65 T 0.028 0.024 e e staggered 0 0 0 
446 0.005 0.952 1.51 B m e staggered 0 0 0 v 
446 0.004 4.26564 1.82374 B m e staggered 0 0 0 v 
447 0 4.16369 4.0871 T 0.012 0.049 e e staggered 0 0 0 
447 0 0.191 1.52698 T 0.024 0.028 e e staggered 0 0 0 
447 0.005 0.191 1.48798 B m e staggered 0 0 0 v 
447 0.005 0.09 2.79 B m e staggered 0 0 0 v 
447 0.004 4.14 4.19 B m e staggered 0 0 0 v 
447 0.004 0.98 4.2 B m e staggered 0 0 0 v 
448 0 4.20306 4.0886 T 0.012 0.046 e e staggered 0 0 0 
448 0 0.416 1.52698 T 0.024 0.028 e e staggered 0 0 0 
448 0.005 0.416 1.48798 B m e staggered 0 0 0 v 
448 0.005 0.09 2.86 B m e staggered 0 0 0 v 
448 0.004 4.22337 4.24 B m e staggered 0 0 0 v 
448 0.004 0.9 4.205 B m e staggered 0 0 0 v 
449 0 4.18337 4.0871 T 0.012 0.049 e e staggered 0 0 0 
449 0 0.326 1.52698 T 0.024 0.028 e e staggered 0 0 0 
449 0.005 0.326 1.487 B m e staggered 0 0 0 v 
449 0.005 0.15 2.79 B m e staggered 0 0 0 v 
449 0.004 4.168 4.24 B m e staggered 0 0 0 v 
449 0.004 0.855 4.205 B m e staggered 0 0 0 v 
450 0 4.08494 4.0886 T 0.012 0.046 e e staggered 0 0 0 
450 0 0.821 1.05 T 0.028 0.024 e e staggered 0 0 0 
450 0.005 0.41409 1.32591 B m e staggered 0 0 0 v 
450 0.005 0.89 1.105 B m e staggered 0 0 0 v 
450 0.005 0.805 4.205 B m e staggered 0 0 0 v 
450 0.004 3.93 4.185 B m e staggered 0 0 0 v 
451 0 4.12431 4.0871 T 0.012 0.049 e e staggered 0 0 0 
451 0 0.821 1.3 T 0.028 0.024 e e staggered 0 0 0 
451 0.005 0.465 1.33 B m e staggered 0 0 0 v 
451 0.005 0.87 1.3 B m e staggered 0 0 0 v 
451 0.004 4.03 4.185 B m e staggered 0 0 0 v 
451 0.004 0.705 4.19 B m e staggered 0 0 0 v 
452 0 4.10463 4.0871 T 0.012 0.049 e e staggered 0 0 0 
452 0 0.821 1.2 T 0.028 0.024 e e staggered 0 0 0 
452 0.005 0.415 1.275 B m e staggered 0 0 0 v 
452 0.005 0.87 1.2 B m e staggered 0 0 0 v 
452 0.004 3.98 4.185 B m e staggered 0 0 0 v 
452 0.004 0.7558 4.19004 B m e staggered 0 0 0 v 
453 0 4.0489 4.01169 T 0.049 0.012 e e staggered 0 0 0 
453 0 0.197 2.66408 T 0.024 0.028 e e staggered 0 0 0 
453 0.005 0.19 2.625 B m e staggered 0 0 0 v 
453 0.004 3.985 4 B m e staggered 0 0 0 v 
454 0 4.0474 4.05106 T 0.046 0.012 e e staggered 0 0 0 
454 0 0.377 2.66408 T 0.024 0.028 e e staggered 0 0 0 
454 0.005 0.405 2.62 B m e staggered 0 0 0 v 
454 0.004 3.885 4 B m e staggered 0 0 0 v 
455 0 4.0489 4.03137 T 0.049 0.012 e e staggered 0 0 0 
455 0 0.332 2.66408 T 0.024 0.028 e e staggered 0 0 0 
455 0.005 0.332 2.62508 B m e staggered 0 0 0 v 
455 0.004 3.935 4 B m e staggered 0 0 0 v 
456 0 4.0474 3.93294 T 0.046 0.012 e e staggered 0 0 0 
456 0 0.78747 1.75 T 0.028 0.024 e e staggered 0 0 0 
456 0.005 0.835 1.78 B m e staggered 0 0 0 v 
456 0.004 3.985 3.91 B m e staggered 0 0 0 v 
457 0 4.0489 3.97231 T 0.049 0.012 e e staggered 0 0 0 
457 0 0.78747 1.93 T 0.028 0.024 e e staggered 0 0 0 
457 0.005 0.835 1.93 B m e staggered 0 0 0 v 
457 0.004 3.885 3.91 B m e staggered 0 0 0 v 
458 0 4.0489 3.95263 T 0.049 0.012 e e staggered 0 0 0 
458 0 0.78747 1.885 T 0.028 0.024 e e staggered 0 0 0 
458 0.005 0.835 1.885 B m e staggered 0 0 0 v 
458 0.004 3.935 3.91 B m e staggered 0 0 0 v 
459 0 4.12431 3.8969 T 0.012 0.049 e e staggered 0 0 0 
459 0 0.18 3.189 T 0.024 0.028 e e staggered 0 0 0 
459 0.005 0.18 3.145 B m e staggered 0 0 0 v 
459 0.004 4.15463 3.83 B m e staggered 0 0 0 v 
460 0 4.08494 3.8954 T 0.012 0.046 e e staggered 0 0 0 
460 0 0.43 3.189 T 0.024 0.028 e e staggered 0 0 0 
460 0.005 0.43 3.145 B m e staggered 0 0 0 v 
460 0.004 4.05463 3.83 B m e staggered 0 0 0 v 
461 0 4.10463 3.8969 T 0.012 0.049 e e staggered 0 0 0 
461 0 0.33 3.189 T 0.024 0.028 e e staggered 0 0 0 
461 0.005 0.33 3.145 B m e staggered 0 0 0 v 
461 0.004 4.10463 3.83 B m e staggered 0 0 0 v 
462 0.00985 4.0491 2.04028 T e e staggered 0 0 0 
462 0 0.78747 1.795 T 0.028 0.024 e e staggered 0 0 0 
462 0.005 0.905 1.885 B m e staggered 0 0 0 v 
462 0.004 4.02942 2.05996 B m e staggered 0 0 0 v 
463 0.00985 4.00973 2.04028 T e e staggered 0 0 0 
463 0 0.78747 1.975 T 0.028 0.024 e e staggered 0 0 0 
463 0.005 0.945 1.97 B m e staggered 0 0 0 v 
463 0.004 3.99005 2.05996 B m e staggered 0 0 0 v 
464 0 2.1734 3.2655 T 0.018 0.06 e e staggered 0 0 0 
464 0 2.2628 3.287 T 0.024 0.028 e e staggered 0 0 0 
464 0.004 2.22 3.3 B m e staggered 0 0 0 v 
465 0 6.0845 1.0834 T 0.06 0.018 e e staggered 0 0 0 
465 0 5.956 1.08 T 0.028 0.024 e e staggered 0 0 0 
465 0.005 6.0085 1.1235 B m e staggered 0 0 0 v 
466 0 2.0966 3.0845 T 0.018 0.06 e e staggered 0 0 0 
466 0 2.083 2.973 T 0.024 0.028 e e staggered 0 0 0 
466 0 2.083 2.973 D 0.024 0.028 e e staggered 0 0 0 
466 0.004 2.085 3.017 B m e staggered 0 0 0 v 
467 0 6.2655 1.0066 T 0.06 0.018 e e staggered 0 0 0 
467 0 6.379 0.965 T 0.028 0.024 e e staggered 0 0 0 
467 0 6.379 0.965 D 0.028 0.024 e e staggered 0 0 0 
467 0.005 6.335 0.965 B m e staggered 0 0 0 v 
468 0 2.1222 3.0845 T 0.018 0.06 e e staggered 0 0 0 
468 0 2.128 2.973 T 0.024 0.028 e e staggered 0 0 0 
468 0 2.128 2.973 D 0.024 0.028 e e staggered 0 0 0 
468 0.004 2.135 3.017 B m e staggered 0 0 0 v 
469 0 6.2655 1.0322 T 0.06 0.018 e e staggered 0 0 0 
469 0 6.379 1.02 T 0.028 0.024 e e staggered 0 0 0 
469 0 6.379 1.02 D 0.028 0.024 e e staggered 0 0 0 
469 0.005 6.335 1.02 B m e staggered 0 0 0 v 
470 0 2.1478 3.0845 T 0.018 0.06 e e staggered 0 0 0 
470 0 2.173 2.973 T 0.024 0.028 e e staggered 0 0 0 
470 0 2.173 2.973 D 0.024 0.028 e e staggered 0 0 0 
470 0.004 2.185 3.017 B m e staggered 0 0 0 v 
471 0 6.2655 1.0578 T 0.06 0.018 e e staggered 0 0 0 
471 0 6.379 1.08 T 0.028 0.024 e e staggered 0 0 0 
471 0 6.379 1.08 D 0.028 0.024 e e staggered 0 0 0 
471 0.005 6.335 1.08 B m e staggered 0 0 0 v 
472 0.005 2.017 3.279 B e e staggered 0 0 0 
472 0.00985 4.32469 2.15839 T e e staggered 0 0 0 
472 0 2.1222 3.2655 T 0.018 0.06 e e staggered 0 0 0 
472 0 1.959 3.247 T 0.024 0.028 e e staggered 0 0 0 
472 0.005 3.125 3.075 B m e staggered 0 0 0 v 
472 0.004 4.34437 2.17807 B m e staggered 0 0 0 v 
473 0.005 5.8 1.048 B e e staggered 0 0 0 
473 0.00985 4.32469 2.00091 T e e staggered 0 0 0 
473 0 6.0845 1.0322 T 0.06 0.018 e e staggered 0 0 0 
473 0 5.956 0.965 T 0.028 0.024 e e staggered 0 0 0 
473 0.004 5.285 2.99 B m e staggered 0 0 0 v 
473 0.004 4.34437 2.02059 B m e staggered 0 0 0 v 
474 0.00985 4.08847 2.00091 T e e staggered 0 0 0 
474 0 0.78747 1.84 T 0.028 0.024 e e staggered 0 0 0 
474 0.005 0.905 1.935 B m e staggered 0 0 0 v 
474 0.004 4.06879 2.02059 B m e staggered 0 0 0 v 
475 0.00985 3.93098 2.07965 T e e staggered 0 0 0 
475 0 0.23 3.189 T 0.024 0.028 e e staggered 0 0 0 
475 0.005 0.975 2.14 B m e staggered 0 0 0 v 
475 0.005 0.445 3.09 B m e staggered 0 0 0 v 
475 0.004 3.9113 2.09933 B m e staggered 0 0 0 v 
476 0.00985 3.89161 2.07965 T e e staggered 0 0 0 
476 0 0.38 3.189 T 0.024 0.028 e e staggered 0 0 0 
476 0.005 0.395 3.09 B m e staggered 0 0 0 v 
476 0.005 0.99 2.065 B m e staggered 0 0 0 v 
476 0.004 3.87193 2.09933 B m e staggered 0 0 0 v 
477 0.00985 3.89161 2.00091 T e e staggered 0 0 0 
477 0 0.28 3.189 T 0.024 0.028 e e staggered 0 0 0 
477 0.005 0.345 3.09 B m e staggered 0 0 0 v 
477 0.005 0.99 1.885 B m e staggered 0 0 0 v 
477 0.005 3.84091 2.00091 B m e staggered 0 0 0 v 
478 0.00985 4.67902 1.8828 T e e staggered 0 0 0 
478 0 4.34 3.454 T 0.024 0.028 e e staggered 0 0 0 
478 0.005 4.615 3.11 B m e staggered 0 0 0 v 
478 0.005 4.4 3.325 B m e staggered 0 0 0 v 
478 0.004 4.6987 1.90248 B m e staggered 0 0 0 v 
479 0 1.9695 3.388 D 0.065 0.02 e e staggered 0 0 0 
479 0 2.104 3.36 D 0.028 0.024 e e staggered 0 0 0 
479 0 2.105 3.409 D 0.024 0.028 e e staggered 0 0 0 
479 0.015 2.05 3.375 D m e staggered 0 0 0 v t 
480 0 1.352 3.47695 T 0.064 0.012 e e staggered 0 0 0 
480 0 1.9695 3.538 D 0.065 0.02 e e staggered 0 0 0 
480 0 2.104 3.55 D 0.028 0.024 e e staggered 0 0 0 
480 0.005 2.05 3.538 B m e staggered 0 0 0 v 
481 0 1.352 3.45727 T 0.064 0.012 e e staggered 0 0 0 
481 0 1.9695 3.488 D 0.065 0.02 e e staggered 0 0 0 
481 0 2.104 3.5 D 0.028 0.024 e e staggered 0 0 0 
481 0.005 2.05 3.488 B m e staggered 0 0 0 v 
482 0 4.0355 3.76457 T 0.062 0.014 e e staggered 0 0 0 
482 0.005 3.95 3.82 B e e staggered 0 0 0 
482 0 3.881 3.758 T 0.028 0.024 e e staggered 0 0 0 
482 0 3.881 3.81 T 0.028 0.024 e e staggered 0 0 0 
482 0 3.881 3.81 D 0.028 0.024 e e staggered 0 0 0 
482 0 3.881 3.758 D 0.028 0.024 e e staggered 0 0 0 
483 0.00985 4.16721 1.80406 T e e staggered 0 0 0 
483 0 3.839 3.81 T 0.028 0.024 e e staggered 0 0 0 
483 0.005 4.13 3.005 B m e staggered 0 0 0 v 
483 0.005 4.39 3.02 B m e staggered 0 0 0 v 
483 0.005 3.795 3.81 B m e staggered 0 0 0 v 
483 0.004 4.14753 1.82374 B m e staggered 0 0 0 v 
484 0 0.894 3.4179 T 0.064 0.012 e e staggered 0 0 0 
484 0 3.839 3.758 T 0.028 0.024 e e staggered 0 0 0 
484 0.005 0.795 3.4179 B m e staggered 0 0 0 v 
484 0.005 3.795 3.758 B m e staggered 0 0 0 v 
485 0 0.73662 0.7085 T 0.014 0.062 e e staggered 0 0 0 
485 0 0.721 0.817 D 0.024 0.028 e e staggered 0 0 0 
485 0.005 0.715 0.77 B m e staggered 0 0 0 v 
486 0 1.352 3.43758 T 0.064 0.012 e e staggered 0 0 0 
486 0 1.9695 3.438 D 0.065 0.02 e e staggered 0 0 0 
486 0 2.105 3.451 D 0.024 0.028 e e staggered 0 0 0 
486 0.005 2.15 3.438 B m e staggered 0 0 0 v 
487 0 1.62033 2.99531 T 0.041 0.012 e e staggered 0 0 0 
487 0 1.055 3.731 T 0.024 0.028 e e staggered 0 0 0 
487 0.005 1.045 3.77 B m e staggered 0 0 0 v 
487 0.005 1.566 2.95 B m e staggered 0 0 0 v 
488 0 4.00559 3.4056 T 0.017 0.024 e e staggered 0 0 0 
488 0 4.20059 3.4076 T 0.017 0.024 e e staggered 0 0 0 
488 0 4.1695 3.24557 T 0.062 0.014 e e staggered 0 0 0 
488 0.005 4.08 3.27 B e e staggered 0 0 0 
488 0 4.015 3.239 T 0.028 0.024 e e staggered 0 0 0 
488 0 4.015 3.291 T 0.028 0.024 e e staggered 0 0 0 
488 0 4.015 3.291 D 0.028 0.024 e e staggered 0 0 0 
488 0 4.015 3.239 D 0.028 0.024 e e staggered 0 0 0 
489 0 4.4085 3.21998 T 0.062 0.014 e e staggered 0 0 0 
489 0 4.512 3.22 T 0.028 0.024 e e staggered 0 0 0 
489 0.005 4.47 3.21998 B m e staggered 0 0 0 v 
490 0 5.59271 3.737 T 0.047 0.012 e e staggered 0 0 0 
490 0 5.72 3.757 T 0.028 0.024 e e staggered 0 0 0 
490 0.005 5.686 3.76 B m e staggered 0 0 0 v 
491 0 1.01473 3.578 T 0.012 0.064 e e staggered 0 0 0 
491 0 1.04 3.564 D 0.024 0.028 e e staggered 0 0 0 
491 0.005 1.03 3.515 B m e staggered 0 0 0 v 
492 0.00985 4.12784 1.80406 T e e staggered 0 0 0 
492 0 3.973 3.291 T 0.028 0.024 e e staggered 0 0 0 
492 0.005 4.075 3.005 B m e staggered 0 0 0 v 
492 0.005 4.345 3.02 B m e staggered 0 0 0 v 
492 0.005 3.925 3.291 B m e staggered 0 0 0 v 
492 0.004 4.10816 1.82374 B m e staggered 0 0 0 v 
493 0 0.894 3.39821 T 0.064 0.012 e e staggered 0 0 0 
493 0 3.973 3.239 T 0.028 0.024 e e staggered 0 0 0 
493 0.005 0.825 3.39 B m e staggered 0 0 0 v 
493 0.005 3.925 3.239 B m e staggered 0 0 0 v 
494 0 1.17221 3.578 T 0.012 0.064 e e staggered 0 0 0 
494 0 1.175 3.564 D 0.024 0.028 e e staggered 0 0 0 
494 0.005 1.19 3.52 B m e staggered 0 0 0 v 
495 0 0.894 3.47695 T 0.064 0.012 e e staggered 0 0 0 
495 0 0.869 3.5 D 0.028 0.024 e e staggered 0 0 0 
495 0 0.869 3.455 D 0.028 0.024 e e staggered 0 0 0 
495 0.005 0.795 3.485 B m e staggered 0 0 0 v 
496 0 0.97536 3.578 T 0.012 0.064 e e staggered 0 0 0 
496 0 0.95 3.564 D 0.024 0.028 e e staggered 0 0 0 
496 0.005 0.951 3.519 B m e staggered 0 0 0 v 
497 0 4.0355 3.6878 T 0.062 0.014 e e staggered 0 0 0 
497 0 0.95 3.606 D 0.024 0.028 e e staggered 0 0 0 
497 0.005 0.915 3.595 B m e staggered 0 0 0 v 
497 0.005 3.95 3.7 B m e staggered 0 0 0 v 
498 0 0.894 3.49664 T 0.064 0.012 e e staggered 0 0 0 
498 0 0.882 3.553 D 0.024 0.028 e e staggered 0 0 0 
498 0.005 0.83 3.525 B m e staggered 0 0 0 v 
499 0 4.0355 3.61102 T 0.062 0.014 e e staggered 0 0 0 
499 0 0.882 3.595 D 0.024 0.028 e e staggered 0 0 0 
499 0.005 0.835 3.6 B m e staggered 0 0 0 v 
499 0.005 3.95 3.6 B m e staggered 0 0 0 v 
500 0 4.2745 3.58543 T 0.062 0.014 e e staggered 0 0 0 
500 0 0.911 3.5 D 0.028 0.024 e e staggered 0 0 0 
500 0.005 1.015 3.41 B m e staggered 0 0 0 v 
500 0.005 4.225 3.545 B m e staggered 0 0 0 v 
501 0 0.894 3.45727 T 0.064 0.012 e e staggered 0 0 0 
501 0 0.869 3.41 D 0.028 0.024 e e staggered 0 0 0 
501 0.005 0.83 3.445 B m e staggered 0 0 0 v 
502 0 4.2745 3.6622 T 0.062 0.014 e e staggered 0 0 0 
502 0 0.911 3.41 D 0.028 0.024 e e staggered 0 0 0 
502 0.005 0.975 3.41 B m e staggered 0 0 0 v 
502 0.005 4.205 3.66 B m e staggered 0 0 0 v 
503 0 0.894 3.31947 T 0.064 0.012 e e staggered 0 0 0 
503 0 0.746 3.245 T 0.028 0.024 e e staggered 0 0 0 
503 0.005 0.78635 3.24492 B m e staggered 0 0 0 v 
504 0 4.8855 0.79161 T 0.062 0.014 e e staggered 0 0 0 
504 0 5.1245 0.8428 T 0.062 0.014 e e staggered 0 0 0 
504 0 0.704 3.245 T 0.028 0.024 e e staggered 0 0 0 
504 0 0.704 3.245 D 0.028 0.024 e e staggered 0 0 0 
504 0.005 3.62 1.235 B m e staggered 0 0 0 v 
504 0.005 4.937 0.79161 B m e staggered 0 0 0 v 
504 0.005 0.66 3.235 B m e staggered 0 0 0 v 
504 0.005 5.195 0.815 B m e staggered 0 0 0 v 
505 0 0.894 3.29979 T 0.064 0.012 e e staggered 0 0 0 
505 0 0.746 3.2 T 0.028 0.024 e e staggered 0 0 0 
505 0.005 0.82951 3.2794 B m e staggered 0 0 0 v 
506 0 4.8855 0.86839 T 0.062 0.014 e e staggered 0 0 0 
506 0 5.1245 0.76602 T 0.062 0.014 e e staggered 0 0 0 
506 0 0.704 3.2 T 0.028 0.024 e e staggered 0 0 0 
506 0 0.704 3.155 D 0.028 0.024 e e staggered 0 0 0 
506 0 0.704 3.2 D 0.028 0.024 e e staggered 0 0 0 
506 0.005 3.62 1.28 B m e staggered 0 0 0 v 
506 0.005 4.96 0.85 B m e staggered 0 0 0 v 
506 0.005 0.66 3.185 B m e staggered 0 0 0 v 
506 0.005 5.195 0.755 B m e staggered 0 0 0 v 
507 0 0.894 3.2801 T 0.064 0.012 e e staggered 0 0 0 
507 0 0.746 3.155 D 0.028 0.024 e e staggered 0 0 0 
507 0.005 0.79 3.155 B m e staggered 0 0 0 v 
508 0 4.8855 0.89398 T 0.062 0.014 e e staggered 0 0 0 
508 0.00985 4.48217 1.92217 T e e staggered 0 0 0 
508 0 4.736 0.865 T 0.028 0.024 e e staggered 0 0 0 
508 0.005 4.575 2.235 B m e staggered 0 0 0 v 
508 0.005 4.705 0.825 B m e staggered 0 0 0 v 
508 0.004 4.50185 1.94185 B m e staggered 0 0 0 v 
509 0 4.8855 0.8172 T 0.062 0.014 e e staggered 0 0 0 
509 0.00985 4.36406 1.96154 T e e staggered 0 0 0 
509 0 4.736 0.785 T 0.028 0.024 e e staggered 0 0 0 
509 0.005 4.575 2.275 B m e staggered 0 0 0 v 
509 0.005 4.755 0.825 B m e staggered 0 0 0 v 
509 0.004 4.38374 1.98122 B m e staggered 0 0 0 v 
510 0 5.1245 0.79161 T 0.062 0.014 e e staggered 0 0 0 
510 0.00985 4.71839 1.96154 T e e staggered 0 0 0 
510 0 5.249 0.76 T 0.028 0.024 e e staggered 0 0 0 
510 0.005 5.365 0.79 B m e staggered 0 0 0 v 
511 0 5.1245 0.86839 T 0.062 0.014 e e staggered 0 0 0 
511 0.00985 4.71839 1.92217 T e e staggered 0 0 0 
511 0 5.249 0.82 T 0.028 0.024 e e staggered 0 0 0 
511 0.005 5.365 0.845 B m e staggered 0 0 0 v 
512 0 4.8855 0.91957 T 0.062 0.014 e e staggered 0 0 0 
512 0.005 4.795 0.925 B e e staggered 0 0 0 
512 0 4.736 0.915 T 0.028 0.024 e e staggered 0 0 0 
512 0 4.736 0.965 T 0.028 0.024 e e staggered 0 0 0 
512 0 4.736 0.965 D 0.028 0.024 e e staggered 0 0 0 
512 0 4.736 0.915 D 0.028 0.024 e e staggered 0 0 0 
513 0 5.1245 0.89398 T 0.062 0.014 e e staggered 0 0 0 
513 0 5.249 0.87 T 0.028 0.024 e e staggered 0 0 0 
513 0.005 5.2 0.87 B m e staggered 0 0 0 v 
514 0.00985 4.12784 1.8828 T e e staggered 0 0 0 
514 0 4.694 0.965 T 0.028 0.024 e e staggered 0 0 0 
514 0.005 3.73649 1.85735 B m e staggered 0 0 0 v 
514 0.004 4.10816 1.90248 B m e staggered 0 0 0 v 
515 0 0.894 3.37853 T 0.064 0.012 e e staggered 0 0 0 
515 0 4.694 0.915 T 0.028 0.024 e e staggered 0 0 0 
515 0.005 3.38 1.025 B m e staggered 0 0 0 v 
515 0.005 0.62 3.235 B m e staggered 0 0 0 v 
515 0.005 4.585 0.865 B m e staggered 0 0 0 v 
516 0 1.62033 3.015 T 0.041 0.012 e e staggered 0 0 0 
516 0 1.53 3.004 T 0.024 0.028 e e staggered 0 0 0 
516 0 1.526 2.95 T 0.028 0.024 e e staggered 0 0 0 
516 0 1.521 3 D 0.028 0.024 e e staggered 0 0 0 
516 0.005 1.568 3.011 B m e staggered 0 0 0 v 
517 0.00985 4.56091 1.80406 T e e staggered 0 0 0 
517 0.0125 4.5609 1.84343 D e e staggered 0 0 0 
517 0 4.884 1.855 D 0.028 0.024 e e staggered 0 0 0 
517 0.005 4.84 1.855 B m e staggered 0 0 0 v 
517 0.004 4.58059 1.82374 B m e staggered 0 0 0 v 
518 0 2.997 0.621 T 0.028 0.024 e e staggered 0 0 0 
518 0 2.996 0.57441 T 0.028 0.024 e e staggered 0 0 0 
518 0 3.6576 2.6265 T 0.02 0.047 e e staggered 0 0 0 
518 0.005 3.12 2.645 B m e staggered 0 0 0 v 
518 0.005 3.65 2.68 B m e staggered 0 0 0 v 
518 0.005 3.125 1.605 B m e staggered 0 0 0 v 
519 0.00985 4.52154 1.92217 T e e staggered 0 0 0 
519 0 3.256 3.475 D 0.028 0.024 e e staggered 0 0 0 
519 0.004 3.61124 3.49876 B m e staggered 0 0 0 v 
519 0.004 4.54122 1.94185 B m e staggered 0 0 0 v 
520 0 5.91902 1.90865 T 0.024 0.028 e e staggered 0 0 0 
520 0 3.2815 3.35339 T 0.062 0.014 e e staggered 0 0 0 
520 0 5.91902 1.95065 D 0.024 0.028 e e staggered 0 0 0 
520 0.005 3.865 3.65 B m e staggered 0 0 0 v 
520 0.005 5.875 1.9 B m e staggered 0 0 0 v 
521 0 6.06902 1.90865 T 0.024 0.028 e e staggered 0 0 0 
521 0 3.2815 3.37898 T 0.062 0.014 e e staggered 0 0 0 
521 0 6.06902 1.90865 D 0.024 0.028 e e staggered 0 0 0 
521 0.005 3.81 3.65 B m e staggered 0 0 0 v 
521 0.005 6.06902 1.86 B m e staggered 0 0 0 v 
522 0 5.96047 2.04418 T 0.012 0.041 e e staggered 0 0 0 
522 0 5.91902 1.95065 T 0.024 0.028 e e staggered 0 0 0 
522 0.004 5.91902 2.003 B m e staggered 0 0 0 v 
523 0 6.01953 2.04418 T 0.012 0.041 e e staggered 0 0 0 
523 0 6.06902 1.95065 T 0.024 0.028 e e staggered 0 0 0 
523 0.004 6.06902 2.004 B m e staggered 0 0 0 v 
524 0 5.98016 2.04418 T 0.012 0.041 e e staggered 0 0 0 
524 0 5.96902 1.95065 T 0.024 0.028 e e staggered 0 0 0 
524 0 5.96902 1.95065 D 0.024 0.028 e e staggered 0 0 0 
524 0.004 5.97 1.999 B m e staggered 0 0 0 v 
525 0 5.59271 3.67794 T 0.047 0.012 e e staggered 0 0 0 
525 0 5.72 3.617 T 0.028 0.024 e e staggered 0 0 0 
525 0.005 5.681 3.617 B m e staggered 0 0 0 v 
526 0 0.75897 2.661 T 0.014 0.011 e e staggered 0 0 0 
526 0 0.68448 2.664 T 0.028 0.024 e e staggered 0 0 0 
526 0.005 0.724 2.646 B m e staggered 0 0 0 v 
527 0 0.77964 2.69151 T 0.011 0.014 e e staggered 0 0 0 
527 0 0.714 2.79 T 0.028 0.024 e e staggered 0 0 0 
527 0.004 0.758 2.743 B m e staggered 0 0 0 v 
528 0 3.0425 3.35339 T 0.062 0.014 e e staggered 0 0 0 
528 0 3.461 2.21 D 0.028 0.024 e e staggered 0 0 0 
528 0 3.461 2.255 D 0.028 0.024 e e staggered 0 0 0 
528 0.005 3.56 3.023 B m e staggered 0 0 0 v 
529 0 3.0425 3.3278 T 0.062 0.014 e e staggered 0 0 0 
529 0 3.329 2.21 D 0.028 0.024 e e staggered 0 0 0 
529 0 3.329 2.255 D 0.028 0.024 e e staggered 0 0 0 
529 0.005 3.57 2.955 B m e staggered 0 0 0 v 
530 0 3.45152 2.22542 T 0.027 0.01 e e staggered 0 0 0 
530 0 3.419 2.21 D 0.028 0.024 e e staggered 0 0 0 
530 0.004 3.4593 2.17 B m e staggered 0 0 0 v 
531 0 3.41953 2.22296 T 0.01 0.023 e e staggered 0 0 0 
531 0 3.371 2.21 D 0.028 0.024 e e staggered 0 0 0 
531 0.005 3.44 2.12 B m e staggered 0 0 0 v 
532 0.00985 4.20658 1.96154 T e e staggered 0 0 0 
532 0 3.159 2.299 T 0.028 0.024 e e staggered 0 0 0 
532 0.005 3.12 2.565 B m e staggered 0 0 0 v 
532 0.005 3.119 2.299 B m e staggered 0 0 0 v 
532 0.004 4.1869 1.98122 B m e staggered 0 0 0 v 
533 0.005 3.305 2.65 B e e staggered 0 0 0 
533 0 3.32848 2.2451 T 0.027 0.01 e e staggered 0 0 0 
533 0 3.201 2.254 T 0.028 0.024 e e staggered 0 0 0 
533 0.005 3.24 2.275 B m e staggered 0 0 0 v 
534 0 5.59271 3.69763 T 0.047 0.012 e e staggered 0 0 0 
534 0 5.72 3.667 T 0.028 0.024 e e staggered 0 0 0 
534 0.005 5.681 3.664 B m e staggered 0 0 0 v 
535 0.00985 4.28532 1.8828 T e e staggered 0 0 0 
535 0 3.335 2.553 D 0.024 0.028 e e staggered 0 0 0 
535 0.005 3.385 2.59 B m e staggered 0 0 0 v 
535 0.004 4.26564 1.90248 B m e staggered 0 0 0 v 
536 0.00985 4.67902 2.00091 T e e staggered 0 0 0 
536 0 4.884 2.025 T 0.028 0.024 e e staggered 0 0 0 
536 0.005 4.80288 2.03788 B m e staggered 0 0 0 v 
537 0 0.99505 3.12 T 0.012 0.064 e e staggered 0 0 0 
537 0.005 0.95 2.915 B e e staggered 0 0 0 
538 0.005 4.73807 1.54816 B e e staggered 0 0 0 
538 0.00985 4.71839 1.56784 T e e staggered 0 0 0 
539 0.005 4.73807 1.50879 B e e staggered 0 0 0 
539 0.00985 4.71839 1.52847 T e e staggered 0 0 0 
540 0.005 5.03 1.55 B e e staggered 0 0 0 
540 0.00985 4.56091 1.64658 T e e staggered 0 0 0 
540 0.004 4.58059 1.6269 B m e staggered 0 0 0 v 
541 0.005 4.975 1.485 B e e staggered 0 0 0 
541 0.00985 4.56091 1.60721 T e e staggered 0 0 0 
541 0.004 4.58059 1.58753 B m e staggered 0 0 0 v 
542 0.005 4.85 1.54 B e e staggered 0 0 0 
542 0.00985 4.67902 1.60721 T e e staggered 0 0 0 
543 0.005 4.91 1.54 B e e staggered 0 0 0 
543 0.00985 4.71839 1.60721 T e e staggered 0 0 0 
544 0.005 5.035 1.49 B e e staggered 0 0 0 
544 0.00985 4.63965 1.60721 T e e staggered 0 0 0 
544 0.004 4.65933 1.58753 B m e staggered 0 0 0 v 
545 0.005 4.915 1.485 B e e staggered 0 0 0 
545 0.00985 4.63965 1.56784 T e e staggered 0 0 0 
545 0.004 4.65933 1.54816 B m e staggered 0 0 0 v 
546 0.005 4.61996 1.6269 B e e staggered 0 0 0 
546 0.00985 4.60028 1.64658 T e e staggered 0 0 0 
547 0.005 4.65933 1.6269 B e e staggered 0 0 0 
547 0.00985 4.63965 1.64658 T e e staggered 0 0 0 
548 0.005 3.83 2.325 B e e staggered 0 0 0 
548 0.00985 3.93098 2.15839 T e e staggered 0 0 0 
549 0.005 3.75 2.1 B e e staggered 0 0 0 
549 0.00985 3.93098 2.11902 T e e staggered 0 0 0 
550 0.005 3.8 2.1 B e e staggered 0 0 0 
550 0.00985 3.89161 2.11902 T e e staggered 0 0 0 
551 0.005 4.149 2.298 B e e staggered 0 0 0 
551 0.00985 4.0491 2.15839 T e e staggered 0 0 0 
552 0.005 4.161 2.354 B e e staggered 0 0 0 
552 0.00985 4.00973 2.15839 T e e staggered 0 0 0 
553 0.005 4.23 2.354 B e e staggered 0 0 0 
553 0.00985 4.0491 2.11902 T e e staggered 0 0 0 
554 0.005 3.94 2.235 B e e staggered 0 0 0 
554 0.00985 4.00973 2.11902 T e e staggered 0 0 0 
555 0.005 4.205 2.295 B e e staggered 0 0 0 
555 0.00985 4.12784 2.11902 T e e staggered 0 0 0 
556 0.005 4.254 2.296 B e e staggered 0 0 0 
556 0.00985 4.12784 2.15839 T e e staggered 0 0 0 
557 0.005 4.768 1.207 B e e staggered 0 0 0 
557 0.00985 4.40343 1.4891 T e e staggered 0 0 0 
557 0.004 4.42311 1.46942 B m e staggered 0 0 0 v 
558 0.005 4.828 1.103 B e e staggered 0 0 0 
558 0.00985 4.40343 1.44973 T e e staggered 0 0 0 
558 0.004 4.42311 1.43005 B m e staggered 0 0 0 v 
559 0.005 4.15 1.235 B e e staggered 0 0 0 
559 0.00985 4.32469 1.52847 T e e staggered 0 0 0 
559 0.004 4.34437 1.50879 B m e staggered 0 0 0 v 
560 0.005 4.185 1.17 B e e staggered 0 0 0 
560 0.00985 4.32469 1.4891 T e e staggered 0 0 0 
560 0.004 4.34437 1.46942 B m e staggered 0 0 0 v 
561 0.005 4.83 1.33 B e e staggered 0 0 0 
561 0.00985 4.4428 1.33161 T e e staggered 0 0 0 
562 0.005 4.22 1.235 B e e staggered 0 0 0 
562 0.00985 4.40343 1.33161 T e e staggered 0 0 0 
563 0.005 4.816 1.258 B e e staggered 0 0 0 
563 0.00985 4.40343 1.37098 T e e staggered 0 0 0 
564 0.005 4.665 1.104 B e e staggered 0 0 0 
564 0.00985 4.36406 1.37098 T e e staggered 0 0 0 
564 0.004 4.38374 1.3513 B m e staggered 0 0 0 v 
565 0.005 4.712 1.157 B e e staggered 0 0 0 
565 0.00985 4.40343 1.52847 T e e staggered 0 0 0 
565 0.004 4.42311 1.50879 B m e staggered 0 0 0 v 
566 0.005 4.29 1.235 B e e staggered 0 0 0 
566 0.00985 4.36406 1.4891 T e e staggered 0 0 0 
566 0.004 4.38374 1.46942 B m e staggered 0 0 0 v 
567 0 0.894 3.35884 T 0.064 0.012 e e staggered 0 0 0 
567 0.005 0.78 3.305 B e e staggered 0 0 0 
568 0 0.894 3.26042 T 0.064 0.012 e e staggered 0 0 0 
568 0.005 0.795 3.085 B e e staggered 0 0 0 
569 0.005 3.385 2.135 B e e staggered 0 0 0 
569 0 3.39984 2.22296 T 0.01 0.023 e e staggered 0 0 0 
570 0 0.894 3.24073 T 0.064 0.012 e e staggered 0 0 0 
570 0.005 0.875 2.955 B e e staggered 0 0 0 
571 0.005 3.9 2.325 B e e staggered 0 0 0 
571 0.00985 3.97035 2.15839 T e e staggered 0 0 0 
572 0 0.894 3.20136 T 0.064 0.012 e e staggered 0 0 0 
572 0.005 0.885 3.03 B e e staggered 0 0 0 
573 0 0.97536 3.12 T 0.012 0.064 e e staggered 0 0 0 
573 0.005 0.945 2.99 B e e staggered 0 0 0 
574 0 4.1695 3.19439 T 0.062 0.014 e e staggered 0 0 0 
574 0 4.0355 3.71339 T 0.062 0.014 e e staggered 0 0 0 
574 0.005 4.09 3.71339 B m e staggered 0 0 0 v 
575 0 4.1695 3.11761 T 0.062 0.014 e e staggered 0 0 0 
575 0 4.0355 3.63661 T 0.062 0.014 e e staggered 0 0 0 
575 0.005 4.1184 3.5362 B m e staggered 0 0 0 v 
575 0.005 4.085 3.11 B m e staggered 0 0 0 v 
576 0 4.4085 3.09202 T 0.062 0.014 e e staggered 0 0 0 
576 0 4.2745 3.61102 T 0.062 0.014 e e staggered 0 0 0 
576 0.005 4.51 3.065 B m e staggered 0 0 0 v 
576 0.005 4.33382 3.60466 B m e staggered 0 0 0 v 
577 0 4.4085 3.1688 T 0.062 0.014 e e staggered 0 0 0 
577 0 4.2745 3.6878 T 0.062 0.014 e e staggered 0 0 0 
577 0.005 4.34 3.28 B m e staggered 0 0 0 v 
577 0.005 4.335 3.665 B m e staggered 0 0 0 v 

### steps/pcb/layers/backdrill_l09_gnd4_bottom/features
#
#Num Features
#
F 26

#
#Units
#
U INCH

#
#Feature symbol names
#
$0 r8

#
#Feature attribute names
#
@0 .pf_optimized
@1 .geometry

#
#Feature attribute text strings
#
&0 V008C018P
&1 V008C018P_ANTI28
&2 V008C018P_ANTI026_NSM

#
#Layer features
#
P 3.375 1.162 0 P 0 8 0;0,1=0
P 3.375 1.194 0 P 0 8 0;0,1=0
P 3.41798996 1.085 0 P 0 8 0;0,1=0
P 3.44998996 1.085 0 P 0 8 0;0,1=0
P 3.51463996 1.04706998 0 P 0 8 0;0,1=0
P 3.54663996 1.04706998 0 P 0 8 0;0,1=0
P 3.657 0.92 0 P 0 8 0;0,1=1
P 6.19961004 2.24473996 0 P 0 8 0;0,1=1
P 3.625 0.92 0 P 0 8 0;0,1=1
P 6.19961004 2.27673996 0 P 0 8 0;0,1=1
P 1.105 3.825 0 P 0 8 0;0,1=1
P 0.735 3.575 0 P 0 8 0;0,1=1
P 1.073 3.825 0 P 0 8 0;0,1=1
P 0.703 3.575 0 P 0 8 0;0,1=1
P 3.87193002 1.43005 0 P 0 8 0;0,1=2
P 3.9113 1.43005 0 P 0 8 0;0,1=2
P 3.95066998 1.46941998 0 P 0 8 0;0,1=2
P 3.99005 1.46941998 0 P 0 8 0;0,1=2
P 3.87193002 1.50878996 0 P 0 8 0;0,1=2
P 3.9113 1.50878996 0 P 0 8 0;0,1=2
P 3.95066998 1.54816004 0 P 0 8 0;0,1=2
P 3.99005 1.54816004 0 P 0 8 0;0,1=2
P 4.73806998 1.3513 0 P 0 8 0;0,1=2
P 4.73806998 1.39066998 0 P 0 8 0;0,1=2
P 4.73806998 1.46941998 0 P 0 8 0;0,1=2
P 4.6987 1.46941998 0 P 0 8 0;0,1=2

### steps/pcb/layers/backdrill_top_l07_gnd3/features
#
#Num Features
#
F 10

#
#Units
#
U INCH

#
#Feature symbol names
#
$0 r8

#
#Feature attribute names
#
@0 .pf_optimized
@1 .geometry

#
#Feature attribute text strings
#
&0 V008C018P
&1 V008C018P_ANTI28

#
#Layer features
#
P 2.40508002 0.699 0 P 0 8 0;0,1=0
P 2.40508002 0.731 0 P 0 8 0;0,1=0
P 2.50221998 0.763 0 P 0 8 0;0,1=1
P 2.47021998 0.763 0 P 0 8 0;0,1=1
P 2.69906998 0.763 0 P 0 8 0;0,1=1
P 2.66706998 0.763 0 P 0 8 0;0,1=1
P 2.85055 0.763 0 P 0 8 0;0,1=1
P 2.81855 0.763 0 P 0 8 0;0,1=1
P 3.14763002 0.85236998 0 P 0 8 0;0,1=1
P 3.125 0.875 0 P 0 8 0;0,1=1

### steps/pcb/layers/bottom/features
#
#Num Features
#
F 7788

#
#Units
#
U INCH

#
#Feature symbol names
#
$0 r3.6
$1 r3.9
$2 r4
$3 r4.7
$4 r5
$5 r5.7
$6 r6
$7 r8
$8 r10
$9 r12
$10 r15
$11 r18
$12 r20
$13 r24
$14 r25
$15 r30
$16 r40
$17 r57
$18 r86
$19 r90
$20 r100
$21 r104
$22 r108
$23 r115
$24 r198
$25 s104
$26 oval75x35 I
$27 oval75x48 I
$28 rect108x85 I
$29 rect13x38 I
$30 rect15x12 I
$31 rect20x47 I
$32 rect24x28 I
$33 rect24x5 I
$34 rect28x126 I
$35 rect28x165 I
$36 rect28x24 I
$37 rect30x34 I
$38 rect34x30 I
$39 rect38x54 I
$40 rect39x57 I
$41 rect43x57 I
$42 rect45x104 I
$43 rect54x38 I
$44 rect55x39 I
$45 rect5x24 I
$46 rect60x18 I
$47 rect65x20 I

#
#Feature attribute names
#
@0 .smd
@1 .test_point
@2 .nomenclature
@3 .geometry
@4 .string
@5 .pad_usage
@6 .string_angle

#
#Feature attribute text strings
#
&0 S028X024
&1 V010C020P_TP030B
&2 V008C018P-ANTI28-NSM
&3 V010C020P
&4 TPV010CT020B030
&5 V008C018P_ANTI026_TP030B
&6 V008C018P_NATI28_TP030B_NSMT
&7 016C024P
&8 S030X034
&9 S020X065
&10 V008C018P_TP030B
&11 V008C018P
&12 S038X054
&13 V008C018P_ANTI28
&14 TP030C_B
&15 S057X039
&16 059C086P
&17 S039X055
&18 S018X060
&19 S025C
&20 S020X047
&21 S045X104
&22 S013X038
&23 S005X024_V3_NSM
&24 S012X015
&25 V008C018P_ANTI026_NSM
&26 076S104P
&27 076C104P
&28 S085X108
&29 079C100P
&30 EFB028X165
&31 V010C020P_SM014-NTH
&32 V012C024-NTH
&33 024X063OB035X075P
&34 166CT244CB198P
&35 S057X043
&36 024X051OB071X075P_R
&37 024X051OB071X075P_L
&38 033C057P
&39 063C090P
&40 EFB028X126
&41 BOTTOM
&42 FID040
&43 MTH100C090N
&44 MTH125C115N
&45 MTH118C108N
&46 P/N : R4006-B0001-02
&47 Date: 2022-02-25
&48 Layer:
&49 Rev : 01

#
#Layer features
#
S P 0
OB 2.805669980315 1.121430019685 I
OC 2.805669980315 1.121430019685 2.685669980315 1.121430019685 Y
OE
OB 2.748169980315 1.121430019685 H
OC 2.748169980315 1.121430019685 2.685669980315 1.121430019685 N
OE
SE
P 4.266 4.065 36 P 0 8 0;0,3=0,5=0
L 4.266 4.065 4.31 4.065 3 P 0 
P 4.354 4.065 36 P 0 8 0;0,3=0,5=0
L 4.354 4.065 4.31 4.065 3 P 0 
P 4.31 4.065 15 P 0 8 0;1,3=1,5=1
P 4.266 4.115 36 P 0 8 0;0,3=0,5=0
L 4.266 4.115 4.31 4.115 3 P 0 
P 4.354 4.115 36 P 0 8 0;0,3=0,5=0
L 4.354 4.115 4.31 4.115 3 P 0 
P 4.31 4.115 15 P 0 8 0;1,3=1,5=1
P 4.61 2.3 15 P 0 8 0;1,3=1,5=1
P 4.50185 2.05996004 11 P 0 8 0;3=2,5=1
P 4.49 2.275 15 P 0 8 0;1,3=1,5=1
P 4.435 2.315 15 P 0 8 0;1,3=1,5=1
P 4.49 2.325 15 P 0 8 0;1,3=1,5=1
P 4.435 2.365 15 P 0 8 0;1,3=1,5=1
P 3.655 2.465 15 P 0 8 0;1,3=1,5=1
P 3.125 1.605 15 P 0 8 0;1,3=1,5=1
P 3.65 2.68 12 P 0 8 0;3=3,5=1
P 3.12 2.645 12 P 0 8 0;3=3,5=1
P 4.1869 2.09933002 11 P 0 8 0;3=2,5=1
P 3.765 2.69 15 P 0 8 0;1,3=1,5=1
P 4.50185 1.50878996 11 P 0 8 0;3=2,5=1
P 4.3 3.865 15 P 0 8 0;1,3=4,5=0
P 4.354 3.865 36 P 0 8 0;0,3=0,5=0
L 4.3 3.865 4.273 3.892 3 P 0 
L 4.273 3.892 4.273 3.908 3 P 0 
L 4.273 3.908 4.24 3.941 3 P 0 
P 4.24 3.941 32 P 0 8 0;0,3=0,5=0
L 4.354 3.865 4.3 3.865 3 P 0 
L 3.37 3.44 3.37 3.30975 3 P 0 
L 3.37 3.30975 3.36525 3.305 3 P 0 
P 3.36525 3.305 15 P 0 8 0;1,3=5,5=1
L 3.298 3.475 3.335 3.475 3 P 0 
L 3.335 3.475 3.37 3.44 3 P 0 
P 3.37 3.44 15 P 0 8 0;3=4,5=0
L 3.298 3.43 3.298 3.385 3 P 0 
P 3.298 3.385 36 P 0 8 0;0,3=0,5=0
P 3.298 3.475 36 P 0 8 0;0,3=0,5=0
L 3.298 3.475 3.298 3.43 3 P 0 
P 3.298 3.43 36 P 0 8 0;0,3=0,5=0
L 4.795 0.925 4.785 0.915 3 P 0 
L 4.785 0.915 4.736 0.915 3 P 0 
L 4.736 0.915 4.736 0.965 3 P 0 
P 4.795 0.925 15 P 0 8 0;1,3=4,5=0
P 4.736 0.965 36 P 0 8 0;0,3=0,5=0
P 4.736 0.915 36 P 0 8 0;0,3=0,5=0
L 4.015 3.291 4.059 3.291 3 P 0 
L 4.059 3.291 4.08 3.27 3 P 0 
P 4.08 3.27 15 P 0 8 0;1,3=4,5=0
P 4.015 3.291 36 P 0 8 0;0,3=0,5=0
L 4.015 3.239 4.015 3.291 3 P 0 
P 4.015 3.239 36 P 0 8 0;0,3=0,5=0
L 3.881 3.81 3.94 3.81 3 P 0 
L 3.94 3.81 3.95 3.82 3 P 0 
P 3.95 3.82 15 P 0 8 0;1,3=4,5=0
P 3.881 3.81 36 P 0 8 0;0,3=0,5=0
L 3.881 3.758 3.881 3.81 3 P 0 
P 3.881 3.758 36 P 0 8 0;0,3=0,5=0
P 3.746 1.72 36 P 0 8 0;0,3=0,5=0
L 3.746 1.72 3.746 1.782 3 P 0 
P 3.746 1.782 15 P 0 8 0;1,3=4,5=0
P 4.06878996 1.58753002 11 P 0 8 0;3=2,5=1
P 4.205 0.82 15 P 0 8 0;1,3=4,5=0
P 3.82286004 0.86213996 15 P 0 8 0;1,3=1,5=1
P 3.705 0.84 15 P 0 8 0;3=4,5=0
L 0.496 2.13455 0.496 2.10063996 3 P 0 
L 0.496 2.10063996 0.50563996 2.091 3 P 0 
L 0.50563996 2.091 0.53 2.091 3 P 0 
P 0.496 2.13455 15 P 0 8 0;1,3=1,5=1
P 0.53 2.091 32 P 0 8 0;0,3=0,5=0
L 0.53 2.626 0.5188 2.6372 3 P 0 
L 0.5188 2.6372 0.5188 2.7108 3 P 0 
L 0.5188 2.7108 0.528 2.72 3 P 0 
P 0.528 2.72 15 P 0 8 0;1,3=1,5=1
P 0.53 2.626 32 P 0 8 0;0,3=0,5=0
L 0.575 1.015 0.555 0.995 3 P 0 
L 0.555 0.995 0.555 0.946 3 P 0 
L 0.555 0.946 0.535 0.926 3 P 0 
P 0.535 0.926 32 P 0 8 0;0,3=0,5=0
P 0.575 1.015 15 P 0 8 0;1,3=1,5=1
L 0.48956998 1.53618996 0.48956998 1.52643002 3 P 0 
L 0.48956998 1.52643002 0.53 1.486 3 P 0 
P 0.53 1.486 32 P 0 8 0;0,3=0,5=0
P 0.48956998 1.53618996 15 P 0 8 0;1,3=1,5=1
P 4.65933002 1.98121998 11 P 0 8 0;3=2,5=1
P 4.06878996 1.90248002 11 P 0 8 0;3=2,5=1
P 4.50185 1.39066998 11 P 0 8 0;3=2,5=1
P 4.06878996 2.1387 11 P 0 8 0;3=2,5=1
P 4.22626998 2.05996004 11 P 0 8 0;3=2,5=1
P 3.95066998 2.05996004 11 P 0 8 0;3=2,5=1
P 4.22626998 2.02058996 11 P 0 8 0;3=2,5=1
P 4.26563996 2.09933002 11 P 0 8 0;3=2,5=1
P 4.26563996 2.05996004 11 P 0 8 0;3=2,5=1
P 4.50185 1.90248002 11 P 0 8 0;3=2,5=1
P 4.73806998 2.09933002 11 P 0 8 0;3=2,5=1
P 4.02941998 2.02058996 11 P 0 8 0;3=2,5=1
P 4.50185 1.86311004 11 P 0 8 0;3=2,5=1
P 4.6987 2.05996004 11 P 0 8 0;3=2,5=1
P 4.61996004 1.94185 11 P 0 8 0;3=2,5=1
P 4.61996004 1.98121998 11 P 0 8 0;3=2,5=1
P 4.26563996 2.02058996 11 P 0 8 0;3=2,5=1
P 4.61996004 1.90248002 11 P 0 8 0;3=2,5=1
P 4.58058996 1.98121998 11 P 0 8 0;3=2,5=1
P 4.54121998 2.02058996 11 P 0 8 0;3=2,5=1
P 4.34436998 2.09933002 11 P 0 8 0;3=2,5=1
P 4.06878996 2.09933002 15 P 0 8 0;1,3=6,5=1
P 4.6987 1.50878996 11 P 0 8 0;3=2,5=1
P 4.54121998 1.98121998 11 P 0 8 0;3=2,5=1
P 4.06878996 2.05996004 11 P 0 8 0;3=2,5=1
P 4.65933002 1.50878996 11 P 0 8 0;3=2,5=1
P 3.95066998 2.09933002 11 P 0 8 0;3=2,5=1
P 4.61996004 1.54816004 11 P 0 8 0;3=2,5=1
P 3.99005 2.09933002 15 P 0 8 0;1,3=6,5=1
P 4.58058996 1.54816004 11 P 0 8 0;3=2,5=1
P 4.6987 1.94185 11 P 0 8 0;3=2,5=1
P 4.50185 2.02058996 11 P 0 8 0;3=2,5=1
P 4.46248002 2.02058996 11 P 0 8 0;3=2,5=1
P 4.42311004 1.98121998 11 P 0 8 0;3=2,5=1
P 4.46248002 1.94185 11 P 0 8 0;3=2,5=1
P 4.38373996 1.86311004 11 P 0 8 0;3=2,5=1
P 4.38373996 1.82373996 11 P 0 8 0;3=2,5=1
P 4.46248002 1.98121998 11 P 0 8 0;3=2,5=1
P 4.10816004 1.94185 11 P 0 8 0;3=2,5=1
P 4.02941998 1.98121998 11 P 0 8 0;3=2,5=1
P 4.58058996 2.17806998 11 P 0 8 0;3=2,5=1
P 4.73806998 1.90248002 11 P 0 8 0;3=2,5=1
P 4.54121998 2.1387 11 P 0 8 0;3=2,5=1
P 4.10816004 2.02058996 11 P 0 8 0;3=2,5=1
P 4.50185 2.1387 11 P 0 8 0;3=2,5=1
P 3.99005 1.94185 11 P 0 8 0;3=2,5=1
P 4.02941998 1.94185 11 P 0 8 0;3=2,5=1
P 4.50185 2.09933002 11 P 0 8 0;3=2,5=1
P 4.14753002 2.02058996 11 P 0 8 0;3=2,5=1
P 4.61996004 2.17806998 11 P 0 8 0;3=2,5=1
P 4.02941998 1.86311004 11 P 0 8 0;3=2,5=1
P 4.06878996 1.43005 11 P 0 8 0;3=2,5=1
P 4.54121998 1.54816004 11 P 0 8 0;3=2,5=1
P 4.26563996 1.50878996 11 P 0 8 0;3=2,5=1
P 4.1869 1.94185 11 P 0 8 0;3=2,5=1
P 4.14753002 1.46941998 11 P 0 8 0;3=2,5=1
P 4.1869 1.46941998 11 P 0 8 0;3=2,5=1
P 4.1869 2.1387 11 P 0 8 0;3=2,5=1
P 4.6987 1.43005 11 P 0 8 0;3=2,5=1
P 4.10816004 1.39066998 11 P 0 8 0;3=2,5=1
P 4.65933002 1.43005 11 P 0 8 0;3=2,5=1
P 4.14753002 1.39066998 11 P 0 8 0;3=2,5=1
P 4.61996004 1.43005 11 P 0 8 0;3=2,5=1
P 4.10816004 1.43005 11 P 0 8 0;3=2,5=1
P 4.58058996 1.43005 11 P 0 8 0;3=2,5=1
P 4.14753002 1.43005 11 P 0 8 0;3=2,5=1
P 4.1869 1.43005 11 P 0 8 0;3=2,5=1
P 4.22626998 1.43005 11 P 0 8 0;3=2,5=1
P 4.54121998 1.46941998 11 P 0 8 0;3=2,5=1
P 4.22626998 1.39066998 11 P 0 8 0;3=2,5=1
P 4.50185 1.46941998 11 P 0 8 0;3=2,5=1
P 4.26563996 1.39066998 11 P 0 8 0;3=2,5=1
P 4.61996004 1.46941998 11 P 0 8 0;3=2,5=1
P 4.26563996 1.31193002 11 P 0 8 0;3=2,5=1
P 4.61996004 1.50878996 11 P 0 8 0;3=2,5=1
P 4.34436998 1.31193002 11 P 0 8 0;3=2,5=1
P 4.58058996 1.46941998 11 P 0 8 0;3=2,5=1
P 4.34436998 1.3513 11 P 0 8 0;3=2,5=1
P 4.54121998 1.50878996 11 P 0 8 0;3=2,5=1
P 4.34436998 1.39066998 11 P 0 8 0;3=2,5=1
P 4.1869 1.50878996 11 P 0 8 0;3=2,5=1
P 4.46248002 1.50878996 11 P 0 8 0;3=2,5=1
P 4.22626998 1.50878996 11 P 0 8 0;3=2,5=1
P 4.26563996 1.43005 15 P 0 8 0;1,3=6,5=1
P 4.26563996 1.46941998 11 P 0 8 0;3=2,5=1
P 4.38373996 1.39066998 11 P 0 8 0;3=2,5=1
P 4.38373996 1.43005 11 P 0 8 0;3=2,5=1
P 4.54121998 1.31193002 11 P 0 8 0;3=2,5=1
P 4.49876004 1.31501998 11 P 0 8 0;3=2,5=1
P 4.34436998 1.98121998 11 P 0 8 0;3=2,5=1
P 4.57843996 1.35345 11 P 0 8 0;3=2,5=1
P 3.9113 1.3513 11 P 0 8 0;3=2,5=1
P 4.54121998 1.3513 11 P 0 8 0;3=2,5=1
P 3.95066998 1.3513 11 P 0 8 0;3=2,5=1
P 4.45938996 1.35438996 11 P 0 8 0;3=2,5=1
P 3.99 1.31188002 11 P 0 8 0;3=2,5=1
P 4.46248002 1.39066998 11 P 0 8 0;3=2,5=1
P 4.65933002 1.3513 11 P 0 8 0;3=2,5=1
P 3.99 1.35125 11 P 0 8 0;3=2,5=1
P 4.61996004 1.3513 11 P 0 8 0;3=2,5=1
P 4.6987 1.86311004 11 P 0 8 0;3=2,5=1
P 4.46248002 2.05996004 11 P 0 8 0;3=2,5=1
P 4.06873996 1.31188002 11 P 0 8 0;3=2,5=1
P 4.65933002 1.82373996 11 P 0 8 0;3=2,5=1
P 4.42311004 2.05996004 11 P 0 8 0;3=2,5=1
P 4.10811004 1.31188002 11 P 0 8 0;3=2,5=1
P 4.58058996 1.39066998 11 P 0 8 0;3=2,5=1
P 4.02941998 1.39066998 11 P 0 8 0;3=2,5=1
P 4.54121998 1.39066998 11 P 0 8 0;3=2,5=1
P 4.06878996 1.39066998 11 P 0 8 0;3=2,5=1
P 4.73806998 1.78436998 11 P 0 8 0;3=2,5=1
P 4.73806998 1.31193002 11 P 0 8 0;3=2,5=1
P 4.1869 1.31193002 11 P 0 8 0;3=2,5=1
P 4.73806998 1.70563996 11 P 0 8 0;3=2,5=1
P 4.6987 1.31193002 11 P 0 8 0;3=2,5=1
P 4.22626998 1.31193002 11 P 0 8 0;3=2,5=1
P 4.10816004 1.3513 11 P 0 8 0;3=2,5=1
P 4.14753002 1.3513 11 P 0 8 0;3=2,5=1
P 4.6987 1.39066998 11 P 0 8 0;3=2,5=1
P 4.1869 1.3513 11 P 0 8 0;3=2,5=1
P 4.65933002 1.39066998 11 P 0 8 0;3=2,5=1
P 4.22626998 1.3513 11 P 0 8 0;3=2,5=1
P 4.73806998 2.17806998 11 P 0 8 0;3=2,5=1
P 4.73806998 2.1387 11 P 0 8 0;3=2,5=1
P 4.58058996 2.09933002 11 P 0 8 0;3=2,5=1
P 4.54121998 2.09933002 11 P 0 8 0;3=2,5=1
P 4.58058996 1.86311004 11 P 0 8 0;3=2,5=1
P 4.65933002 2.05996004 11 P 0 8 0;3=2,5=1
P 4.58058996 2.05996004 11 P 0 8 0;3=2,5=1
P 4.54121998 1.90248002 11 P 0 8 0;3=2,5=1
P 4.58058996 2.02058996 11 P 0 8 0;3=2,5=1
P 4.22626998 1.98121998 11 P 0 8 0;3=2,5=1
P 4.26563996 1.94185 11 P 0 8 0;3=2,5=1
P 4.10816004 1.98121998 11 P 0 8 0;3=2,5=1
P 4.14753002 1.98121998 11 P 0 8 0;3=2,5=1
P 4.61996004 2.1387 11 P 0 8 0;3=2,5=1
P 4.6987 1.70563996 11 P 0 8 0;3=2,5=1
P 4.6987 1.66626998 11 P 0 8 0;3=2,5=1
L 1.45 3.59 1.45 3.635 10 P 0 
L 1.45 3.635 1.4075 3.6775 10 P 0 
L 1.4075 3.6775 1.2786 3.6775 10 P 0 
L 1.2786 3.6775 1.245 3.7111 10 P 0 
L 1.245 3.7111 1.245 3.725 10 P 0 
L 1.245 3.725 1.225 3.745 10 P 0 
L 1.225 3.745 1.165 3.745 10 P 0 
L 1.165 3.745 1.151 3.731 10 P 0 
L 1.151 3.731 1.055 3.731 10 P 0 
P 1.055 3.731 32 P 0 8 0;0,3=0,5=0
P 1.45 3.59 15 P 0 8 0;1,3=1,5=1
P 1.56 3.165 12 P 0 8 0;3=3,5=1
P 1.56 3.205 15 P 0 8 0;1,3=1,5=1
P 0.7 3.426 32 P 0 8 0;0,3=0,5=0
L 0.7 3.426 0.7 3.443 10 P 0 
L 0.7 3.443 0.72 3.463 10 P 0 
P 0.72 3.463 12 P 0 8 0;3=3,5=1
P 0.42326004 3.4315 13 P 0 8 0;3=7,5=0
P 0.40553996 3.4008 13 P 0 8 0;3=7,5=0
P 0.2815 3.4315 13 P 0 8 0;3=7,5=0
P 0.26378002 3.4008 13 P 0 8 0;3=7,5=0
P 0.71 3.305 15 P 0 8 0;1,3=4,5=0
S P 0
OB 1.097 3.571980019685 I
OC 1.1075 3.57496003937 1.096991633858 3.591997637795 N
OC 1.118 3.571980019685 1.118008366142 3.591997637795 N
OS 1.142980019685 3.571980019685
OS 1.142980019685 3.55
OC 1.145 3.54125 1.162997047244 3.550012893701 N
OS 1.145 3.515
OS 1.13676003937 3.50676003937
OS 1.13616003937 3.50663996063
OC 1.131280019685 3.505019980315 1.139973720472 3.486991338583 N
OS 1.11671003937 3.505019980315
OS 1.10671003937 3.495019980315
OS 1.074980019685 3.495019980315
OS 1.07 3.5
OS 1.07 3.54125
OC 1.072019980315 3.55 1.052002952756 3.550012893701 N
OS 1.072019980315 3.571980019685
OS 1.097 3.571980019685
OE
SE
P 1.085 3.564 32 P 0 8 0;0,3=0,5=0
P 1.13 3.564 32 P 0 8 0;0,3=0,5=0
P 1.09 3.512 38 P 0 8 0;0,3=8,5=0
P 1.14 3.52 15 P 0 8 0;1,3=1,5=1
L 1.245 3.52 1.22 3.545 10 P 0 
L 1.22 3.545 1.22 3.564 10 P 0 
L 1.22 3.564 1.265 3.564 10 P 0 
L 1.265 3.564 1.265 3.563 10 P 0 
L 1.265 3.563 1.28 3.548 10 P 0 
L 1.28 3.548 1.32 3.548 10 P 0 
P 1.245 3.52 15 P 0 8 0;1,3=1,5=1
P 1.22 3.564 32 P 0 8 0;0,3=0,5=0
P 1.265 3.564 32 P 0 8 0;0,3=0,5=0
P 1.32 3.548 38 P 0 8 0;0,3=8,5=0
S P 0
OB 4.65 3.975 I
OS 4.725 3.975
OS 4.735 3.965
OS 4.735 3.89
OS 4.73 3.885
OS 4.648019980315 3.885
OS 4.648019980315 3.907
OC 4.64503996063 3.9175 4.628002362205 3.906991633858 N
OC 4.648019980315 3.928 4.628002362205 3.928008366142 N
OS 4.648019980315 3.952
OC 4.645269980315 3.96211003937 4.628004232283 3.951984645669 N
OS 4.645 3.962580019685
OS 4.645 3.97
OS 4.65 3.975
OE
SE
P 4.705 3.95 15 P 0 8 0;1,3=5,5=1
P 4.778 3.551 36 P 0 8 0;0,3=0,5=0
L 4.778 3.551 4.778 3.837 8 P 0 
L 4.778 3.837 4.705 3.91 8 P 0 
P 4.705 3.91 12 P 0 8 0;3=3,5=1
P 4.656 3.895 36 P 0 8 0;0,3=0,5=0
P 4.656 3.94 36 P 0 8 0;0,3=0,5=0
L 1.045 3.77 1.04735 3.76765 3 P 0 
L 1.04735 3.76765 1.27573996 3.76765 3 P 0 
L 1.27573996 3.76765 1.31073996 3.73265 3 P 0 
L 1.31073996 3.73265 1.34765 3.73265 3 P 0 
L 1.34765 3.73265 1.365 3.75 3 P 0 
L 1.365 3.75 1.42 3.75 3 P 0 
L 1.42 3.75 1.435 3.735 3 P 0 
L 1.435 3.735 1.435 3.7 3 P 0 
L 1.435 3.7 1.455 3.68 3 P 0 
L 1.455 3.68 1.465 3.68 3 P 0 
L 1.465 3.68 1.48 3.665 3 P 0 
L 1.48 3.665 1.52 3.665 3 P 0 
L 1.52 3.665 1.56 3.625 3 P 0 
L 1.56 3.625 1.56 3.365 3 P 0 
L 1.56 3.365 1.605 3.32 3 P 0 
L 1.605 3.32 1.605 2.989 3 P 0 
L 1.605 2.989 1.566 2.95 3 P 0 
P 1.566 2.95 15 P 0 8 0;1,3=1,5=1
P 1.045 3.77 12 P 0 8 0;3=3,5=1
P 1.515 3.58 12 P 0 8 0;3=3,5=1
L 6.145 4.094 6.145 4.035 10 P 0 
P 6.145 4.035 15 P 0 8 0;1,3=1,5=1
P 6.145 4.094 32 P 0 8 0;0,3=0,5=0
L 1.37 3.64 1.375 3.635 10 P 0 
L 1.375 3.635 1.375 3.601 10 P 0 
L 1.32 3.602 1.321 3.601 10 P 0 
L 1.321 3.601 1.375 3.601 10 P 0 
P 1.37 3.64 12 P 0 8 0;3=3,5=1
P 1.32 3.602 38 P 0 8 0;0,3=8,5=0
P 1.375 3.601 32 P 0 8 0;0,3=0,5=0
P 1.667 3.438 12 P 0 8 0;3=3,5=1
L 1.7485 3.438 1.667 3.438 10 P 0 
P 1.7485 3.438 47 P 0 8 0;0,3=9,5=0
P 1.591 3.546 12 P 0 8 0;3=3,5=1
L 1.63 3.546 1.591 3.546 10 P 0 
P 1.7485 3.538 47 P 0 8 0;0,3=9,5=0
L 1.7485 3.538 1.638 3.538 10 P 0 
L 1.638 3.538 1.63 3.546 10 P 0 
P 1.63 3.546 32 P 0 8 0;0,3=0,5=0
S P 0
OB 1.141180019685 3.485 I
OS 1.155 3.485
OS 1.161980019685 3.47801003937
OS 1.161980019685 3.463
OC 1.165 3.45243996063 1.181996456693 3.4630125 N
OS 1.165 3.44
OS 1.155 3.43
OS 1.07 3.43
OS 1.06 3.44
OS 1.06 3.45168996063
OC 1.07018996063 3.473080019685 1.040190748031 3.474249015748 N
OS 1.07026003937 3.475
OS 1.115 3.475
OS 1.125 3.485
OS 1.13885 3.485
OC 1.14 3.484980019685 1.140033267717 3.519999409449 N
OC 1.14115 3.485 1.139966732283 3.519999409449 N
OS 1.141180019685 3.485
OE
SE
P 1.13 3.445 12 P 0 8 0;3=3,5=1
P 1.09 3.458 38 P 0 8 0;0,3=8,5=0
P 1.154 3.475 36 P 0 8 0;0,3=0,5=0
L 0.911 3.455 0.94 3.455 10 P 0 
L 0.94 3.455 0.95 3.445 10 P 0 
P 0.95 3.445 12 P 0 8 0;3=3,5=1
P 0.911 3.455 36 P 0 8 0;0,3=0,5=0
L 2.146 3.36 2.164 3.36 10 P 0 
L 2.164 3.36 2.192 3.388 10 P 0 
L 2.146 3.5 2.15 3.504 10 P 0 
L 2.15 3.504 2.15 3.546 10 P 0 
L 2.15 3.546 2.146 3.55 10 P 0 
L 2.19 3.488 2.158 3.488 10 P 0 
L 2.158 3.488 2.146 3.5 10 P 0 
P 2.146 3.36 36 P 0 8 0;0,3=0,5=0
P 2.146 3.55 36 P 0 8 0;0,3=0,5=0
P 2.19 3.488 12 P 0 8 0;3=3,5=1
P 2.146 3.5 36 P 0 8 0;0,3=0,5=0
P 2.192 3.388 12 P 0 8 0;3=3,5=1
P 1.41916004 3.33916004 12 P 0 8 0;3=3,5=1
L 1.381 3.235 1.407 3.209 10 P 0 
L 1.407 3.209 1.407 3.2 10 P 0 
P 1.407 3.2 12 P 0 8 0;3=3,5=1
P 1.381 3.235 36 P 0 8 0;0,3=0,5=0
P 1.495 3.11033996 12 P 0 8 0;3=3,5=1
P 1.535 3.105 15 P 0 8 0;1,3=4,5=0
P 1.15253002 3.06246998 12 P 0 8 0;3=3,5=1
P 0.95 3.215 12 P 0 8 0;3=3,5=1
L 0.746 3.2 0.87 3.2 11 P 0 
L 0.87 3.2 0.945 3.125 11 P 0 
P 0.945 3.125 12 P 0 8 0;3=3,5=1
L 0.746 3.2 0.746 3.245 11 P 0 
P 0.746 3.245 36 P 0 8 0;0,3=0,5=0
P 0.746 3.2 36 P 0 8 0;0,3=0,5=0
P 1.175 2.9 12 P 0 8 0;3=3,5=1
P 1.025 3.02 12 P 0 8 0;3=3,5=1
P 5.275 3.891 15 P 0 8 0;1,3=1,5=1
P 5.275 3.931 12 P 0 8 0;3=3,5=1
P 5.275 3.971 15 P 0 8 0;1,3=1,5=1
P 5.321 3.99 12 P 0 8 0;3=3,5=1
S P 0
OB 5.517 3.483 I
OS 5.622030019685 3.483
OC 5.625919980315 3.478080019685 5.622029625984 3.479001870079 Y
OC 5.624980019685 3.47 5.660002362205 3.470020472441 N
OC 5.65053996063 3.436280019685 5.660002559055 3.47 N
OS 5.652 3.435869980315
OS 5.652 3.1795
OS 5.634 3.1615
OS 5.5175 3.1615
OS 5.506 3.173
OS 5.506 3.262980019685
OS 5.507019980315 3.262980019685
OS 5.507019980315 3.313019980315
OS 5.506 3.313019980315
OS 5.506 3.338980019685
OS 5.507019980315 3.338980019685
OS 5.507019980315 3.389019980315
OS 5.506 3.389019980315
OS 5.506 3.415980019685
OS 5.507019980315 3.415980019685
OS 5.507019980315 3.466019980315
OS 5.506 3.466019980315
OS 5.506 3.472
OS 5.517 3.483
OE
SE
P 5.762 3.425 15 P 0 8 0;3=10,5=1
P 5.567 3.203 12 P 0 8 0;3=3,5=1
P 5.617 3.203 15 P 0 8 0;1,3=1,5=1
P 5.62 3.316 12 P 0 8 0;3=3,5=1
P 5.625 3.261 15 P 0 8 0;1,3=1,5=1
P 5.625 3.361 12 P 0 8 0;3=3,5=1
P 5.6 3.421 15 P 0 8 0;1,3=1,5=1
P 5.552 3.71141004 11 P 0 8 0;3=11,5=1
P 5.552 3.74683996 11 P 0 8 0;3=11,5=1
P 5.552 3.78226998 11 P 0 8 0;3=11,5=1
P 5.552 3.67596998 11 P 0 8 0;3=11,5=1
P 5.527 3.206 39 P 0 8 0;0,3=12,5=0
P 5.531 3.364 39 P 0 8 0;0,3=12,5=0
P 5.531 3.288 39 P 0 8 0;0,3=12,5=0
P 5.531 3.441 39 P 0 8 0;0,3=12,5=0
P 5.52 3.78226998 11 P 0 8 0;3=11,5=1
P 5.52 3.74683996 11 P 0 8 0;3=11,5=1
P 5.52 3.71141004 11 P 0 8 0;3=11,5=1
P 5.52 3.67596998 11 P 0 8 0;3=11,5=1
P 0.978 3.918 15 P 0 8 0;3=4,5=0
P 0.928 3.961 12 P 0 8 0;3=3,5=1
P 0.968 3.961 12 P 0 8 0;3=3,5=1
P 0.968 4.021 12 P 0 8 0;3=3,5=1
P 0.928 4.021 15 P 0 8 0;3=1,5=1
P 0.928 4.081 12 P 0 8 0;3=3,5=1
P 0.968 4.081 15 P 0 8 0;3=1,5=1
P 0.928 4.141 15 P 0 8 0;3=1,5=1
P 0.968 4.141 12 P 0 8 0;3=3,5=1
P 0.603 3.951 15 P 0 8 0;3=1,5=1
P 0.643 3.956 12 P 0 8 0;3=3,5=1
P 0.603 4.011 12 P 0 8 0;3=3,5=1
P 0.643 4.016 15 P 0 8 0;3=1,5=1
P 0.603 4.071 15 P 0 8 0;3=1,5=1
P 0.643 4.076 12 P 0 8 0;3=3,5=1
P 0.603 4.131 12 P 0 8 0;3=3,5=1
P 0.643 4.136 15 P 0 8 0;3=1,5=1
P 0.854 3.942 12 P 0 8 0;3=3,5=1
P 0.807 3.942 12 P 0 8 0;3=3,5=1
P 0.76 3.942 12 P 0 8 0;3=3,5=1
P 0.713 3.942 12 P 0 8 0;3=3,5=1
P 0.76 4.042 12 P 0 8 0;3=3,5=1
P 0.76 3.992 12 P 0 8 0;3=3,5=1
P 0.713 3.992 12 P 0 8 0;3=3,5=1
P 0.713 4.042 12 P 0 8 0;3=3,5=1
P 0.713 4.092 12 P 0 8 0;3=3,5=1
P 0.76 4.092 12 P 0 8 0;3=3,5=1
P 0.807 4.092 12 P 0 8 0;3=3,5=1
P 0.807 4.042 12 P 0 8 0;3=3,5=1
P 0.807 3.992 12 P 0 8 0;3=3,5=1
P 0.854 3.992 12 P 0 8 0;3=3,5=1
P 0.854 4.042 12 P 0 8 0;3=3,5=1
P 0.854 4.092 12 P 0 8 0;3=3,5=1
L 0.74 1.005 0.743 1.002 3 P 0 
L 0.743 1.002 0.743 0.953 3 P 0 
L 0.743 0.953 0.698 0.953 3 P 0 
P 0.698 0.953 32 P 0 8 0;0,3=0,5=0
P 0.743 0.953 32 P 0 8 0;0,3=0,5=0
P 0.74 1.005 15 P 0 8 0;1,3=1,5=1
L 0.79 1.005 0.788 1.003 3 P 0 
L 0.788 1.003 0.788 0.953 3 P 0 
P 0.79 1.005 15 P 0 8 0;1,3=1,5=1
P 0.833 0.953 32 P 0 8 0;0,3=0,5=0
L 0.833 0.953 0.788 0.953 3 P 0 
P 0.788 0.953 32 P 0 8 0;0,3=0,5=0
L 0.878 0.953 0.907 0.953 3 P 0 
L 0.907 0.953 0.94 0.92 3 P 0 
L 0.94 0.92 1.035 0.92 3 P 0 
L 1.035 0.92 1.1163 0.8387 3 P 0 
L 1.1163 0.8387 1.1163 0.832 3 P 0 
L 1.1163 0.832 1.1583 0.79 3 P 0 
L 1.1583 0.79 1.3413 0.79 3 P 0 
L 1.3413 0.79 1.351 0.7803 3 P 0 
L 1.351 0.7803 1.351 0.753 3 P 0 
L 0.84 1.005 0.862 1.005 3 P 0 
L 0.862 1.005 0.878 0.989 3 P 0 
L 0.878 0.989 0.878 0.953 3 P 0 
P 0.84 1.005 15 P 0 8 0;1,3=1,5=1
P 0.878 0.953 32 P 0 8 0;0,3=0,5=0
P 1.351 0.753 36 P 0 8 0;0,3=0,5=0
P 1.521 3 36 P 0 8 0;0,3=0,5=0
L 1.521 3 1.557 3 3 P 0 
L 1.557 3 1.568 3.011 3 P 0 
P 1.568 3.011 15 P 0 8 0;1,3=1,5=1
P 1.738 3.241 15 P 0 8 0;1,3=1,5=1
P 1.765 2.9 15 P 0 8 0;1,3=1,5=1
P 1.78 3.095 15 P 0 8 0;1,3=1,5=1
L 1.885 2.939 1.802 2.939 3 P 0 
L 1.802 2.939 1.795 2.946 3 P 0 
P 1.885 2.939 32 P 0 8 0;0,3=0,5=0
P 1.795 2.946 15 P 0 8 0;1,3=1,5=1
P 5.2 0.87 15 P 0 8 0;1,3=1,5=1
P 4.47 3.21998002 15 P 0 8 0;1,3=1,5=1
P 4.385 3.645 15 P 0 8 0;1,3=1,5=1
P 0.78 3.305 15 P 0 8 0;1,3=4,5=0
L 1.03 3.515 1.04 3.525 3 P 0 
L 1.04 3.525 1.04 3.564 3 P 0 
P 1.04 3.564 32 P 0 8 0;0,3=0,5=0
P 1.03 3.515 15 P 0 8 0;1,3=1,5=1
L 1.19 3.52 1.175 3.535 3 P 0 
L 1.175 3.535 1.175 3.564 3 P 0 
P 1.175 3.564 32 P 0 8 0;0,3=0,5=0
P 1.19 3.52 15 P 0 8 0;1,3=1,5=1
P 0.95 2.915 15 P 0 8 0;1,3=4,5=0
P 0.945 2.99 15 P 0 8 0;1,3=4,5=0
P 0.885 3.03 15 P 0 8 0;1,3=4,5=0
P 0.875 2.955 15 P 0 8 0;1,3=4,5=0
P 0.795 3.085 15 P 0 8 0;1,3=4,5=0
P 0.55 3.36 15 P 0 8 0;1,3=1,5=1
P 0.3701 3.4008 13 P 0 8 0;3=7,5=0
L 0.55 3.554 0.55 3.522 2 P 0 
L 0.55 3.522 0.498 3.47 2 P 0 
L 0.498 3.47 0.345 3.47 2 P 0 
L 0.345 3.47 0.31693996 3.44193996 2 P 0 
L 0.31693996 3.44193996 0.31693996 3.4315 2 P 0 
P 0.55 3.554 15 P 0 8 0;1,3=1,5=1
P 0.31693996 3.4315 13 P 0 8 0;3=7,5=0
L 5.92 1.57063002 5.93036998 1.581 3 P 0 
L 5.93036998 1.581 5.98 1.581 3 P 0 
P 5.98 1.581 32 P 0 8 0;0,3=0,5=0
P 5.92 1.57063002 15 P 0 8 0;1,3=1,5=1
L 6.22 1.57 6.214 1.576 3 P 0 
L 6.214 1.576 6.17 1.576 3 P 0 
P 6.17 1.576 32 P 0 8 0;0,3=0,5=0
P 6.22 1.57 15 P 0 8 0;1,3=1,5=1
P 5.98 1.461 32 P 0 8 0;0,3=0,5=0
L 5.98 1.461 5.921 1.461 3 P 0 
L 5.921 1.461 5.92 1.46 3 P 0 
P 5.92 1.46 15 P 0 8 0;1,3=1,5=1
P 6.17 1.476 32 P 0 8 0;0,3=0,5=0
L 6.17 1.476 6.209 1.476 3 P 0 
L 6.209 1.476 6.22 1.465 3 P 0 
P 6.22 1.465 15 P 0 8 0;1,3=1,5=1
P 5.98 1.676 32 P 0 8 0;0,3=0,5=0
L 5.92 1.68 5.924 1.676 3 P 0 
L 5.924 1.676 5.98 1.676 3 P 0 
P 5.92 1.68 15 P 0 8 0;1,3=1,5=1
L 6.17 1.676 6.21498002 1.676 3 P 0 
L 6.21498002 1.676 6.22035 1.67063002 3 P 0 
P 6.17 1.676 32 P 0 8 0;0,3=0,5=0
P 6.22035 1.67063002 15 P 0 8 0;1,3=1,5=1
P 5.98 1.781 32 P 0 8 0;0,3=0,5=0
L 5.92 1.78 5.921 1.781 3 P 0 
L 5.921 1.781 5.98 1.781 3 P 0 
P 5.92 1.78 15 P 0 8 0;1,3=1,5=1
L 6.22 1.755 6.206 1.769 3 P 0 
L 6.206 1.769 6.155 1.769 3 P 0 
P 6.155 1.769 32 P 0 8 0;0,3=0,5=0
P 6.22 1.755 15 P 0 8 0;1,3=1,5=1
L 6.09423996 4.13778996 6.09603002 4.136 3 P 0 
L 6.09603002 4.136 6.145 4.136 3 P 0 
P 6.145 4.136 32 P 0 8 0;0,3=0,5=0
P 6.09423996 4.13778996 15 P 0 8 0;1,3=1,5=1
P 3.51 3.08 15 P 0 8 0;1,3=1,5=1
P 1.025 2.9 12 P 0 8 0;3=3,5=1
P 4.42311004 1.94185 11 P 0 8 0;3=2,5=1
P 3.46 3.065 15 P 0 8 0;1,3=1,5=1
P 1.125 2.9 12 P 0 8 0;3=3,5=1
P 4.42311004 1.90248002 11 P 0 8 0;3=2,5=1
P 3.035 1.64 12 P 0 8 0;3=3,5=1
L 1.1737 0.7086 1.1504 0.7086 3 P 0 
L 1.1504 0.7086 1.1288 0.7302 3 P 0 
P 3.445 2.65 15 P 0 8 0;1,3=4,5=0
P 1.1737 0.7086 36 P 0 8 0;0,3=0,5=0
P 1.08 0.718 36 P 0 8 0;0,3=0,5=0
L 1.08 0.718 1.1166 0.718 3 P 0 
L 1.1166 0.718 1.1288 0.7302 3 P 0 
P 1.1288 0.7302 15 P 0 8 0;1,3=10,5=1
P 3.075 1.605 12 P 0 8 0;3=3,5=1
P 3.365 2.95 15 P 0 8 0;1,3=5,5=1
L 0.755 0.62 0.765 0.62 3 P 0 
L 0.765 0.62 0.809 0.664 3 P 0 
L 0.809 0.664 0.809 0.665 3 P 0 
L 0.799 0.711 0.809 0.701 3 P 0 
L 0.809 0.701 0.809 0.665 3 P 0 
L 0.799 0.711 0.846 0.711 3 P 0 
L 0.846 0.711 0.847 0.71 3 P 0 
P 0.847 0.71 36 P 0 8 0;0,3=0,5=0
P 0.755 0.62 15 P 0 8 0;3=4,5=0
P 0.799 0.711 32 P 0 8 0;0,3=0,5=0
P 0.809 0.665 36 P 0 8 0;0,3=0,5=0
L 0.715 0.77 0.721 0.776 3 P 0 
L 0.721 0.776 0.721 0.817 3 P 0 
P 0.721 0.817 32 P 0 8 0;0,3=0,5=0
P 0.715 0.77 15 P 0 8 0;1,3=1,5=1
L 0.83 3.445 0.83 3.43998996 3 P 0 
L 0.83 3.43998996 0.85998996 3.41 3 P 0 
L 0.85998996 3.41 0.869 3.41 3 P 0 
P 0.869 3.41 36 P 0 8 0;0,3=0,5=0
P 0.83 3.445 15 P 0 8 0;1,3=1,5=1
L 0.795 3.485 0.80805 3.485 3 P 0 
L 0.80805 3.485 0.81305 3.49 3 P 0 
L 0.81305 3.49 0.85 3.49 3 P 0 
L 0.85 3.49 0.86 3.5 3 P 0 
L 0.86 3.5 0.869 3.5 3 P 0 
P 0.869 3.455 36 P 0 8 0;0,3=0,5=0
L 0.869 3.455 0.869 3.5 3 P 0 
P 0.869 3.5 36 P 0 8 0;0,3=0,5=0
P 0.795 3.485 15 P 0 8 0;1,3=1,5=1
L 0.83 3.525 0.82583002 3.52916998 3 P 0 
L 0.82583002 3.52916998 0.82583002 3.53583002 3 P 0 
L 0.82583002 3.53583002 0.843 3.553 3 P 0 
L 0.843 3.553 0.882 3.553 3 P 0 
P 0.882 3.553 32 P 0 8 0;0,3=0,5=0
P 0.83 3.525 15 P 0 8 0;1,3=1,5=1
L 0.951 3.519 0.95 3.52 3 P 0 
L 0.95 3.52 0.95 3.564 3 P 0 
P 0.95 3.564 32 P 0 8 0;0,3=0,5=0
P 0.951 3.519 15 P 0 8 0;1,3=1,5=1
P 0.82951004 3.2794 15 P 0 8 0;1,3=1,5=1
L 0.746 3.155 0.79 3.155 3 P 0 
P 0.746 3.155 36 P 0 8 0;0,3=0,5=0
P 0.79 3.155 15 P 0 8 0;1,3=1,5=1
P 0.78635 3.24491998 15 P 0 8 0;1,3=1,5=1
L 1.26 3.18 1.28 3.16 3 P 0 
L 1.28 3.16 1.28 3.136 3 P 0 
P 1.28 3.136 32 P 0 8 0;0,3=0,5=0
P 1.26 3.18 15 P 0 8 0;1,3=1,5=1
L 1.295 3.28 1.339 3.28 3 P 0 
P 1.339 3.235 36 P 0 8 0;0,3=0,5=0
L 1.339 3.235 1.339 3.28 3 P 0 
P 1.339 3.28 36 P 0 8 0;0,3=0,5=0
P 1.295 3.28 15 P 0 8 0;1,3=1,5=1
P 1.075 3.02 15 P 0 8 0;1,3=1,5=1
P 1.125 3.02 15 P 0 8 0;1,3=1,5=1
P 1.073 3.825 11 P 0 8 0;3=13,5=1
P 0.703 3.575 11 P 0 8 0;3=13,5=1
P 0.35238002 3.4315 13 P 0 8 0;3=7,5=0
P 0.33466004 3.4008 13 P 0 8 0;3=7,5=0
P 0.735 3.575 11 P 0 8 0;3=13,5=1
P 1.105 3.825 11 P 0 8 0;3=13,5=1
P 0.38781998 3.4315 13 P 0 8 0;3=7,5=0
P 0.29921998 3.4008 13 P 0 8 0;3=7,5=0
L 1.055 3.689 1.026 3.689 3 P 0 
L 1.026 3.689 1.015 3.7 3 P 0 
L 1.015 3.7 0.995 3.7 3 P 0 
L 0.995 3.7 0.995 3.606 3 P 0 
P 1.04 3.606 32 P 0 8 0;0,3=0,5=0
L 1.04 3.606 0.995 3.606 3 P 0 
P 1.055 3.689 32 P 0 8 0;0,3=0,5=0
P 0.995 3.7 15 P 0 8 0;1,3=4,5=0
P 0.995 3.606 32 P 0 8 0;0,3=0,5=0
P 4.285 3.46 12 P 0 8 0;3=3,5=1
L 1.9695 3.388 2.037 3.388 3 P 0 
L 2.037 3.388 2.05 3.375 3 P 0 
L 2.104 3.36 2.065 3.36 3 P 0 
L 2.065 3.36 2.05 3.375 3 P 0 
P 2.05 3.375 15 P 0 8 0;1,3=14,5=1
P 2.105 3.409 32 P 0 8 0;0,3=0,5=0
L 2.105 3.409 2.105 3.361 3 P 0 
L 2.105 3.361 2.104 3.36 3 P 0 
P 2.104 3.36 36 P 0 8 0;0,3=0,5=0
P 1.9695 3.388 47 P 0 8 0;0,3=9,5=0
L 2.105 3.451 2.07695 3.451 3 P 0 
L 2.07695 3.451 2.07225 3.4463 3 P 0 
L 2.07225 3.4463 2.07225 3.4207 3 P 0 
L 2.07225 3.4207 2.06755 3.416 3 P 0 
L 2.06755 3.416 2.05225 3.416 3 P 0 
L 2.05225 3.416 2.04755 3.4207 3 P 0 
L 2.04755 3.4207 2.04755 3.4463 3 P 0 
L 2.04755 3.4463 2.04285 3.451 3 P 0 
L 2.04285 3.451 2.03 3.451 3 P 0 
L 2.03 3.451 2.017 3.438 3 P 0 
L 2.017 3.438 1.9695 3.438 3 P 0 
L 2.105 3.451 2.137 3.451 3 P 0 
L 2.137 3.451 2.15 3.438 3 P 0 
P 2.105 3.451 32 P 0 8 0;0,3=0,5=0
P 2.15 3.438 15 P 0 8 0;1,3=1,5=1
P 1.9695 3.438 47 P 0 8 0;0,3=9,5=0
L 2.104 3.55 2.092 3.538 3 P 0 
L 2.092 3.538 2.05 3.538 3 P 0 
L 2.05 3.538 1.9695 3.538 3 P 0 
P 2.05 3.538 15 P 0 8 0;1,3=1,5=1
P 1.9695 3.538 47 P 0 8 0;0,3=9,5=0
P 2.104 3.55 36 P 0 8 0;0,3=0,5=0
L 2.05 3.488 2.092 3.488 3 P 0 
L 2.092 3.488 2.104 3.5 3 P 0 
L 1.9695 3.488 2.05 3.488 3 P 0 
P 2.05 3.488 15 P 0 8 0;1,3=1,5=1
P 1.9695 3.488 47 P 0 8 0;0,3=9,5=0
P 2.104 3.5 36 P 0 8 0;0,3=0,5=0
L 1.0541 3.185 1.035 3.1659 10 P 0 
L 1.035 3.1659 1.035 3.136 10 P 0 
L 1.29 3.215 1.255 3.25 11 P 0 
L 1.255 3.25 1.255 3.425 11 P 0 
L 1.255 3.425 1.3 3.47 11 P 0 
L 1.3 3.47 1.3 3.49663996 11 P 0 
L 1.3 3.49663996 1.30336004 3.5 10 P 0 
L 1.30336004 3.5 1.334 3.5 10 P 0 
P 1.29 3.215 12 P 0 8 0;3=3,5=1
P 1.035 3.136 32 P 0 8 0;0,3=0,5=0
P 1.0541 3.185 15 P 0 8 0;1,3=1,5=1
P 1.334 3.5 36 P 0 8 0;0,3=0,5=0
P 1.3 3.49663996 12 P 0 8 0;3=3,5=1
P 1.04018996 3.47425 12 P 0 8 0;3=3,5=1
P 4.205 3.66 15 P 0 8 0;1,3=1,5=1
L 0.911 3.41 0.975 3.41 3 P 0 
P 0.911 3.41 36 P 0 8 0;0,3=0,5=0
P 0.975 3.41 12 P 0 8 0;3=3,5=1
L 1.015 3.41 1.015 3.415 3 P 0 
L 1.015 3.415 0.95 3.48 3 P 0 
L 0.95 3.48 0.931 3.48 3 P 0 
L 0.931 3.48 0.911 3.5 3 P 0 
P 4.225 3.545 15 P 0 8 0;1,3=1,5=1
P 1.015 3.41 12 P 0 8 0;3=3,5=1
P 0.911 3.5 36 P 0 8 0;0,3=0,5=0
P 3.95 3.6 15 P 0 8 0;1,3=1,5=1
L 0.835 3.6 0.84 3.6 3 P 0 
L 0.84 3.6 0.845 3.595 3 P 0 
L 0.845 3.595 0.882 3.595 3 P 0 
P 0.835 3.6 12 P 0 8 0;3=3,5=1
P 0.882 3.595 32 P 0 8 0;0,3=0,5=0
L 0.95 3.606 0.9197 3.606 3 P 0 
L 0.9197 3.606 0.915 3.6013 3 P 0 
L 0.915 3.6013 0.915 3.595 3 P 0 
P 3.95 3.7 15 P 0 8 0;1,3=1,5=1
P 0.95 3.606 32 P 0 8 0;0,3=0,5=0
P 0.915 3.595 12 P 0 8 0;3=3,5=1
P 4.1184 3.5362 12 P 0 8 0;3=3,5=1
P 4.085 3.11 15 P 0 8 0;1,3=1,5=1
L 4.33381998 3.60466004 4.355 3.58348002 3 P 0 
L 4.355 3.58348002 4.355 3.52 3 P 0 
L 4.355 3.52 4.3425 3.5075 3 P 0 
L 4.3425 3.5075 4.3425 3.4496 3 P 0 
L 4.3425 3.4496 4.31 3.4171 3 P 0 
L 4.31 3.4171 4.31 3.27 3 P 0 
L 4.31 3.27 4.445 3.135 3 P 0 
L 4.445 3.135 4.445 3.09 3 P 0 
L 4.445 3.09 4.47 3.065 3 P 0 
L 4.47 3.065 4.51 3.065 3 P 0 
P 4.51 3.065 12 P 0 8 0;3=3,5=1
P 4.33381998 3.60466004 15 P 0 8 0;1,3=1,5=1
L 4.34 3.28 4.36 3.3 3 P 0 
L 4.36 3.3 4.36 3.33276004 3 P 0 
L 4.36 3.33276004 4.3553 3.33746004 3 P 0 
L 4.3553 3.33746004 4.3501 3.33746004 3 P 0 
L 4.3501 3.33746004 4.3454 3.34216004 3 P 0 
L 4.3454 3.34216004 4.3454 3.35746004 3 P 0 
L 4.3454 3.35746004 4.3501 3.36216004 3 P 0 
L 4.3501 3.36216004 4.3553 3.36216004 3 P 0 
L 4.3553 3.36216004 4.36 3.36686004 3 P 0 
L 4.36 3.36686004 4.36 3.38216004 3 P 0 
L 4.36 3.38216004 4.3553 3.38686004 3 P 0 
L 4.3553 3.38686004 4.3501 3.38686004 3 P 0 
L 4.3501 3.38686004 4.3454 3.39156004 3 P 0 
L 4.3454 3.39156004 4.3454 3.40686004 3 P 0 
L 4.3454 3.40686004 4.3501 3.41156004 3 P 0 
L 4.3501 3.41156004 4.3553 3.41156004 3 P 0 
L 4.3553 3.41156004 4.36 3.41626004 3 P 0 
L 4.36 3.41626004 4.36 3.435 3 P 0 
L 4.36 3.435 4.3723 3.4473 3 P 0 
L 4.3723 3.4473 4.3723 3.46851998 3 P 0 
L 4.3723 3.46851998 4.377 3.47321998 3 P 0 
L 4.377 3.47321998 4.3948 3.47321998 3 P 0 
L 4.3948 3.47321998 4.3995 3.47791998 3 P 0 
L 4.3995 3.47791998 4.3995 3.49321998 3 P 0 
L 4.3995 3.49321998 4.3948 3.49791998 3 P 0 
L 4.3948 3.49791998 4.377 3.49791998 3 P 0 
L 4.377 3.49791998 4.3723 3.50261998 3 P 0 
L 4.3723 3.50261998 4.3723 3.51791998 3 P 0 
L 4.3723 3.51791998 4.377 3.52261998 3 P 0 
L 4.377 3.52261998 4.3948 3.52261998 3 P 0 
L 4.3948 3.52261998 4.3995 3.52731998 3 P 0 
L 4.3995 3.52731998 4.3995 3.54261998 3 P 0 
L 4.3995 3.54261998 4.3948 3.54731998 3 P 0 
L 4.3948 3.54731998 4.377 3.54731998 3 P 0 
L 4.377 3.54731998 4.3723 3.55201998 3 P 0 
L 4.3723 3.55201998 4.3723 3.56731998 3 P 0 
L 4.3723 3.56731998 4.377 3.57201998 3 P 0 
L 4.377 3.57201998 4.3948 3.57201998 3 P 0 
L 4.3948 3.57201998 4.3995 3.57671998 3 P 0 
L 4.3995 3.57671998 4.3995 3.59201998 3 P 0 
L 4.3995 3.59201998 4.3948 3.59671998 3 P 0 
L 4.3948 3.59671998 4.377 3.59671998 3 P 0 
L 4.377 3.59671998 4.3723 3.60141998 3 P 0 
L 4.3723 3.60141998 4.3723 3.61193996 3 P 0 
L 4.3723 3.61193996 4.335 3.64923996 3 P 0 
L 4.335 3.64923996 4.335 3.665 3 P 0 
P 4.34 3.28 12 P 0 8 0;3=3,5=1
P 4.335 3.665 15 P 0 8 0;1,3=1,5=1
P 4.09 3.71338996 15 P 0 8 0;1,3=1,5=1
P 3.38 1.025 12 P 0 8 0;3=3,5=1
P 4.585 0.865 15 P 0 8 0;1,3=1,5=1
P 0.62 3.235 12 P 0 8 0;3=3,5=1
P 3.925 3.239 15 P 0 8 0;1,3=1,5=1
P 0.825 3.39 12 P 0 8 0;3=3,5=1
P 0.795 3.4179 12 P 0 8 0;3=3,5=1
P 3.795 3.758 15 P 0 8 0;1,3=1,5=1
L 0.704 3.2 0.675 3.2 3 P 0 
L 0.675 3.2 0.66 3.185 3 P 0 
P 3.62 1.28 12 P 0 8 0;3=3,5=1
L 5.195 0.755 5.095 0.755 3 P 0 
L 5.095 0.755 4.93 0.59 3 P 0 
L 4.93 0.59 3.7 0.59 3 P 0 
L 3.7 0.59 3.53 0.76 3 P 0 
L 3.53 0.76 3.42 0.76 3 P 0 
L 3.42 0.76 3.35 0.83 3 P 0 
L 3.35 0.83 3.35 0.89501004 3 P 0 
L 3.35 0.89501004 3.43266004 0.97766998 3 P 0 
L 3.43266004 0.97766998 3.59768002 0.97766998 3 P 0 
L 3.59768002 0.97766998 3.62233002 1.00231998 3 P 0 
L 3.62233002 1.00231998 3.62233002 1.10786998 3 P 0 
L 3.62233002 1.10786998 3.595 1.1352 3 P 0 
L 3.595 1.1352 3.595 1.255 3 P 0 
L 3.595 1.255 3.62 1.28 3 P 0 
P 5.195 0.755 15 P 0 8 0;1,3=1,5=1
P 4.96 0.85 12 P 0 8 0;3=3,5=1
P 0.66 3.185 12 P 0 8 0;3=3,5=1
P 0.704 3.155 36 P 0 8 0;0,3=0,5=0
P 0.704 3.2 36 P 0 8 0;0,3=0,5=0
L 0.704 3.155 0.704 3.2 3 P 0 
P 3.62 1.235 12 P 0 8 0;3=3,5=1
L 5.195 0.815 5.13 0.815 3 P 0 
L 5.13 0.815 4.92266998 0.60766998 3 P 0 
L 4.92266998 0.60766998 3.70731998 0.60766998 3 P 0 
L 3.70731998 0.60766998 3.53731998 0.77766998 3 P 0 
L 3.53731998 0.77766998 3.42731998 0.77766998 3 P 0 
L 3.42731998 0.77766998 3.375 0.82998996 3 P 0 
L 3.375 0.82998996 3.375 0.885 3 P 0 
L 3.375 0.885 3.45 0.96 3 P 0 
L 3.45 0.96 3.605 0.96 3 P 0 
L 3.605 0.96 3.64 0.995 3 P 0 
L 3.64 0.995 3.64 1.185 3 P 0 
L 3.64 1.185 3.62 1.205 3 P 0 
L 3.62 1.205 3.62 1.235 3 P 0 
L 0.704 3.245 0.694 3.235 3 P 0 
L 0.694 3.235 0.66 3.235 3 P 0 
P 5.195 0.815 15 P 0 8 0;1,3=1,5=1
P 4.937 0.79161004 12 P 0 8 0;3=3,5=1
P 0.704 3.245 36 P 0 8 0;0,3=0,5=0
P 0.66 3.235 12 P 0 8 0;3=3,5=1
P 4.205 3.81 12 P 0 8 0;3=3,5=1
L 5.6705 2.9225 5.6705 2.8885 3 P 0 
L 5.6705 2.8885 5.719 2.84 3 P 0 
L 5.719 2.84 5.795 2.84 3 P 0 
L 5.795 2.84 5.814 2.821 3 P 0 
P 5.814 2.821 15 P 0 8 0;1,3=10,5=1
P 5.6705 2.9225 40 P 0 8 0;0,3=15,5=0
L 5.6705 2.9225 5.544 2.9225 3 P 0 
P 5.544 2.9225 36 P 0 8 0;0,3=0,5=0
L 5.546 2.77 5.57236004 2.77 3 P 0 
L 5.57236004 2.77 5.57336004 2.771 3 P 0 
L 5.57336004 2.771 5.584 2.771 3 P 0 
L 5.584 2.771 5.6305 2.7245 3 P 0 
L 5.6305 2.7245 5.6755 2.7245 3 P 0 
P 4.19 3.735 12 P 0 8 0;3=3,5=1
L 5.814 2.721 5.814 2.761 3 P 0 
L 5.814 2.761 5.795 2.78 3 P 0 
L 5.795 2.78 5.695 2.78 3 P 0 
L 5.695 2.78 5.6755 2.7605 3 P 0 
L 5.6755 2.7605 5.6755 2.7245 3 P 0 
P 5.546 2.77 36 P 0 8 0;0,3=0,5=0
P 5.6755 2.7245 40 P 0 8 0;0,3=15,5=0
P 5.814 2.721 15 P 0 8 0;1,3=10,5=1
L 5.546 3.02 5.57236004 3.02 3 P 0 
L 5.57236004 3.02 5.57336004 3.019 3 P 0 
L 5.57336004 3.019 5.602 3.019 3 P 0 
L 5.602 3.019 5.6115 3.0095 3 P 0 
L 5.6115 3.0095 5.6705 3.0095 3 P 0 
P 3.895 3.7 12 P 0 8 0;3=3,5=1
L 5.6705 3.0095 5.6705 3.0505 3 P 0 
L 5.6705 3.0505 5.681 3.061 3 P 0 
L 5.681 3.061 5.775 3.061 3 P 0 
L 5.775 3.061 5.815 3.021 3 P 0 
P 5.546 3.02 36 P 0 8 0;0,3=0,5=0
P 5.6705 3.0095 40 P 0 8 0;0,3=15,5=0
P 5.815 3.021 15 P 0 8 0;1,3=10,5=1
L 5.6755 2.6375 5.57486004 2.6375 3 P 0 
L 5.57486004 2.6375 5.57236004 2.64 3 P 0 
L 5.57236004 2.64 5.546 2.64 3 P 0 
P 4.135 3.735 12 P 0 8 0;3=3,5=1
L 5.814 2.621 5.814 2.599 3 P 0 
L 5.814 2.599 5.785 2.57 3 P 0 
L 5.785 2.57 5.696 2.57 3 P 0 
L 5.696 2.57 5.6755 2.5905 3 P 0 
L 5.6755 2.5905 5.6755 2.6375 3 P 0 
P 5.6755 2.6375 40 P 0 8 0;0,3=15,5=0
P 5.546 2.64 36 P 0 8 0;0,3=0,5=0
P 5.814 2.621 15 P 0 8 0;1,3=10,5=1
P 2.3 3.475 12 P 0 8 0;3=3,5=1
P 5.045 3.405 12 P 0 8 0;3=3,5=1
P 6.33 2.67 15 P 0 8 0;1,3=10,5=1
P 1.28 3.094 32 P 0 8 0;0,3=0,5=0
P 1.35 3.12 12 P 0 8 0;3=3,5=1
L 1.35 3.12 1.324 3.094 3 P 0 
L 1.324 3.094 1.28 3.094 3 P 0 
L 1.46 3.34 1.4 3.28 3 P 0 
L 1.4 3.28 1.381 3.28 3 P 0 
P 2.255 3.475 12 P 0 8 0;3=3,5=1
P 5.09 3.405 12 P 0 8 0;3=3,5=1
P 6.33 2.865 15 P 0 8 0;1,3=1,5=1
P 1.381 3.28 36 P 0 8 0;0,3=0,5=0
P 1.46 3.34 12 P 0 8 0;3=3,5=1
L 4.705 0.825 4.765 0.885 3 P 0 
L 4.765 0.885 4.80501004 0.885 3 P 0 
L 4.80501004 0.885 4.90098002 0.98096998 3 P 0 
L 4.90098002 0.98096998 4.90098002 0.98761004 3 P 0 
L 4.90098002 0.98761004 4.88461998 1.00396998 3 P 0 
L 4.88461998 1.00396998 4.88461998 1.01061004 3 P 0 
L 4.88461998 1.01061004 4.89545 1.02143996 3 P 0 
L 4.89545 1.02143996 4.90208996 1.02143996 3 P 0 
L 4.90208996 1.02143996 4.91845 1.00508002 3 P 0 
L 4.91845 1.00508002 4.92508996 1.00508002 3 P 0 
L 4.92508996 1.00508002 4.93591998 1.01591004 3 P 0 
L 4.93591998 1.01591004 4.93591998 1.02255 3 P 0 
L 4.93591998 1.02255 4.91956004 1.03891004 3 P 0 
L 4.91956004 1.03891004 4.91956004 1.04555 3 P 0 
L 4.91956004 1.04555 4.93038996 1.05638002 3 P 0 
L 4.93038996 1.05638002 4.93703002 1.05638002 3 P 0 
L 4.93703002 1.05638002 4.95338996 1.04001998 3 P 0 
L 4.95338996 1.04001998 4.96003002 1.04001998 3 P 0 
L 4.96003002 1.04001998 4.98 1.05998996 3 P 0 
L 4.98 1.05998996 4.98 1.14766998 3 P 0 
L 4.98 1.14766998 5.06733002 1.235 3 P 0 
L 5.06733002 1.235 5.06733002 1.47656998 3 P 0 
L 5.06733002 1.47656998 5.06735 1.47658996 3 P 0 
L 5.06735 1.47658996 5.06735 1.75233996 3 P 0 
L 5.06735 1.75233996 5.1 1.78498996 3 P 0 
L 5.1 1.78498996 5.1 1.93 3 P 0 
L 5.1 1.93 4.985 2.045 3 P 0 
L 4.985 2.045 4.985 2.06501004 3 P 0 
L 4.985 2.06501004 4.95501004 2.095 3 P 0 
L 4.95501004 2.095 4.9 2.095 3 P 0 
L 4.9 2.095 4.795 2.2 3 P 0 
L 4.795 2.2 4.705 2.2 3 P 0 
L 4.705 2.2 4.695 2.21 3 P 0 
L 4.695 2.21 4.6 2.21 3 P 0 
L 4.6 2.21 4.575 2.235 3 P 0 
P 4.575 2.235 12 P 0 8 0;3=3,5=1
P 4.50185 1.94185 11 P 0 8 0;3=2,5=1
P 4.705 0.825 15 P 0 8 0;1,3=1,5=1
L 4.755 0.825 4.7977 0.8677 3 P 0 
L 4.7977 0.8677 4.81218002 0.8677 3 P 0 
L 4.81218002 0.8677 5.00473996 1.06026004 3 P 0 
L 5.00473996 1.06026004 5.00473996 1.14691998 3 P 0 
L 5.00473996 1.14691998 5.085 1.22718002 3 P 0 
L 5.085 1.22718002 5.085 1.745 3 P 0 
L 5.085 1.745 5.115 1.775 3 P 0 
L 5.115 1.775 5.115 1.77551998 3 P 0 
L 5.115 1.77551998 5.1173 1.77781998 3 P 0 
L 5.1173 1.77781998 5.1173 1.93716998 3 P 0 
L 5.1173 1.93716998 5.005 2.04946998 3 P 0 
L 5.005 2.04946998 5.005 2.07 3 P 0 
L 5.005 2.07 4.955 2.12 3 P 0 
L 4.955 2.12 4.91 2.12 3 P 0 
L 4.91 2.12 4.81 2.22 3 P 0 
L 4.81 2.22 4.71 2.22 3 P 0 
L 4.71 2.22 4.68 2.25 3 P 0 
L 4.68 2.25 4.64661004 2.25 3 P 0 
L 4.64661004 2.25 4.62926004 2.26735 3 P 0 
L 4.62926004 2.26735 4.58765 2.26735 3 P 0 
L 4.58765 2.26735 4.58 2.275 3 P 0 
L 4.58 2.275 4.575 2.275 3 P 0 
P 4.575 2.275 12 P 0 8 0;3=3,5=1
P 4.38373996 1.98121998 11 P 0 8 0;3=2,5=1
P 4.755 0.825 15 P 0 8 0;1,3=1,5=1
L 1.2157 0.7086 1.2486 0.7086 3 P 0 
L 1.2486 0.7086 1.26 0.72 3 P 0 
P 1.26 0.72 15 P 0 8 0;1,3=1,5=1
P 1.2157 0.7086 36 P 0 8 0;0,3=0,5=0
P 4.6987 1.82373996 11 P 0 8 0;3=2,5=1
L 0.842 0.75 0.839 0.753 3 P 0 
L 0.839 0.753 0.799 0.753 3 P 0 
P 0.842 0.75 15 P 0 8 0;1,3=1,5=1
P 0.799 0.753 32 P 0 8 0;0,3=0,5=0
P 4.73806998 1.82373996 11 P 0 8 0;3=2,5=1
P 4.10816004 1.90248002 15 P 0 8 0;1,3=6,5=1
P 3.73648996 1.85735 12 P 0 8 0;3=3,5=1
P 4.10816004 1.82373996 11 P 0 8 0;3=2,5=1
P 4.345 3.02 12 P 0 8 0;3=3,5=1
P 4.075 3.005 12 P 0 8 0;3=3,5=1
P 3.925 3.291 15 P 0 8 0;1,3=1,5=1
P 4.14753002 1.82373996 11 P 0 8 0;3=2,5=1
P 4.39 3.02 12 P 0 8 0;3=3,5=1
P 4.13 3.005 12 P 0 8 0;3=3,5=1
P 3.795 3.81 15 P 0 8 0;1,3=1,5=1
L 4.4 3.325 4.425 3.325 3 P 0 
L 4.425 3.325 4.615 3.135 3 P 0 
L 4.615 3.135 4.615 3.11 3 P 0 
P 4.615 3.11 12 P 0 8 0;3=3,5=1
P 4.6987 1.90248002 11 P 0 8 0;3=2,5=1
P 4.4 3.325 15 P 0 8 0;1,3=1,5=1
L 4.615 2.68408996 4.55988002 2.68408996 3 P 0 
L 4.55988002 2.68408996 4.48188996 2.6061 3 P 0 
L 4.48188996 2.6061 4.29786998 2.6061 3 P 0 
L 4.29786998 2.6061 4.24 2.54823002 3 P 0 
L 4.24 2.54823002 4.24 2.46738996 3 P 0 
L 4.24 2.46738996 4.21826004 2.44565 3 P 0 
L 4.21826004 2.44565 4.19433996 2.44565 3 P 0 
L 4.19433996 2.44565 4.17198996 2.468 3 P 0 
L 4.17198996 2.468 4.15 2.468 3 P 0 
P 4.615 2.68408996 12 P 0 8 0;3=3,5=1
P 4.15 2.51 32 P 0 8 0;0,3=0,5=0
L 4.15 2.51 4.15 2.468 3 P 0 
P 4.15 2.468 12 P 0 8 0;3=3,5=1
L 6.17 1.434 6.201 1.434 3 P 0 
L 6.201 1.434 6.22 1.415 3 P 0 
P 6.17 1.434 32 P 0 8 0;0,3=0,5=0
P 6.22 1.415 15 P 0 8 0;1,3=1,5=1
P 4.685 2.7 12 P 0 8 0;3=3,5=1
L 4.209 2.51 4.209 2.468 3 P 0 
P 4.209 2.468 12 P 0 8 0;3=3,5=1
P 4.209 2.51 32 P 0 8 0;0,3=0,5=0
P 4.34436998 2.1387 11 P 0 8 0;3=2,5=1
P 6.22 1.516 15 P 0 8 0;1,3=1,5=1
L 6.17 1.534 6.202 1.534 3 P 0 
L 6.202 1.534 6.22 1.516 3 P 0 
P 6.17 1.534 32 P 0 8 0;0,3=0,5=0
L 4.975 2.26 4.925 2.31 3 P 0 
L 4.925 2.31 4.90001004 2.31 3 P 0 
L 4.90001004 2.31 4.86 2.35001004 3 P 0 
L 4.86 2.35001004 4.86 2.575 3 P 0 
L 4.86 2.575 4.76 2.675 3 P 0 
L 4.76 2.675 4.665 2.675 3 P 0 
L 4.665 2.675 4.65 2.66 3 P 0 
L 4.65 2.66 4.59 2.66 3 P 0 
L 4.59 2.66 4.5897 2.6597 3 P 0 
L 4.5897 2.6597 4.57391004 2.6597 3 P 0 
L 4.57391004 2.6597 4.50561004 2.5914 3 P 0 
L 4.50561004 2.5914 4.30396004 2.5914 3 P 0 
L 4.30396004 2.5914 4.255 2.54243996 3 P 0 
L 4.255 2.54243996 4.255 2.465 3 P 0 
L 4.255 2.465 4.25471004 2.46471004 3 P 0 
L 4.25471004 2.46471004 4.25471004 2.46131004 3 P 0 
L 4.25471004 2.46131004 4.22435 2.43095 3 P 0 
L 4.22435 2.43095 4.18825 2.43095 3 P 0 
L 4.18825 2.43095 4.1792 2.44 3 P 0 
L 4.1792 2.44 4.14 2.44 3 P 0 
L 4.14 2.44 4.112 2.468 3 P 0 
L 4.112 2.468 4.093 2.468 3 P 0 
P 4.975 2.26 12 P 0 8 0;3=3,5=1
L 4.093 2.51 4.093 2.468 3 P 0 
P 4.093 2.468 12 P 0 8 0;3=3,5=1
P 4.093 2.51 32 P 0 8 0;0,3=0,5=0
P 6.17 1.634 32 P 0 8 0;0,3=0,5=0
L 6.17 1.634 6.206 1.634 3 P 0 
L 6.206 1.634 6.22 1.62 3 P 0 
P 6.22 1.62 15 P 0 8 0;1,3=1,5=1
L 4.925 2.26 4.91 2.26 3 P 0 
L 4.91 2.26 4.84 2.33 3 P 0 
L 4.84 2.33 4.84 2.57 3 P 0 
L 4.84 2.57 4.78 2.63 3 P 0 
L 4.78 2.63 4.70161004 2.63 3 P 0 
L 4.70161004 2.63 4.69426004 2.62265 3 P 0 
L 4.69426004 2.62265 4.63235 2.62265 3 P 0 
L 4.63235 2.62265 4.61 2.645 3 P 0 
L 4.61 2.645 4.58 2.645 3 P 0 
L 4.58 2.645 4.5117 2.5767 3 P 0 
L 4.5117 2.5767 4.31048002 2.5767 3 P 0 
L 4.31048002 2.5767 4.27 2.53621998 3 P 0 
L 4.27 2.53621998 4.27 2.455 3 P 0 
L 4.27 2.455 4.2697 2.4547 3 P 0 
L 4.2697 2.4547 4.2697 2.44891004 3 P 0 
L 4.2697 2.44891004 4.23703996 2.41625 3 P 0 
L 4.23703996 2.41625 4.18216004 2.41625 3 P 0 
L 4.18216004 2.41625 4.17311004 2.4253 3 P 0 
L 4.17311004 2.4253 4.13391004 2.4253 3 P 0 
L 4.13391004 2.4253 4.11421004 2.445 3 P 0 
L 4.11421004 2.445 4.08 2.445 3 P 0 
L 4.08 2.445 4.057 2.468 3 P 0 
L 4.057 2.468 4.037 2.468 3 P 0 
P 4.925 2.26 15 P 0 8 0;1,3=1,5=1
L 4.037 2.51 4.037 2.468 3 P 0 
P 4.037 2.468 12 P 0 8 0;3=3,5=1
P 4.037 2.51 32 P 0 8 0;0,3=0,5=0
P 6.155 1.811 32 P 0 8 0;0,3=0,5=0
L 6.155 1.811 6.216 1.811 3 P 0 
L 6.216 1.811 6.22 1.815 3 P 0 
P 6.22 1.815 15 P 0 8 0;1,3=1,5=1
L 3.801 2.468 3.78201004 2.468 3 P 0 
L 3.78201004 2.468 3.77205 2.47796004 3 P 0 
L 3.77205 2.47796004 3.77205 2.49795 3 P 0 
L 3.77205 2.49795 3.735 2.535 3 P 0 
L 3.735 2.535 3.735 2.57998996 3 P 0 
L 3.735 2.57998996 3.77233996 2.61733002 3 P 0 
L 3.77233996 2.61733002 4.18233002 2.61733002 3 P 0 
L 4.18233002 2.61733002 4.215 2.65 3 P 0 
L 4.215 2.65 4.345 2.65 3 P 0 
L 4.345 2.65 4.4 2.705 3 P 0 
L 4.4 2.705 4.575 2.705 3 P 0 
L 4.575 2.705 4.6 2.73 3 P 0 
L 4.6 2.73 4.73 2.73 3 P 0 
L 4.73 2.73 4.88 2.58 3 P 0 
L 4.88 2.58 4.88 2.375 3 P 0 
L 4.88 2.375 4.93 2.325 3 P 0 
L 4.93 2.325 4.945 2.325 3 P 0 
L 4.945 2.325 5.09 2.18 3 P 0 
L 5.09 2.18 5.09 2.155 3 P 0 
P 5.92 1.41 15 P 0 8 0;1,3=1,5=1
L 5.98 1.419 5.929 1.419 3 P 0 
L 5.929 1.419 5.92 1.41 3 P 0 
P 5.98 1.419 32 P 0 8 0;0,3=0,5=0
P 5.09 2.155 12 P 0 8 0;3=3,5=1
L 3.801 2.51 3.801 2.468 3 P 0 
P 3.801 2.468 12 P 0 8 0;3=3,5=1
P 3.801 2.51 32 P 0 8 0;0,3=0,5=0
P 4.10816004 2.09933002 11 P 0 8 0;3=2,5=1
L 3.86 2.468 3.83261004 2.468 3 P 0 
L 3.83261004 2.468 3.81026004 2.44565 3 P 0 
L 3.81026004 2.44565 3.77936004 2.44565 3 P 0 
L 3.77936004 2.44565 3.77501004 2.45 3 P 0 
L 3.77501004 2.45 3.775 2.45 3 P 0 
L 3.775 2.45 3.75735 2.46765 3 P 0 
L 3.75735 2.46765 3.75735 2.49186004 3 P 0 
L 3.75735 2.49186004 3.7203 2.52891004 3 P 0 
L 3.7203 2.52891004 3.7203 2.5903 3 P 0 
L 3.7203 2.5903 3.76203002 2.63203002 3 P 0 
L 3.76203002 2.63203002 4.17623996 2.63203002 3 P 0 
L 4.17623996 2.63203002 4.20891004 2.6647 3 P 0 
L 4.20891004 2.6647 4.33891004 2.6647 3 P 0 
L 4.33891004 2.6647 4.39391004 2.7197 3 P 0 
L 4.39391004 2.7197 4.56891004 2.7197 3 P 0 
L 4.56891004 2.7197 4.59391004 2.7447 3 P 0 
L 4.59391004 2.7447 4.73608996 2.7447 3 P 0 
L 4.73608996 2.7447 4.8947 2.58608996 3 P 0 
L 4.8947 2.58608996 4.8947 2.38108996 3 P 0 
L 4.8947 2.38108996 4.93578996 2.34 3 P 0 
L 4.93578996 2.34 4.95498996 2.34 3 P 0 
L 4.95498996 2.34 5.135 2.15998996 3 P 0 
L 5.135 2.15998996 5.135 2.155 3 P 0 
P 5.98 1.539 32 P 0 8 0;0,3=0,5=0
L 5.98 1.539 5.944 1.539 3 P 0 
L 5.944 1.539 5.92 1.515 3 P 0 
P 5.92 1.515 15 P 0 8 0;1,3=1,5=1
P 5.135 2.155 12 P 0 8 0;3=3,5=1
P 3.86 2.468 12 P 0 8 0;3=3,5=1
L 3.86 2.51 3.86 2.468 3 P 0 
P 3.86 2.51 32 P 0 8 0;0,3=0,5=0
P 4.14753002 2.09933002 11 P 0 8 0;3=2,5=1
L 5.115 2.065 5.11446998 2.065 3 P 0 
L 5.11446998 2.065 4.97216998 2.2073 3 P 0 
L 4.97216998 2.2073 4.87533002 2.2073 3 P 0 
L 4.87533002 2.2073 4.79263002 2.29 3 P 0 
L 4.79263002 2.29 4.69 2.29 3 P 0 
L 4.69 2.29 4.6623 2.3177 3 P 0 
L 4.6623 2.3177 4.6623 2.52716998 3 P 0 
L 4.6623 2.52716998 4.64216998 2.5473 3 P 0 
L 4.64216998 2.5473 4.32783002 2.5473 3 P 0 
L 4.32783002 2.5473 4.305 2.52446998 3 P 0 
L 4.305 2.52446998 4.305 2.415 3 P 0 
L 4.305 2.415 4.27635 2.38635 3 P 0 
L 4.27635 2.38635 4.13128002 2.38635 3 P 0 
L 4.13128002 2.38635 4.11263002 2.405 3 P 0 
L 4.11263002 2.405 3.965 2.405 3 P 0 
L 3.965 2.405 3.919 2.451 3 P 0 
L 3.919 2.451 3.919 2.468 3 P 0 
P 5.92 1.63 15 P 0 8 0;1,3=1,5=1
P 5.98 1.634 32 P 0 8 0;0,3=0,5=0
L 5.98 1.634 5.924 1.634 3 P 0 
L 5.924 1.634 5.92 1.63 3 P 0 
P 5.115 2.065 12 P 0 8 0;3=3,5=1
L 3.919 2.51 3.919 2.468 3 P 0 
P 3.919 2.468 12 P 0 8 0;3=3,5=1
P 3.919 2.51 32 P 0 8 0;0,3=0,5=0
L 5.13 2.105 5.09526004 2.105 3 P 0 
L 5.09526004 2.105 4.97826004 2.222 3 P 0 
L 4.97826004 2.222 4.88141998 2.222 3 P 0 
L 4.88141998 2.222 4.79341998 2.31 3 P 0 
L 4.79341998 2.31 4.755 2.31 3 P 0 
L 4.755 2.31 4.677 2.388 3 P 0 
L 4.677 2.388 4.677 2.53326004 3 P 0 
L 4.677 2.53326004 4.64826004 2.562 3 P 0 
L 4.64826004 2.562 4.32173996 2.562 3 P 0 
L 4.32173996 2.562 4.285 2.52526004 3 P 0 
L 4.285 2.52526004 4.285 2.45 3 P 0 
L 4.285 2.45 4.2847 2.4497 3 P 0 
L 4.2847 2.4497 4.2847 2.44891004 3 P 0 
L 4.2847 2.44891004 4.28441004 2.44861998 3 P 0 
L 4.28441004 2.44861998 4.28441004 2.41941004 3 P 0 
L 4.28441004 2.41941004 4.26655 2.40155 3 P 0 
L 4.26655 2.40155 4.17606998 2.40155 3 P 0 
L 4.17606998 2.40155 4.16701998 2.4106 3 P 0 
L 4.16701998 2.4106 4.12781998 2.4106 3 P 0 
L 4.12781998 2.4106 4.10841998 2.43 3 P 0 
L 4.10841998 2.43 3.995 2.43 3 P 0 
L 3.995 2.43 3.978 2.447 3 P 0 
L 3.978 2.447 3.978 2.468 3 P 0 
P 5.98 1.739 32 P 0 8 0;0,3=0,5=0
L 5.98 1.739 5.929 1.739 3 P 0 
L 5.929 1.739 5.92 1.73 3 P 0 
P 5.92 1.73 15 P 0 8 0;1,3=1,5=1
P 5.13 2.105 12 P 0 8 0;3=3,5=1
L 3.978 2.51 3.978 2.468 3 P 0 
P 3.978 2.468 12 P 0 8 0;3=3,5=1
P 3.978 2.51 32 P 0 8 0;0,3=0,5=0
P 4.685 2.645 12 P 0 8 0;3=3,5=1
P 4.1 3.38 15 P 0 8 0;1,3=1,5=1
P 4.53 2.5 12 P 0 8 0;3=3,5=1
P 3.9 3.385 15 P 0 8 0;1,3=1,5=1
P 4.485 3.115 15 P 0 8 0;1,3=1,5=1
P 4.575 2.374 12 P 0 8 0;3=3,5=1
P 4.485 2.5 12 P 0 8 0;3=3,5=1
P 4.29441998 3.10075 15 P 0 8 0;1,3=1,5=1
P 4.61 2.345 12 P 0 8 0;3=3,5=1
P 4.54 3.125 15 P 0 8 0;1,3=1,5=1
L 4.35 2.505 4.35 2.461 3 P 0 
P 4.085 3.21998002 15 P 0 8 0;1,3=1,5=1
P 4.35 2.461 32 P 0 8 0;0,3=0,5=0
P 4.35 2.505 12 P 0 8 0;3=3,5=1
P 5.365 0.79 15 P 0 8 0;1,3=1,5=1
P 5.365 0.845 15 P 0 8 0;1,3=1,5=1
L 4.0661 3.5341 4.035 3.5652 3 P 0 
L 4.035 3.5652 3.956 3.5652 3 P 0 
L 3.956 3.5652 3.91815 3.52735 3 P 0 
L 3.91815 3.52735 3.74435 3.52735 3 P 0 
L 3.74435 3.52735 3.633 3.416 3 P 0 
L 3.633 3.416 3.633 3.263 3 P 0 
L 3.633 3.263 3.605 3.235 3 P 0 
L 3.605 3.235 3.506 3.235 3 P 0 
P 4.0661 3.5341 15 P 0 8 0;1,3=1,5=1
P 3.506 3.235 36 P 0 8 0;0,3=0,5=0
L 3.744 3.415 3.744 3.434 3 P 0 
L 3.744 3.434 3.765 3.455 3 P 0 
L 3.765 3.455 3.819 3.455 3 P 0 
L 3.819 3.455 3.83 3.466 3 P 0 
P 3.744 3.415 36 P 0 8 0;0,3=0,5=0
P 3.83 3.466 15 P 0 8 0;1,3=10,5=1
L 4.35143002 3.06643002 4.17456998 3.06643002 3 P 0 
L 4.17456998 3.06643002 4.09835 3.14265 3 P 0 
L 4.09835 3.14265 4.00735 3.14265 3 P 0 
L 4.00735 3.14265 3.99 3.16 3 P 0 
L 3.99 3.16 3.895 3.16 3 P 0 
L 3.895 3.16 3.855 3.2 3 P 0 
L 3.855 3.2 3.71 3.2 3 P 0 
L 3.71 3.2 3.68765 3.22235 3 P 0 
L 3.68765 3.22235 3.68765 3.31265 3 P 0 
L 3.68765 3.31265 3.7 3.325 3 P 0 
P 4.35143002 3.06643002 12 P 0 8 0;3=3,5=1
L 3.744 3.325 3.7 3.325 3 P 0 
P 3.7 3.325 15 P 0 8 0;1,3=1,5=1
P 3.744 3.325 36 P 0 8 0;0,3=0,5=0
L 3.5825 3.4005 3.568 3.415 3 P 0 
L 3.568 3.415 3.506 3.415 3 P 0 
P 3.5825 3.4005 15 P 0 8 0;1,3=5,5=1
P 3.506 3.415 36 P 0 8 0;0,3=0,5=0
L 3.83 3.235 3.865 3.235 3 P 0 
L 3.865 3.235 3.92 3.18 3 P 0 
L 3.92 3.18 4.005 3.18 3 P 0 
L 4.005 3.18 4.01263002 3.18763002 3 P 0 
L 4.01263002 3.18763002 4.14245 3.18763002 3 P 0 
L 4.14245 3.18763002 4.14715 3.18293002 3 P 0 
L 4.14715 3.18293002 4.14715 3.1227 3 P 0 
L 4.14715 3.1227 4.15185 3.118 3 P 0 
L 4.15185 3.118 4.16715 3.118 3 P 0 
L 4.16715 3.118 4.17185 3.1227 3 P 0 
L 4.17185 3.1227 4.17185 3.18293002 3 P 0 
L 4.17185 3.18293002 4.17655 3.18763002 3 P 0 
L 4.17655 3.18763002 4.19185 3.18763002 3 P 0 
L 4.19185 3.18763002 4.19655 3.18293002 3 P 0 
L 4.19655 3.18293002 4.19655 3.1227 3 P 0 
L 4.19655 3.1227 4.20125 3.118 3 P 0 
L 4.20125 3.118 4.21655 3.118 3 P 0 
L 4.21655 3.118 4.22125 3.1227 3 P 0 
L 4.22125 3.1227 4.22125 3.18293002 3 P 0 
L 4.22125 3.18293002 4.22595 3.18763002 3 P 0 
L 4.22595 3.18763002 4.24125 3.18763002 3 P 0 
L 4.24125 3.18763002 4.24595 3.18293002 3 P 0 
L 4.24595 3.18293002 4.24595 3.1227 3 P 0 
L 4.24595 3.1227 4.25065 3.118 3 P 0 
L 4.25065 3.118 4.26595 3.118 3 P 0 
L 4.26595 3.118 4.27065 3.1227 3 P 0 
L 4.27065 3.1227 4.27065 3.18293002 3 P 0 
L 4.27065 3.18293002 4.27535 3.18763002 3 P 0 
L 4.27535 3.18763002 4.28556998 3.18763002 3 P 0 
L 4.28556998 3.18763002 4.33 3.1432 3 P 0 
P 4.33 3.1432 12 P 0 8 0;3=3,5=1
P 3.786 3.235 36 P 0 8 0;0,3=0,5=0
L 3.786 3.235 3.83 3.235 3 P 0 
P 3.83 3.235 15 P 0 8 0;1,3=1,5=1
P 4.085 3.165 12 P 0 8 0;3=3,5=1
L 3.415 3.335 3.425 3.325 3 P 0 
L 3.425 3.325 3.464 3.325 3 P 0 
P 3.464 3.325 36 P 0 8 0;0,3=0,5=0
P 3.415 3.335 15 P 0 8 0;1,3=5,5=1
L 0.785 0.8225 0.7805 0.8225 3 P 0 
L 0.7805 0.8225 0.744 0.859 3 P 0 
L 0.744 0.859 0.721 0.859 3 P 0 
L 1.26 0.62 1.2545 0.62 3 P 0 
L 1.2545 0.62 1.2158 0.6587 3 P 0 
L 1.26 0.62 1.2705 0.62 3 P 0 
L 1.2705 0.62 1.3085 0.658 3 P 0 
P 0.74 1.3 12 P 0 8 0;3=3,5=1
P 1.3085 0.658 36 P 0 8 0;0,3=0,5=0
P 1.2158 0.6587 36 P 0 8 0;0,3=0,5=0
P 1.26 0.62 15 P 0 8 0;1,3=10,5=1
P 0.721 0.859 32 P 0 8 0;0,3=0,5=0
P 0.785 0.8225 12 P 0 8 0;3=3,5=1
L 1.3087 0.708 1.2707 0.67 3 P 0 
L 1.2707 0.67 1.26 0.67 3 P 0 
P 0.695 1.3 12 P 0 8 0;3=3,5=1
P 1.3087 0.708 36 P 0 8 0;0,3=0,5=0
P 1.26 0.67 15 P 0 8 0;1,3=10,5=1
P 0.76321004 0.783 12 P 0 8 0;3=3,5=1
L 3.485 2.864 3.49 2.864 3 P 0 
L 3.49 2.864 3.50935 2.88335 3 P 0 
L 3.50935 2.88335 3.50935 2.94273996 3 P 0 
L 3.50935 2.94273996 3.515 2.94838996 3 P 0 
L 3.515 2.94838996 3.515 2.975 3 P 0 
L 3.515 2.975 3.5 2.99 3 P 0 
L 3.5 2.99 3.40976998 2.99 3 P 0 
L 3.40976998 2.99 3.38476998 3.015 3 P 0 
L 3.38476998 3.015 3.32 3.015 3 P 0 
P 3.32 3.015 15 P 0 8 0;1,3=4,5=0
P 3.485 2.864 32 P 0 8 0;0,3=0,5=0
L 3.44 2.864 3.485 2.864 3 P 0 
P 3.44 2.864 32 P 0 8 0;0,3=0,5=0
L 3.24 3.01 3.26765 2.98235 3 P 0 
L 3.26765 2.98235 3.39295 2.98235 3 P 0 
L 3.39295 2.98235 3.405 2.9703 3 P 0 
L 3.405 2.9703 3.405 2.945 3 P 0 
L 3.405 2.945 3.395 2.935 3 P 0 
L 3.395 2.935 3.395 2.906 3 P 0 
P 3.24 3.01 15 P 0 8 0;1,3=4,5=0
P 3.395 2.906 32 P 0 8 0;0,3=0,5=0
L 3.395 2.906 3.35 2.906 3 P 0 
P 3.35 2.906 32 P 0 8 0;0,3=0,5=0
P 1.7485 3.488 47 P 0 8 0;0,3=9,5=0
L 0.606 1.57 0.606 1.563 3 P 0 
L 0.606 1.563 0.674 1.495 3 P 0 
P 0.606 1.57 15 P 0 8 0;1,3=1,5=1
P 0.674 1.495 36 P 0 8 0;0,3=0,5=0
L 0.835 1.73 0.85 1.715 3 P 0 
L 0.85 1.715 0.85 1.684 3 P 0 
P 0.835 1.73 15 P 0 8 0;1,3=1,5=1
P 0.85 1.684 36 P 0 8 0;0,3=0,5=0
S P 0
OB 2.805669980315 2.559430019685 I
OC 2.805669980315 2.559430019685 2.685669980315 2.559430019685 Y
OE
OB 2.748169980315 2.559430019685 H
OC 2.748169980315 2.559430019685 2.685669980315 2.559430019685 N
OE
SE
S P 0
OB 1.580669980315 2.680430019685 I
OC 1.580669980315 2.680430019685 1.460669980315 2.680430019685 Y
OE
OB 1.523169980315 2.680430019685 H
OC 1.523169980315 2.680430019685 1.460669980315 2.680430019685 N
OE
SE
S P 0
OB 1.555669980315 1.060430019685 I
OC 1.555669980315 1.060430019685 1.435669980315 1.060430019685 Y
OE
OB 1.498169980315 1.060430019685 H
OC 1.498169980315 1.060430019685 1.435669980315 1.060430019685 N
OE
SE
P 0.355 3.27 15 P 0 8 0;1,3=1,5=1
P 0.28 3.27 15 P 0 8 0;1,3=1,5=1
P 0.13 3.187 15 P 0 8 0;1,3=1,5=1
L 0.125 2.195 0.24 2.195 3 P 0 
L 0.24 2.195 0.49 1.945 3 P 0 
L 0.49 1.945 0.64998996 1.945 3 P 0 
L 0.64998996 1.945 0.69023002 1.98523996 3 P 0 
P 0.69023002 1.98523996 12 P 0 8 0;3=3,5=1
P 0.125 2.195 15 P 0 8 0;1,3=1,5=1
L 0.125 2.145 0.265 2.145 3 P 0 
L 0.265 2.145 0.495 1.915 3 P 0 
L 0.495 1.915 0.675 1.915 3 P 0 
L 0.675 1.915 0.69 1.93 3 P 0 
P 0.69 1.93 12 P 0 8 0;3=3,5=1
P 0.125 2.145 15 P 0 8 0;1,3=1,5=1
L 0.125 2.045 0.13 2.045 3 P 0 
L 0.13 2.045 0.165 2.08 3 P 0 
L 0.165 2.08 0.26 2.08 3 P 0 
L 0.26 2.08 0.48 1.86 3 P 0 
L 0.48 1.86 0.48 1.84576004 3 P 0 
L 0.48 1.84576004 0.48735 1.83841004 3 P 0 
L 0.48735 1.83841004 0.48735 1.83188996 3 P 0 
L 0.48735 1.83188996 0.52158996 1.79765 3 P 0 
L 0.52158996 1.79765 0.54841004 1.79765 3 P 0 
L 0.54841004 1.79765 0.55076004 1.8 3 P 0 
L 0.55076004 1.8 0.615 1.8 3 P 0 
L 0.615 1.8 0.69 1.875 3 P 0 
P 0.69 1.875 12 P 0 8 0;3=3,5=1
P 0.125 2.045 15 P 0 8 0;1,3=1,5=1
P 0.13 2.73326998 15 P 0 8 0;1,3=1,5=1
P 0.287 2.743 15 P 0 8 0;1,3=1,5=1
P 0.125 2.615 15 P 0 8 0;1,3=1,5=1
L 0.125 1.06 0.285 1.06 3 P 0 
L 0.285 1.06 0.3947 1.1697 3 P 0 
L 0.3947 1.1697 0.53815 1.1697 3 P 0 
L 0.53815 1.1697 0.5455 1.17705 3 P 0 
L 0.5455 1.17705 0.60043996 1.17705 3 P 0 
L 0.60043996 1.17705 0.61573996 1.19235 3 P 0 
L 0.61573996 1.19235 0.64736004 1.19235 3 P 0 
L 0.64736004 1.19235 0.66736004 1.21235 3 P 0 
L 0.66736004 1.21235 0.71265 1.21235 3 P 0 
L 0.71265 1.21235 0.735 1.19 3 P 0 
P 0.735 1.19 12 P 0 8 0;3=3,5=1
P 0.125 1.06 15 P 0 8 0;1,3=1,5=1
L 0.68 1.19 0.67661004 1.19 3 P 0 
L 0.67661004 1.19 0.63161004 1.145 3 P 0 
L 0.63161004 1.145 0.59576004 1.145 3 P 0 
L 0.59576004 1.145 0.57841004 1.16235 3 P 0 
L 0.57841004 1.16235 0.55158996 1.16235 3 P 0 
L 0.55158996 1.16235 0.54423996 1.155 3 P 0 
L 0.54423996 1.155 0.43 1.155 3 P 0 
L 0.43 1.155 0.285 1.01 3 P 0 
L 0.285 1.01 0.125 1.01 3 P 0 
P 0.68 1.19 12 P 0 8 0;3=3,5=1
P 0.125 1.01 15 P 0 8 0;1,3=1,5=1
L 0.125 0.91 0.13 0.91 3 P 0 
L 0.13 0.91 0.165 0.945 3 P 0 
L 0.165 0.945 0.295 0.945 3 P 0 
L 0.295 0.945 0.44 1.09 3 P 0 
L 0.44 1.09 0.57076004 1.09 3 P 0 
L 0.57076004 1.09 0.61106004 1.1303 3 P 0 
L 0.61106004 1.1303 0.6377 1.1303 3 P 0 
L 0.6377 1.1303 0.6524 1.145 3 P 0 
L 0.6524 1.145 0.675 1.145 3 P 0 
P 0.675 1.145 12 P 0 8 0;3=3,5=1
P 0.125 0.91 15 P 0 8 0;1,3=1,5=1
P 0.125 1.62 15 P 0 8 0;1,3=1,5=1
P 0.13 1.57 15 P 0 8 0;1,3=1,5=1
P 0.1362 1.4872 15 P 0 8 0;1,3=1,5=1
P 2.937 3.173 15 P 0 8 0;1,3=1,5=1
L 3.01 3.17 3.026 3.186 9 P 0 
L 3.026 3.186 3.026 3.21 9 P 0 
P 3.01 3.17 12 P 0 8 0;3=3,5=1
P 3.026 3.21 36 P 0 8 0;0,3=0,5=0
P 3.026 3.26 36 P 0 8 0;0,3=0,5=0
L 3.026 3.26 3.026 3.21 9 P 0 
P 0.896 2.489 15 P 0 8 0;1,3=5,5=1
L 0.896 2.444 0.896 2.489 3 P 0 
P 0.896 2.444 32 P 0 8 0;0,3=0,5=0
P 4.31168996 4.01168996 15 P 0 8 0;1,3=5,5=1
P 4.319 3.922 15 P 0 8 0;1,3=5,5=1
L 2.932 3.295 2.921 3.306 3 P 0 
L 2.921 3.306 2.921 3.401 3 P 0 
L 2.921 3.401 2.97 3.45 3 P 0 
L 2.97 3.45 3.16763996 3.45 3 P 0 
L 3.16763996 3.45 3.23993996 3.5223 3 P 0 
L 3.23993996 3.5223 3.5773 3.5223 3 P 0 
L 3.5773 3.5223 3.76 3.705 3 P 0 
L 3.76 3.705 3.76 3.90553002 3 P 0 
L 3.76 3.90553002 3.93446998 4.08 3 P 0 
L 3.93446998 4.08 4.1 4.08 3 P 0 
L 4.1 4.08 4.21 4.19 3 P 0 
L 4.21 4.19 4.4452 4.19 3 P 0 
L 4.4452 4.19 4.46135 4.17385 3 P 0 
L 4.46135 4.17385 4.46135 4.15365 3 P 0 
L 4.46135 4.15365 4.5 4.115 3 P 0 
L 1.315 2.905 1.315 2.885 3 P 0 
L 1.315 2.885 1.3404 2.8596 3 P 0 
L 1.3404 2.8596 1.60433996 2.8596 3 P 0 
L 1.60433996 2.8596 1.65163996 2.8123 3 P 0 
L 1.65163996 2.8123 2.21476998 2.8123 3 P 0 
L 2.21476998 2.8123 2.2973 2.89483002 3 P 0 
L 2.2973 2.89483002 2.2973 3.29341004 3 P 0 
L 2.2973 3.29341004 2.37738996 3.3735 3 P 0 
L 2.37738996 3.3735 2.66141998 3.3735 3 P 0 
L 2.66141998 3.3735 2.78991998 3.245 3 P 0 
L 2.78991998 3.245 2.9173 3.245 3 P 0 
L 2.9173 3.245 2.922 3.2497 3 P 0 
L 2.922 3.2497 2.922 3.285 3 P 0 
L 2.922 3.285 2.932 3.295 3 P 0 
P 4.5 4.115 15 P 0 8 0;1,3=1,5=1
P 1.315 2.905 11 P 0 8 0;3=11,5=1
P 2.932 3.295 11 P 0 8 0;3=11,5=1
P 0.915 1.4 12 P 0 8 0;3=3,5=1
P 1.42 0.69535 15 P 0 8 0;1,3=10,5=1
L 1.36 2.905 1.3881 2.8769 3 P 0 
L 1.3881 2.8769 1.61151004 2.8769 3 P 0 
L 1.61151004 2.8769 1.65841004 2.83 3 P 0 
L 1.65841004 2.83 2.2033 2.83 3 P 0 
L 2.2033 2.83 2.28 2.9067 3 P 0 
L 2.28 2.9067 2.28 3.30651998 3 P 0 
L 2.28 3.30651998 2.36848002 3.395 3 P 0 
L 2.36848002 3.395 2.66438996 3.395 3 P 0 
L 2.66438996 3.395 2.69755 3.36183996 3 P 0 
L 2.69755 3.36183996 2.70418996 3.36183996 3 P 0 
L 2.70418996 3.36183996 2.71683996 3.3745 3 P 0 
L 2.71683996 3.3745 2.72348002 3.3745 3 P 0 
L 2.72348002 3.3745 2.73431004 3.36366998 3 P 0 
L 2.73431004 3.36366998 2.73431004 3.35703002 3 P 0 
L 2.73431004 3.35703002 2.72166004 3.34436998 3 P 0 
L 2.72166004 3.34436998 2.72166004 3.33773002 3 P 0 
L 2.72166004 3.33773002 2.73248996 3.3269 3 P 0 
L 2.73248996 3.3269 2.73911998 3.3269 3 P 0 
L 2.73911998 3.3269 2.74828996 3.33606998 3 P 0 
L 2.74828996 3.33606998 2.75493002 3.33606998 3 P 0 
L 2.75493002 3.33606998 2.76576004 3.32523996 3 P 0 
L 2.76576004 3.32523996 2.76576004 3.3186 3 P 0 
L 2.76576004 3.3186 2.7566 3.30943996 3 P 0 
L 2.7566 3.30943996 2.7566 3.30278996 3 P 0 
L 2.7566 3.30278996 2.79438996 3.265 3 P 0 
L 2.79438996 3.265 2.8983 3.265 3 P 0 
L 2.8983 3.265 2.903 3.2697 3 P 0 
L 2.903 3.2697 2.903 3.294 3 P 0 
L 2.903 3.294 2.896 3.301 3 P 0 
L 4.5 4.165 4.455 4.21 3 P 0 
L 4.455 4.21 4.2 4.21 3 P 0 
L 4.2 4.21 4.095 4.105 3 P 0 
L 4.095 4.105 3.935 4.105 3 P 0 
L 3.935 4.105 3.7423 3.9123 3 P 0 
L 3.7423 3.9123 3.7423 3.7173 3 P 0 
L 3.7423 3.7173 3.5646 3.5396 3 P 0 
L 3.5646 3.5396 3.23276998 3.5396 3 P 0 
L 3.23276998 3.5396 3.16046998 3.4673 3 P 0 
L 3.16046998 3.4673 2.96283002 3.4673 3 P 0 
L 2.96283002 3.4673 2.9037 3.40816998 3 P 0 
L 2.9037 3.40816998 2.9037 3.3087 3 P 0 
L 2.9037 3.3087 2.896 3.301 3 P 0 
P 4.5 4.165 15 P 0 8 0;1,3=1,5=1
P 1.36 2.905 11 P 0 8 0;3=11,5=1
P 2.896 3.301 11 P 0 8 0;3=11,5=1
P 0.965 1.4 12 P 0 8 0;3=3,5=1
P 1.4207 0.779 15 P 0 8 0;1,3=10,5=1
L 4.396 3.865 4.41 3.851 3 P 0 
L 4.41 3.851 4.41 3.8 3 P 0 
L 4.41 3.8 4.3 3.69 3 P 0 
L 4.3 3.69 4.3 3.575 3 P 0 
L 4.3 3.575 4.33 3.545 3 P 0 
L 4.33 3.545 4.33 3.535 3 P 0 
P 4.65933002 2.02058996 15 P 0 8 0;1,3=6,5=1
P 4.33 3.535 12 P 0 8 0;3=3,5=1
P 4.396 3.865 36 P 0 8 0;0,3=0,5=0
L 4.44 4.065 4.46 4.045 3 P 0 
L 4.46 4.045 4.46 3.81 3 P 0 
L 4.46 3.81 4.4177 3.7677 3 P 0 
L 4.4177 3.7677 4.4177 3.65876004 3 P 0 
L 4.4177 3.65876004 4.41735 3.65841004 3 P 0 
L 4.41735 3.65841004 4.41735 3.43735 3 P 0 
L 4.41735 3.43735 4.395 3.415 3 P 0 
P 4.396 4.065 36 P 0 8 0;0,3=0,5=0
L 4.44 4.065 4.396 4.065 3 P 0 
P 4.44 4.065 15 P 0 8 0;1,3=5,5=1
P 4.61996004 2.05996004 11 P 0 8 0;3=2,5=1
P 4.395 3.415 11 P 0 8 0;3=11,5=1
L 4.425 3.36088996 4.4371 3.37298996 3 P 0 
L 4.4371 3.37298996 4.4371 3.76263002 3 P 0 
L 4.4371 3.76263002 4.4773 3.80283002 3 P 0 
L 4.4773 3.80283002 4.4773 4.0777 3 P 0 
L 4.4773 4.0777 4.44 4.115 3 P 0 
P 4.396 4.115 36 P 0 8 0;0,3=0,5=0
L 4.44 4.115 4.396 4.115 3 P 0 
P 4.44 4.115 15 P 0 8 0;1,3=5,5=1
P 4.61996004 2.09933002 11 P 0 8 0;3=2,5=1
P 4.425 3.36088996 11 P 0 8 0;3=11,5=1
P 0.638 2.74 11 P 0 8 0;3=11,5=1
L 0.825 2.305 0.83 2.31 3 P 0 
L 0.83 2.31 0.83 2.36023996 3 P 0 
L 0.83 2.36023996 0.805 2.38523996 3 P 0 
L 0.805 2.38523996 0.805 2.402 3 P 0 
P 0.805 2.402 32 P 0 8 0;0,3=0,5=0
P 0.825 2.305 15 P 0 8 0;1,3=5,5=1
P 0.755 2.825 11 P 0 8 0;3=11,5=1
L 0.795 2.345 0.795 2.34948996 3 P 0 
L 0.795 2.34948996 0.76 2.38448996 3 P 0 
L 0.76 2.38448996 0.76 2.402 3 P 0 
P 0.76 2.402 32 P 0 8 0;0,3=0,5=0
P 0.795 2.345 15 P 0 8 0;1,3=5,5=1
L 5.97613002 4.13778996 5.98291998 4.131 3 P 0 
L 5.98291998 4.131 6.025 4.131 3 P 0 
P 6.025 4.131 32 P 0 8 0;0,3=0,5=0
P 5.97613002 4.13778996 15 P 0 8 0;1,3=1,5=1
L 5.90748002 4.18725 5.91 4.18473002 3 P 0 
L 5.91 4.18473002 5.91 4.131 3 P 0 
P 5.91 4.131 32 P 0 8 0;0,3=0,5=0
P 5.90748002 4.18725 15 P 0 8 0;1,3=1,5=1
P 4.06878996 2.02058996 11 P 0 8 0;3=2,5=1
P 0.905 1.935 15 P 0 8 0;1,3=1,5=1
P 3.99005 2.05996004 11 P 0 8 0;3=2,5=1
P 0.945 1.97 15 P 0 8 0;1,3=1,5=1
P 4.02941998 2.05996004 11 P 0 8 0;3=2,5=1
P 0.905 1.885 15 P 0 8 0;1,3=1,5=1
L 0.985 2.185 0.965 2.185 3 P 0 
L 0.965 2.185 0.905 2.125 3 P 0 
L 0.905 2.125 0.655 2.125 3 P 0 
L 0.655 2.125 0.63 2.15 3 P 0 
P 0.63 2.15 12 P 0 8 0;3=3,5=1
P 3.95066998 2.02058996 11 P 0 8 0;3=2,5=1
P 0.985 2.185 15 P 0 8 0;1,3=1,5=1
P 0.287 2.62508002 12 P 0 8 0;3=3,5=1
L 0.99 2.015 0.965 2.04 3 P 0 
L 0.965 2.04 0.915 2.04 3 P 0 
L 0.915 2.04 0.85 2.105 3 P 0 
L 0.85 2.105 0.63 2.105 3 P 0 
P 0.43 2.555 15 P 0 8 0;1,3=1,5=1
P 3.95066998 1.98121998 11 P 0 8 0;3=2,5=1
P 0.63 2.105 12 P 0 8 0;3=3,5=1
P 0.99 2.015 12 P 0 8 0;3=3,5=1
L 0.99 1.975 0.945 2.02 3 P 0 
L 0.945 2.02 0.9 2.02 3 P 0 
L 0.9 2.02 0.86 2.06 3 P 0 
L 0.86 2.06 0.63 2.06 3 P 0 
P 0.242 2.62508002 15 P 0 8 0;1,3=1,5=1
P 3.99005 1.98121998 11 P 0 8 0;3=2,5=1
P 0.63 2.06 12 P 0 8 0;3=3,5=1
P 0.99 1.975 12 P 0 8 0;3=3,5=1
P 4.02941998 1.82373996 11 P 0 8 0;3=2,5=1
P 0.935 1.3 15 P 0 8 0;1,3=1,5=1
P 3.95066998 1.90248002 11 P 0 8 0;3=2,5=1
P 0.87 1.255 15 P 0 8 0;1,3=1,5=1
P 3.95066998 1.86311004 11 P 0 8 0;3=2,5=1
P 0.935 1.25 15 P 0 8 0;1,3=1,5=1
L 0.281 1.48798002 0.31805 1.52503002 3 P 0 
L 0.31805 1.52503002 0.43135 1.52503002 3 P 0 
L 0.43135 1.52503002 0.45305 1.50333002 3 P 0 
L 0.45305 1.50333002 0.45305 1.465 3 P 0 
L 0.45305 1.465 0.43 1.44195 3 P 0 
L 0.43 1.44195 0.43 1.39 3 P 0 
L 0.43 1.39 0.45 1.37 3 P 0 
L 0.45 1.37 0.46998996 1.37 3 P 0 
L 0.46998996 1.37 0.47028996 1.3697 3 P 0 
L 0.47028996 1.3697 0.4777 1.3697 3 P 0 
L 0.4777 1.3697 0.488 1.3594 3 P 0 
L 0.488 1.3594 0.53718996 1.3594 3 P 0 
L 0.53718996 1.3594 0.54158996 1.355 3 P 0 
L 0.54158996 1.355 0.61766004 1.355 3 P 0 
L 0.61766004 1.355 0.62206004 1.3594 3 P 0 
L 0.62206004 1.3594 0.76218002 1.3594 3 P 0 
L 0.76218002 1.3594 0.77188002 1.3497 3 P 0 
L 0.77188002 1.3497 0.97968996 1.3497 3 P 0 
L 0.97968996 1.3497 1.02 1.39001004 3 P 0 
L 1.02 1.39001004 1.02 1.60501004 3 P 0 
L 1.02 1.60501004 1.00266004 1.62235 3 P 0 
L 1.00266004 1.62235 0.97158996 1.62235 3 P 0 
L 0.97158996 1.62235 0.94923996 1.6 3 P 0 
L 0.94923996 1.6 0.935 1.6 3 P 0 
L 0.935 1.6 0.91 1.625 3 P 0 
L 0.91 1.625 0.91 1.72 3 P 0 
L 0.91 1.72 0.92 1.73 3 P 0 
P 4.06878996 1.94185 11 P 0 8 0;3=2,5=1
P 0.92 1.73 15 P 0 8 0;1,3=1,5=1
P 0.281 1.48798002 12 P 0 8 0;3=3,5=1
P 4.06878996 1.86311004 11 P 0 8 0;3=2,5=1
L 0.985 1.655 0.995 1.655 3 P 0 
L 0.995 1.655 1.0347 1.6153 3 P 0 
L 1.0347 1.6153 1.0347 1.38391998 3 P 0 
L 1.0347 1.38391998 0.98578002 1.335 3 P 0 
L 0.98578002 1.335 0.76578996 1.335 3 P 0 
L 0.76578996 1.335 0.75608996 1.3447 3 P 0 
L 0.75608996 1.3447 0.62815 1.3447 3 P 0 
L 0.62815 1.3447 0.61845 1.335 3 P 0 
L 0.61845 1.335 0.5408 1.335 3 P 0 
L 0.5408 1.335 0.5311 1.3447 3 P 0 
L 0.5311 1.3447 0.48191004 1.3447 3 P 0 
L 0.48191004 1.3447 0.47161004 1.355 3 P 0 
L 0.47161004 1.355 0.435 1.355 3 P 0 
L 0.435 1.355 0.415 1.375 3 P 0 
L 0.415 1.375 0.415 1.45001004 3 P 0 
L 0.415 1.45001004 0.43835 1.47336004 3 P 0 
L 0.43835 1.47336004 0.43835 1.49723996 3 P 0 
L 0.43835 1.49723996 0.42526004 1.51033002 3 P 0 
L 0.42526004 1.51033002 0.39335 1.51033002 3 P 0 
L 0.39335 1.51033002 0.371 1.48798002 3 P 0 
P 0.985 1.655 15 P 0 8 0;1,3=1,5=1
P 0.371 1.48798002 12 P 0 8 0;3=3,5=1
P 4.06878996 1.82373996 11 P 0 8 0;3=2,5=1
L 0.985 1.59 1.005 1.57 3 P 0 
L 1.005 1.57 1.005 1.40838996 3 P 0 
L 1.005 1.40838996 0.97426004 1.37765 3 P 0 
L 0.97426004 1.37765 0.86973996 1.37765 3 P 0 
L 0.86973996 1.37765 0.80208996 1.4453 3 P 0 
L 0.80208996 1.4453 0.6653 1.4453 3 P 0 
L 0.6653 1.4453 0.59308002 1.37308002 3 P 0 
L 0.59308002 1.37308002 0.54581004 1.37308002 3 P 0 
L 0.54581004 1.37308002 0.50735 1.41121004 3 P 0 
L 0.50735 1.41121004 0.50735 1.41841004 3 P 0 
L 0.50735 1.41841004 0.495 1.43076004 3 P 0 
L 0.495 1.43076004 0.495 1.485 3 P 0 
L 0.495 1.485 0.42 1.56 3 P 0 
L 0.42 1.56 0.30801998 1.56 3 P 0 
L 0.30801998 1.56 0.236 1.48798002 3 P 0 
P 0.985 1.59 15 P 0 8 0;1,3=1,5=1
P 0.236 1.48798002 12 P 0 8 0;3=3,5=1
P 0.345 3.09 12 P 0 8 0;3=3,5=1
P 3.84091004 2.00091004 15 P 0 8 0;1,3=1,5=1
P 0.99 1.885 12 P 0 8 0;3=3,5=1
P 0.395 3.09 12 P 0 8 0;3=3,5=1
P 3.87193002 2.09933002 15 P 0 8 0;1,3=6,5=1
P 0.99 2.065 12 P 0 8 0;3=3,5=1
P 0.445 3.09 15 P 0 8 0;1,3=1,5=1
P 3.9113 2.09933002 11 P 0 8 0;3=2,5=1
P 0.975 2.14 12 P 0 8 0;3=3,5=1
L 0.53 2.049 0.53 2.005 3 P 0 
P 0.53 2.049 32 P 0 8 0;0,3=0,5=0
P 0.53 2.005 15 P 0 8 0;1,3=1,5=1
L 0.552 2.535 0.53 2.557 3 P 0 
L 0.53 2.557 0.53 2.584 3 P 0 
P 0.53 2.584 32 P 0 8 0;0,3=0,5=0
P 0.552 2.535 15 P 0 8 0;1,3=1,5=1
P 0.455 1.825 15 P 0 8 0;1,3=1,5=1
P 0.16038996 1.85433002 18 P 0 8 0;3=16,5=0
P 0.46 2.195 15 P 0 8 0;1,3=1,5=1
P 0.16038996 2.4252 18 P 0 8 0;1,3=16,5=0
L 0.445 0.735 0.475 0.735 3 P 0 
L 0.475 0.735 0.513 0.697 3 P 0 
L 0.513 0.697 0.53 0.697 3 P 0 
P 0.445 0.735 15 P 0 8 0;1,3=1,5=1
P 0.53 0.697 32 P 0 8 0;0,3=0,5=0
P 0.16038996 0.7126 18 P 0 8 0;1,3=16,5=0
P 0.455 1.0439 15 P 0 8 0;1,3=1,5=1
P 0.16038996 1.28346004 18 P 0 8 0;3=16,5=0
P 0.535 1.835 15 P 0 8 0;1,3=1,5=1
P 0.532 2.40186998 15 P 0 8 0;1,3=1,5=1
L 0.505 0.60228002 0.51771998 0.60228002 3 P 0 
L 0.51771998 0.60228002 0.53 0.61456004 3 P 0 
L 0.53 0.61456004 0.53 0.655 3 P 0 
P 0.53 0.655 32 P 0 8 0;0,3=0,5=0
P 0.505 0.60228002 15 P 0 8 0;1,3=1,5=1
P 0.5374 1.26 15 P 0 8 0;1,3=1,5=1
P 0.48 2.005 15 P 0 8 0;1,3=1,5=1
P 0.485 2.525 15 P 0 8 0;1,3=1,5=1
P 0.515 0.835 15 P 0 8 0;1,3=1,5=1
P 0.475 1.405 15 P 0 8 0;1,3=1,5=1
L 6.379 0.965 6.335 0.965 3 P 0 
P 6.379 0.965 36 P 0 8 0;0,3=0,5=0
P 6.335 0.965 15 P 0 8 0;1,3=1,5=1
L 6.379 1.02 6.335 1.02 3 P 0 
P 6.379 1.02 36 P 0 8 0;0,3=0,5=0
P 6.335 1.02 15 P 0 8 0;1,3=1,5=1
L 6.379 1.08 6.335 1.08 3 P 0 
P 6.379 1.08 36 P 0 8 0;0,3=0,5=0
P 6.335 1.08 15 P 0 8 0;1,3=1,5=1
L 2.085 3.017 2.083 3.015 3 P 0 
L 2.083 3.015 2.083 2.973 3 P 0 
P 2.085 3.017 15 P 0 8 0;1,3=10,5=1
P 2.083 2.973 32 P 0 8 0;0,3=0,5=0
L 2.128 2.973 2.128 3.01 3 P 0 
L 2.128 3.01 2.135 3.017 3 P 0 
P 2.135 3.017 15 P 0 8 0;1,3=10,5=1
P 2.128 2.973 32 P 0 8 0;0,3=0,5=0
L 2.173 2.973 2.173 3.005 3 P 0 
L 2.173 3.005 2.185 3.017 3 P 0 
P 2.185 3.017 15 P 0 8 0;1,3=10,5=1
P 2.173 2.973 32 P 0 8 0;0,3=0,5=0
P 2.9715 2.278 44 P 0 8 0;0,3=17,5=0
L 2.9715 2.278 2.9715 2.2515 3 P 0 
L 2.9715 2.2515 2.96 2.24 3 P 0 
L 2.96 2.24 2.9365 2.24 3 P 0 
L 2.9365 2.24 2.925 2.2285 3 P 0 
P 2.9665 2.18 44 P 0 8 0;0,3=17,5=0
L 2.9665 2.18 2.955 2.18 3 P 0 
L 2.955 2.18 2.925 2.21 3 P 0 
L 2.925 2.21 2.925 2.2285 3 P 0 
P 2.925 2.2285 15 P 0 8 0;1,3=14,5=1
L 2.91 2.299 2.931 2.278 3 P 0 
L 2.931 2.278 2.9715 2.278 3 P 0 
P 2.91 2.299 32 P 0 8 0;0,3=0,5=0
P 3.0585 2.315 44 P 0 8 0;0,3=17,5=0
L 2.95 2.13 2.895 2.185 3 P 0 
L 2.895 2.185 2.895 2.2103 3 P 0 
L 2.895 2.2103 2.8833 2.222 3 P 0 
L 2.8833 2.222 2.845 2.222 3 P 0 
L 3.0585 2.315 3.025 2.315 3 P 0 
L 3.025 2.315 3.01365 2.30365 3 P 0 
L 3.01365 2.30365 3.01365 2.16268002 3 P 0 
L 3.01365 2.16268002 2.99596998 2.145 3 P 0 
L 2.99596998 2.145 2.965 2.145 3 P 0 
L 2.965 2.145 2.95 2.13 3 P 0 
P 2.95 2.13 15 P 0 8 0;1,3=14,5=1
P 2.845 2.222 38 P 0 8 0;0,3=8,5=0
L 2.845 2.222 2.845 2.272 3 P 0 
L 2.845 2.272 2.85 2.277 3 P 0 
P 2.85 2.277 43 P 0 8 0;0,3=12,5=0
P 6.0085 1.1235 15 P 0 8 0;1,3=1,5=1
P 2.22 3.3 15 P 0 8 0;1,3=10,5=1
P 5.8 1.048 15 P 0 8 0;1,3=4,5=0
P 4.34436998 2.02058996 11 P 0 8 0;3=2,5=1
P 5.285 2.99 11 P 0 8 0;3=11,5=1
P 3.125 3.075 12 P 0 8 0;3=3,5=1
P 4.34436998 2.17806998 11 P 0 8 0;3=2,5=1
P 2.017 3.279 15 P 0 8 0;1,3=4,5=0
L 0.5505 2.9772 0.58808996 2.9772 3 P 0 
L 0.58808996 2.9772 0.636 2.92928996 3 P 0 
L 0.636 2.92928996 0.636 2.915 3 P 0 
L 2.97 3.105 2.88098002 3.105 3 P 0 
L 2.88098002 3.105 2.65548002 3.3305 3 P 0 
L 2.65548002 3.3305 2.40638996 3.3305 3 P 0 
L 2.40638996 3.3305 2.3219 3.24601004 3 P 0 
L 2.3219 3.24601004 2.3219 2.85688996 3 P 0 
L 2.3219 2.85688996 2.26001004 2.795 3 P 0 
L 2.26001004 2.795 1.64446998 2.795 3 P 0 
L 1.64446998 2.795 1.59716998 2.8423 3 P 0 
L 1.59716998 2.8423 1.2777 2.8423 3 P 0 
L 1.2777 2.8423 1.19 2.93 3 P 0 
L 1.19 2.93 1.02 2.93 3 P 0 
L 1.02 2.93 0.96965 2.87965 3 P 0 
L 0.96965 2.87965 0.92035 2.87965 3 P 0 
L 0.92035 2.87965 0.88 2.92 3 P 0 
L 0.88 2.92 0.82 2.92 3 P 0 
L 0.82 2.92 0.79 2.89 3 P 0 
L 0.79 2.89 0.7037 2.89 3 P 0 
L 0.7037 2.89 0.699 2.8947 3 P 0 
L 0.699 2.8947 0.699 2.915 3 P 0 
L 0.636 2.915 0.699 2.915 3 P 0 
P 0.636 2.915 15 P 0 8 0;3=4,5=0
P 0.5505 2.9772 46 P 0 8 0;0,3=18,5=0
P 0.699 2.915 36 P 0 8 0;0,3=0,5=0
P 4.38373996 2.17806998 11 P 0 8 0;3=2,5=1
P 2.97 3.105 15 P 0 8 0;1,3=1,5=1
L 5.91 2.785 5.915 2.79 3 P 0 
L 5.915 2.79 5.994 2.79 3 P 0 
P 5.91 2.785 15 P 0 8 0;1,3=1,5=1
P 5.994 2.79 36 P 0 8 0;0,3=0,5=0
L 5.994 2.615 5.96776998 2.615 3 P 0 
L 5.96776998 2.615 5.96306998 2.6103 3 P 0 
L 5.96306998 2.6103 5.96306998 2.5895 3 P 0 
L 5.96306998 2.5895 5.95836998 2.5848 3 P 0 
L 5.95836998 2.5848 5.94306998 2.5848 3 P 0 
L 5.94306998 2.5848 5.93836998 2.5895 3 P 0 
L 5.93836998 2.5895 5.93836998 2.6103 3 P 0 
L 5.93836998 2.6103 5.93366998 2.615 3 P 0 
L 5.93366998 2.615 5.91 2.615 3 P 0 
P 5.994 2.615 36 P 0 8 0;0,3=0,5=0
P 5.91 2.615 15 P 0 8 0;1,3=10,5=1
P 5.91 2.915 15 P 0 8 0;1,3=1,5=1
P 5.91 2.715 15 P 0 8 0;1,3=1,5=1
P 0.54 2.135 12 P 0 8 0;3=3,5=1
P 0.67 1.09 15 P 0 8 0;1,3=1,5=1
P 4.61996004 1.66626998 11 P 0 8 0;3=2,5=1
L 0.965 2.355 0.98935 2.33065 3 P 0 
L 0.98935 2.33065 0.98935 2.25435 3 P 0 
L 0.98935 2.25435 0.955 2.22 3 P 0 
L 0.955 2.22 0.81 2.22 3 P 0 
L 0.81 2.22 0.765 2.175 3 P 0 
L 0.765 2.175 0.615 2.175 3 P 0 
L 0.615 2.175 0.6 2.16 3 P 0 
L 0.6 2.16 0.55498996 2.16 3 P 0 
L 0.55498996 2.16 0.54498996 2.17 3 P 0 
L 0.54498996 2.17 0.48568996 2.17 3 P 0 
L 0.48568996 2.17 0.45 2.13431004 3 P 0 
L 0.45 2.13431004 0.45 2.13 3 P 0 
P 4.67901998 2.07965 14 P 0 8 0;0,3=19,5=0
L 4.67901998 2.07965 4.6987 2.09933002 3 P 0 
P 0.45 2.13 12 P 0 8 0;3=3,5=1
P 4.6987 2.09933002 11 P 0 8 0;3=2,5=1
P 0.965 2.355 15 P 0 8 0;1,3=1,5=1
P 4.5806 1.70563996 11 P 0 8 0;3=2,5=1
P 0.735 1.125 15 P 0 8 0;1,3=1,5=1
P 0.48231998 2.6453 12 P 0 8 0;3=3,5=1
L 3.755 3.505 3.65035 3.40035 3 P 0 
L 3.65035 3.40035 3.65035 3.18035 3 P 0 
L 3.65035 3.18035 3.56 3.09 3 P 0 
L 3.56 3.09 3.54576004 3.09 3 P 0 
L 3.54576004 3.09 3.52341004 3.11235 3 P 0 
L 3.52341004 3.11235 3.49658996 3.11235 3 P 0 
L 3.49658996 3.11235 3.48158996 3.09735 3 P 0 
L 3.48158996 3.09735 3.44658996 3.09735 3 P 0 
L 3.44658996 3.09735 3.42923996 3.08 3 P 0 
L 3.42923996 3.08 3.34161004 3.08 3 P 0 
L 3.34161004 3.08 3.28161004 3.14 3 P 0 
L 3.28161004 3.14 3.08 3.14 3 P 0 
L 3.08 3.14 3.005 3.065 3 P 0 
L 3.005 3.065 2.8965 3.065 3 P 0 
L 2.8965 3.065 2.6483 3.3132 3 P 0 
L 2.6483 3.3132 2.41356004 3.3132 3 P 0 
L 2.41356004 3.3132 2.3392 3.23883996 3 P 0 
L 2.3392 3.23883996 2.3392 2.8442 3 P 0 
L 2.3392 2.8442 2.27 2.775 3 P 0 
L 2.27 2.775 1.64 2.775 3 P 0 
L 1.64 2.775 1.59 2.825 3 P 0 
L 1.59 2.825 1.0273 2.825 3 P 0 
L 1.0273 2.825 1.005 2.8473 3 P 0 
P 4.71838996 2.11901998 14 P 0 8 0;0,3=19,5=0
L 4.71838996 2.11901998 4.71838002 2.11901998 3 P 0 
L 4.71838002 2.11901998 4.6987 2.1387 3 P 0 
L 1.005 2.8473 0.98995 2.86235 3 P 0 
L 0.98995 2.86235 0.91265 2.86235 3 P 0 
L 0.91265 2.86235 0.875 2.9 3 P 0 
L 0.875 2.9 0.87121004 2.9 3 P 0 
L 0.87121004 2.9 0.86933996 2.90186998 3 P 0 
L 0.86933996 2.90186998 0.84666004 2.90186998 3 P 0 
L 0.84666004 2.90186998 0.84478996 2.9 3 P 0 
L 0.84478996 2.9 0.8397 2.9 3 P 0 
L 0.8397 2.9 0.83 2.8903 3 P 0 
L 0.83 2.8903 0.83 2.855 3 P 0 
L 0.83 2.855 0.755 2.78 3 P 0 
L 0.755 2.78 0.525 2.78 3 P 0 
P 1.005 2.8473 15 P 0 8 0;1,3=14,5=1
P 3.755 3.505 11 P 0 8 0;3=11,5=1
P 4.6987 2.1387 11 P 0 8 0;3=2,5=1
P 0.525 2.78 12 P 0 8 0;3=3,5=1
L 0.905 1.05 0.79765 1.15735 3 P 0 
L 0.79765 1.15735 0.72158996 1.15735 3 P 0 
L 0.72158996 1.15735 0.68688996 1.12265 3 P 0 
L 0.68688996 1.12265 0.65451998 1.12265 3 P 0 
L 0.65451998 1.12265 0.64486998 1.113 3 P 0 
L 0.64486998 1.113 0.623 1.113 3 P 0 
L 0.623 1.113 0.51765 1.00765 3 P 0 
L 0.51765 1.00765 0.51765 0.966 3 P 0 
P 4.6 0.76 12 P 0 8 0;3=3,5=1
P 4.61996004 1.78436998 11 P 0 8 0;3=2,5=1
P 0.905 1.05 12 P 0 8 0;3=3,5=1
P 4.175 0.75 12 P 0 8 0;3=3,5=1
P 0.51765 0.966 15 P 0 8 0;1,3=5,5=1
P 2.078 0.8301 12 P 0 8 0;3=3,5=1
P 4.639 1.755 36 P 0 8 0;0,3=0,5=0
L 4.639 1.755 4.639 1.76403996 3 P 0 
L 4.639 1.76403996 4.65933002 1.78436998 3 P 0 
P 0.46 0.82 15 P 0 8 0;1,3=5,5=1
P 4.65933002 1.78436998 11 P 0 8 0;3=2,5=1
P 0.5413 1.525 15 P 0 8 0;1,3=1,5=1
P 4.61996004 1.70563996 11 P 0 8 0;3=2,5=1
P 0.625 1.005 12 P 0 8 0;3=3,5=1
P 4.67901004 1.68595 14 P 0 8 0;0,3=19,5=0
L 4.67901004 1.68595 4.67901004 1.68596004 3 P 0 
L 4.67901004 1.68596004 4.65933002 1.70563996 3 P 0 
L 0.935 1.105 0.905 1.135 3 P 0 
L 0.905 1.135 0.905 1.205 3 P 0 
L 0.905 1.205 0.88735 1.22265 3 P 0 
L 0.88735 1.22265 0.79761004 1.22265 3 P 0 
L 0.79761004 1.22265 0.76121004 1.25905 3 P 0 
L 0.76121004 1.25905 0.64801004 1.25905 3 P 0 
L 0.64801004 1.25905 0.63126004 1.2423 3 P 0 
L 0.63126004 1.2423 0.5823 1.2423 3 P 0 
L 0.5823 1.2423 0.56375 1.22375 3 P 0 
L 0.56375 1.22375 0.49125 1.22375 3 P 0 
L 0.49125 1.22375 0.485 1.23 3 P 0 
L 0.485 1.23 0.485 1.28201998 3 P 0 
L 0.485 1.28201998 0.4839 1.28311998 3 P 0 
P 4.65933002 1.70563996 11 P 0 8 0;3=2,5=1
P 0.935 1.105 15 P 0 8 0;1,3=1,5=1
P 0.4839 1.28311998 12 P 0 8 0;3=3,5=1
P 1.128 0.666 15 P 0 8 0;1,3=5,5=1
L 5.97613002 4.27558002 5.99071004 4.261 3 P 0 
L 5.99071004 4.261 6.027 4.261 3 P 0 
P 6.027 4.261 32 P 0 8 0;0,3=0,5=0
P 5.97613002 4.27558002 15 P 0 8 0;1,3=1,5=1
L 0.635 0.845 0.6075 0.8725 3 P 0 
L 0.6075 0.8725 0.6075 0.9225 3 P 0 
L 0.6075 0.9225 0.655 0.97 3 P 0 
L 0.655 0.97 0.655 1.025 3 P 0 
L 0.655 1.025 0.71266998 1.08266998 3 P 0 
L 0.71266998 1.08266998 0.83731998 1.08266998 3 P 0 
L 0.83731998 1.08266998 0.89731998 1.02266998 3 P 0 
L 0.89731998 1.02266998 0.96268002 1.02266998 3 P 0 
L 0.96268002 1.02266998 0.97733002 1.03731998 3 P 0 
L 0.97733002 1.03731998 0.97733002 1.27311998 3 P 0 
L 0.97733002 1.27311998 1.05 1.34578996 3 P 0 
L 1.05 1.34578996 1.05 1.63576004 3 P 0 
L 1.05 1.63576004 0.99841004 1.68735 3 P 0 
L 0.99841004 1.68735 0.97158996 1.68735 3 P 0 
L 0.97158996 1.68735 0.945 1.66076004 3 P 0 
L 0.945 1.66076004 0.945 1.63 3 P 0 
P 4.14753002 1.86311004 11 P 0 8 0;3=2,5=1
P 0.945 1.63 12 P 0 8 0;3=3,5=1
P 0.635 0.845 15 P 0 8 0;1,3=4,5=0
L 0.644 0.7 0.635 0.709 3 P 0 
L 0.635 0.709 0.635 0.79 3 P 0 
L 0.635 0.79 0.67 0.825 3 P 0 
L 0.67 0.825 0.67 0.865 3 P 0 
L 0.67 0.865 0.635 0.9 3 P 0 
L 0.635 0.9 0.635 0.925 3 P 0 
L 0.635 0.925 0.67 0.96 3 P 0 
L 0.67 0.96 0.67 1.015 3 P 0 
L 0.67 1.015 0.71885 1.06385 3 P 0 
L 0.71885 1.06385 0.83115 1.06385 3 P 0 
L 0.83115 1.06385 0.89 1.005 3 P 0 
L 0.89 1.005 0.97 1.005 3 P 0 
L 0.97 1.005 0.995 1.03 3 P 0 
L 0.995 1.03 0.995 1.27 3 P 0 
L 0.995 1.27 1.0647 1.3397 3 P 0 
L 1.0647 1.3397 1.0647 1.642 3 P 0 
L 1.0647 1.642 0.9867 1.72 3 P 0 
L 0.9867 1.72 0.975 1.72 3 P 0 
L 0.555 0.59 0.555 0.6 3 P 0 
L 0.555 0.6 0.55708002 0.60208002 3 P 0 
L 0.55708002 0.60208002 0.55708002 0.60228002 3 P 0 
L 0.55708002 0.60228002 0.577 0.6222 3 P 0 
L 0.577 0.6222 0.577 0.655 3 P 0 
P 4.1869 1.86311004 11 P 0 8 0;3=2,5=1
P 0.975 1.72 12 P 0 8 0;3=3,5=1
L 0.644 0.7 0.599 0.655 3 P 0 
L 0.599 0.655 0.577 0.655 3 P 0 
P 0.644 0.7 15 P 0 8 0;1,3=4,5=0
P 0.555 0.59 15 P 0 8 0;1,3=1,5=1
P 0.577 0.655 32 P 0 8 0;0,3=0,5=0
P 3.935 3.91 15 P 0 8 0;1,3=10,5=1
P 0.835 1.885 12 P 0 8 0;3=3,5=1
P 3.885 3.91 15 P 0 8 0;1,3=10,5=1
P 0.835 1.93 12 P 0 8 0;3=3,5=1
P 3.985 3.91 15 P 0 8 0;1,3=10,5=1
P 0.835 1.78 12 P 0 8 0;3=3,5=1
P 0.645 1.295 15 P 0 8 0;1,3=4,5=0
P 4.1869 1.90248002 11 P 0 8 0;3=2,5=1
P 0.955 1.92 12 P 0 8 0;3=3,5=1
P 0.565 1.13 15 P 0 8 0;3=4,5=0
P 4.14753002 1.90248002 11 P 0 8 0;3=2,5=1
P 0.885 1.49 15 P 0 8 0;1,3=1,5=1
P 0.99 1.755 12 P 0 8 0;3=3,5=1
P 3.935 4 11 P 0 8 0;3=11,5=1
P 0.332 2.62508002 15 P 0 8 0;1,3=1,5=1
P 3.885 4 11 P 0 8 0;3=11,5=1
P 0.405 2.62 15 P 0 8 0;1,3=1,5=1
P 3.985 4 11 P 0 8 0;3=11,5=1
P 0.19 2.625 15 P 0 8 0;1,3=1,5=1
P 0.62 1.995 15 P 0 8 0;1,3=4,5=0
P 4.34436998 1.82373996 11 P 0 8 0;3=2,5=1
P 0.75 1.417 12 P 0 8 0;3=3,5=1
L 0.952 1.51 0.99 1.472 3 P 0 
L 0.99 1.472 0.99 1.44 3 P 0 
L 0.99 1.44 0.97235 1.42235 3 P 0 
L 0.97235 1.42235 0.88826004 1.42235 3 P 0 
L 0.88826004 1.42235 0.87526004 1.43535 3 P 0 
L 0.87526004 1.43535 0.83965 1.43535 3 P 0 
L 0.83965 1.43535 0.815 1.46 3 P 0 
L 0.815 1.46 0.645 1.46 3 P 0 
L 0.645 1.46 0.62 1.485 3 P 0 
L 0.62 1.485 0.58838996 1.485 3 P 0 
L 0.58838996 1.485 0.57365 1.49973996 3 P 0 
L 0.57365 1.49973996 0.57365 1.59135 3 P 0 
L 0.57365 1.59135 0.545 1.62 3 P 0 
L 0.545 1.62 0.545 1.71 3 P 0 
P 4.26563996 1.82373996 11 P 0 8 0;3=2,5=1
P 0.952 1.51 15 P 0 8 0;1,3=1,5=1
P 0.545 1.71 15 P 0 8 0;3=4,5=0
L 3.98 4.185 3.955 4.21 3 P 0 
L 3.955 4.21 3.90498996 4.21 3 P 0 
L 3.90498996 4.21 3.655 3.96001004 3 P 0 
L 3.655 3.96001004 3.655 3.813 3 P 0 
L 3.655 3.813 3.562 3.72 3 P 0 
L 3.562 3.72 3.31 3.72 3 P 0 
L 3.31 3.72 3.285 3.695 3 P 0 
L 3.285 3.695 3.25 3.695 3 P 0 
L 3.25 3.695 3.21 3.655 3 P 0 
L 3.21 3.655 2.89321998 3.655 3 P 0 
L 2.89321998 3.655 2.83188002 3.71633996 3 P 0 
L 2.83188002 3.71633996 2.83188002 4.22811998 3 P 0 
L 2.83188002 4.22811998 2.775 4.285 3 P 0 
L 2.775 4.285 0.83 4.285 3 P 0 
L 0.83 4.285 0.7558 4.2108 3 P 0 
L 0.7558 4.2108 0.7558 4.19003996 3 P 0 
L 0.415 1.275 0.415 1.25 3 P 0 
L 0.415 1.25 0.4659 1.1991 3 P 0 
L 0.4659 1.1991 0.52596998 1.1991 3 P 0 
L 0.52596998 1.1991 0.53331998 1.20645 3 P 0 
L 0.53331998 1.20645 0.57645 1.20645 3 P 0 
L 0.57645 1.20645 0.595 1.225 3 P 0 
L 0.595 1.225 0.63843002 1.225 3 P 0 
L 0.63843002 1.225 0.65518002 1.24175 3 P 0 
L 0.65518002 1.24175 0.75403996 1.24175 3 P 0 
L 0.75403996 1.24175 0.79578996 1.2 3 P 0 
L 0.79578996 1.2 0.87 1.2 3 P 0 
P 0.415 1.275 12 P 0 8 0;3=3,5=1
P 0.87 1.2 12 P 0 8 0;3=3,5=1
P 0.7558 4.19003996 15 P 0 8 0;1,3=10,5=1
P 3.98 4.185 11 P 0 8 0;3=11,5=1
L 4.03 4.185 3.99 4.225 3 P 0 
L 3.99 4.225 3.895 4.225 3 P 0 
L 3.895 4.225 3.635 3.965 3 P 0 
L 3.635 3.965 3.635 3.824 3 P 0 
L 3.635 3.824 3.546 3.735 3 P 0 
L 3.546 3.735 3.29998996 3.735 3 P 0 
L 3.29998996 3.735 3.27498996 3.71 3 P 0 
L 3.27498996 3.71 3.24421004 3.71 3 P 0 
L 3.24421004 3.71 3.20421004 3.67 3 P 0 
L 3.20421004 3.67 2.90323996 3.67 3 P 0 
L 2.90323996 3.67 2.84956998 3.72366998 3 P 0 
L 2.84956998 3.72366998 2.84956998 4.24043002 3 P 0 
L 2.84956998 4.24043002 2.79 4.3 3 P 0 
L 2.79 4.3 0.816 4.3 3 P 0 
L 0.816 4.3 0.706 4.19 3 P 0 
L 0.706 4.19 0.705 4.19 3 P 0 
L 0.87 1.3 0.78 1.3 3 P 0 
L 0.78 1.3 0.75 1.33 3 P 0 
L 0.75 1.33 0.63423996 1.33 3 P 0 
L 0.63423996 1.33 0.62423996 1.32 3 P 0 
L 0.62423996 1.32 0.53501004 1.32 3 P 0 
L 0.53501004 1.32 0.52501004 1.33 3 P 0 
L 0.52501004 1.33 0.465 1.33 3 P 0 
P 0.465 1.33 12 P 0 8 0;3=3,5=1
P 0.87 1.3 12 P 0 8 0;3=3,5=1
P 0.705 4.19 15 P 0 8 0;1,3=10,5=1
P 4.03 4.185 11 P 0 8 0;3=11,5=1
L 3.93 4.185 3.90501004 4.185 3 P 0 
L 3.90501004 4.185 3.675 3.95498996 3 P 0 
L 3.675 3.95498996 3.675 3.81221004 3 P 0 
L 3.675 3.81221004 3.56808996 3.7053 3 P 0 
L 3.56808996 3.7053 3.31608996 3.7053 3 P 0 
L 3.31608996 3.7053 3.29108996 3.6803 3 P 0 
L 3.29108996 3.6803 3.2603 3.6803 3 P 0 
L 3.2603 3.6803 3.215 3.635 3 P 0 
L 3.215 3.635 2.885 3.635 3 P 0 
L 2.885 3.635 2.805 3.715 3 P 0 
L 2.805 3.715 2.805 4.22 3 P 0 
L 2.805 4.22 2.755 4.27 3 P 0 
L 2.755 4.27 0.84 4.27 3 P 0 
L 0.84 4.27 0.805 4.235 3 P 0 
L 0.805 4.235 0.805 4.205 3 P 0 
L 0.89 1.105 0.81 1.185 3 P 0 
L 0.81 1.185 0.79 1.185 3 P 0 
L 0.79 1.185 0.74795 1.22705 3 P 0 
L 0.74795 1.22705 0.66126998 1.22705 3 P 0 
L 0.66126998 1.22705 0.64421998 1.21 3 P 0 
L 0.64421998 1.21 0.61 1.21 3 P 0 
L 0.61 1.21 0.59175 1.19175 3 P 0 
L 0.59175 1.19175 0.53941004 1.19175 3 P 0 
L 0.53941004 1.19175 0.53206004 1.1844 3 P 0 
L 0.53206004 1.1844 0.4556 1.1844 3 P 0 
L 0.4556 1.1844 0.39265 1.24735 3 P 0 
L 0.39265 1.24735 0.39265 1.30265 3 P 0 
L 0.39265 1.30265 0.41408996 1.32408996 3 P 0 
L 0.41408996 1.32408996 0.41408996 1.32591004 3 P 0 
P 0.41408996 1.32591004 12 P 0 8 0;3=3,5=1
P 0.89 1.105 12 P 0 8 0;3=3,5=1
P 0.805 4.205 15 P 0 8 0;1,3=1,5=1
P 3.93 4.185 11 P 0 8 0;3=11,5=1
P 0.647 2.517 15 P 0 8 0;1,3=4,5=0
P 4.22626998 1.82373996 11 P 0 8 0;3=2,5=1
P 0.939 1.552 12 P 0 8 0;3=3,5=1
L 0.957 2.275 0.927 2.245 3 P 0 
L 0.927 2.245 0.81001004 2.245 3 P 0 
L 0.81001004 2.245 0.75731004 2.1923 3 P 0 
L 0.75731004 2.1923 0.6477 2.1923 3 P 0 
L 0.6477 2.1923 0.575 2.265 3 P 0 
P 0.575 2.265 15 P 0 8 0;3=4,5=0
P 4.22626998 1.86311004 11 P 0 8 0;3=2,5=1
P 0.957 2.275 15 P 0 8 0;1,3=1,5=1
L 0.855 4.205 0.855 4.23923996 3 P 0 
L 0.855 4.23923996 0.87076004 4.255 3 P 0 
L 0.87076004 4.255 2.385 4.255 3 P 0 
L 2.385 4.255 2.41 4.23 3 P 0 
L 2.41 4.23 2.41 3.89 3 P 0 
L 2.41 3.89 2.51 3.79 3 P 0 
L 2.51 3.79 2.70501004 3.79 3 P 0 
L 2.70501004 3.79 2.88736004 3.60765 3 P 0 
L 2.88736004 3.60765 3.25926004 3.60765 3 P 0 
L 3.25926004 3.60765 3.27235 3.62073996 3 P 0 
L 3.27235 3.62073996 3.27235 3.65235 3 P 0 
L 3.27235 3.65235 3.285 3.665 3 P 0 
L 3.285 3.665 3.29658002 3.665 3 P 0 
L 3.29658002 3.665 3.32218002 3.6906 3 P 0 
L 3.32218002 3.6906 3.5806 3.6906 3 P 0 
L 3.5806 3.6906 3.69 3.8 3 P 0 
L 3.69 3.8 3.69 3.94841998 3 P 0 
L 3.69 3.94841998 3.90158002 4.16 3 P 0 
L 3.90158002 4.16 4.045 4.16 3 P 0 
L 4.045 4.16 4.125 4.24 3 P 0 
L 4.125 4.24 4.168 4.24 3 P 0 
P 4.168 4.24 11 P 0 8 0;3=11,5=1
P 0.855 4.205 11 P 0 8 0;3=11,5=1
P 0.15 2.79 15 P 0 8 0;1,3=1,5=1
P 0.326 1.487 12 P 0 8 0;3=3,5=1
L 0.9 4.205 0.90583002 4.205 3 P 0 
L 0.90583002 4.205 0.93583002 4.235 3 P 0 
L 0.93583002 4.235 2.36543002 4.235 3 P 0 
L 2.36543002 4.235 2.385 4.21543002 3 P 0 
L 2.385 4.21543002 2.385 3.89 3 P 0 
L 2.385 3.89 2.5 3.775 3 P 0 
L 2.5 3.775 2.69578996 3.775 3 P 0 
L 2.69578996 3.775 2.87783996 3.59295 3 P 0 
L 2.87783996 3.59295 3.26535 3.59295 3 P 0 
L 3.26535 3.59295 3.28705 3.61465 3 P 0 
L 3.28705 3.61465 3.28705 3.64626004 3 P 0 
L 3.28705 3.64626004 3.29108996 3.6503 3 P 0 
L 3.29108996 3.6503 3.30266998 3.6503 3 P 0 
L 3.30266998 3.6503 3.32736998 3.675 3 P 0 
L 3.32736998 3.675 3.5928 3.675 3 P 0 
L 3.5928 3.675 3.71 3.7922 3 P 0 
L 3.71 3.7922 3.71 3.94763002 3 P 0 
L 3.71 3.94763002 3.90236998 4.14 3 P 0 
L 3.90236998 4.14 4.05501004 4.14 3 P 0 
L 4.05501004 4.14 4.13001004 4.215 3 P 0 
L 4.13001004 4.215 4.18001004 4.215 3 P 0 
L 4.18001004 4.215 4.20501004 4.24 3 P 0 
L 4.20501004 4.24 4.22336998 4.24 3 P 0 
P 0.09 2.86 15 P 0 8 0;1,3=1,5=1
P 0.9 4.205 11 P 0 8 0;3=11,5=1
P 4.22336998 4.24 11 P 0 8 0;3=11,5=1
P 0.416 1.48798002 12 P 0 8 0;3=3,5=1
L 4.14 4.19 4.075 4.125 3 P 0 
L 4.075 4.125 3.90973996 4.125 3 P 0 
L 3.90973996 4.125 3.7247 3.93996004 3 P 0 
L 3.7247 3.93996004 3.7247 3.78611004 3 P 0 
L 3.7247 3.78611004 3.59858996 3.66 3 P 0 
L 3.59858996 3.66 3.33998996 3.66 3 P 0 
L 3.33998996 3.66 3.30175 3.62176004 3 P 0 
L 3.30175 3.62176004 3.30175 3.60856004 3 P 0 
L 3.30175 3.60856004 3.27143996 3.57825 3 P 0 
L 3.27143996 3.57825 2.87175 3.57825 3 P 0 
L 2.87175 3.57825 2.7 3.75 3 P 0 
L 2.7 3.75 2.49998996 3.75 3 P 0 
L 2.49998996 3.75 2.36 3.88998996 3 P 0 
L 2.36 3.88998996 2.36 4.2003 3 P 0 
L 2.36 4.2003 2.3453 4.215 3 P 0 
L 2.3453 4.215 1.075 4.215 3 P 0 
L 1.075 4.215 1.035 4.175 3 P 0 
L 1.035 4.175 1.005 4.175 3 P 0 
L 1.005 4.175 0.98 4.2 3 P 0 
P 0.09 2.79 15 P 0 8 0;1,3=1,5=1
P 0.98 4.2 11 P 0 8 0;3=11,5=1
P 4.14 4.19 11 P 0 8 0;3=11,5=1
P 0.191 1.48798002 12 P 0 8 0;3=3,5=1
P 4.10463002 3.83 15 P 0 8 0;1,3=10,5=1
P 0.33 3.145 12 P 0 8 0;3=3,5=1
P 4.05463002 3.83 15 P 0 8 0;1,3=10,5=1
P 0.43 3.145 12 P 0 8 0;3=3,5=1
P 4.15463002 3.83 15 P 0 8 0;1,3=10,5=1
P 0.18 3.145 12 P 0 8 0;3=3,5=1
P 0.869 2.672 12 P 0 8 0;3=3,5=1
P 0.871 2.713 15 P 0 8 0;1,3=5,5=1
P 0.686 2.74 11 P 0 8 0;3=11,5=1
P 0.64248002 2.58 12 P 0 8 0;3=3,5=1
P 0.736 2.525 11 P 0 8 0;3=11,5=1
P 0.714 2.329 12 P 0 8 0;3=3,5=1
P 3.429 2.468 15 P 0 8 0;1,3=5,5=1
P 3.47 2.334 32 P 0 8 0;0,3=0,5=0
L 3.47 2.334 3.50843002 2.334 3 P 0 
L 3.50843002 2.334 3.51 2.33243002 3 P 0 
P 3.51 2.33243002 12 P 0 8 0;3=3,5=1
P 3.278 2.468 15 P 0 8 0;1,3=5,5=1
P 3.243 2.547 15 P 0 8 0;1,3=5,5=1
P 3.385 2.135 15 P 0 8 0;1,3=4,5=0
P 3.24 2.36 15 P 0 8 0;1,3=5,5=1
P 3.285 2.38645 15 P 0 8 0;1,3=5,5=1
P 0.832 2.603 15 P 0 8 0;1,3=1,5=1
P 0.77963996 2.601 15 P 0 8 0;1,3=5,5=1
P 0.695 2.578 15 P 0 8 0;1,3=1,5=1
P 0.72 2.714 15 P 0 8 0;1,3=5,5=1
P 0.858 2.789 32 P 0 8 0;0,3=0,5=0
L 0.858 2.789 0.826 2.757 3 P 0 
L 0.826 2.757 0.826 2.733 3 P 0 
L 0.826 2.733 0.825 2.732 3 P 0 
P 0.825 2.732 15 P 0 8 0;1,3=5,5=1
P 6.01953002 2.18853002 15 P 0 8 0;1,3=1,5=1
P 4.366 2.975 36 P 0 8 0;0,3=0,5=0
L 4.366 2.975 4.415 2.975 3 P 0 
P 4.415 2.975 15 P 0 8 0;1,3=5,5=1
L 6.09423996 4.27558002 6.10881998 4.261 3 P 0 
L 6.10881998 4.261 6.14 4.261 3 P 0 
P 6.14 4.261 32 P 0 8 0;0,3=0,5=0
P 6.09423996 4.27558002 15 P 0 8 0;1,3=1,5=1
L 2.6526 2.1935 2.6526 2.1576 3 P 0 
L 2.6526 2.1576 2.645 2.15 3 P 0 
L 2.645 2.15 2.645 2.14 3 P 0 
P 2.645 2.14 15 P 0 8 0;1,3=14,5=1
L 2.6526 2.1935 2.6526 2.2276 3 P 0 
L 2.6526 2.2276 2.68 2.255 3 P 0 
L 2.68 2.255 2.68 2.36 3 P 0 
L 2.68 2.36 2.665 2.375 3 P 0 
L 2.665 2.375 2.641 2.375 3 P 0 
P 2.6526 2.1935 31 P 0 8 0;0,3=20,5=0
P 2.641 2.375 36 P 0 8 0;0,3=0,5=0
P 0.959 2.789 12 P 0 8 0;3=3,5=1
P 0.845 2.18 15 P 0 8 0;1,3=1,5=1
L 0.908 2.789 0.959 2.789 3 P 0 
P 0.908 2.789 32 P 0 8 0;0,3=0,5=0
P 5.955 2.39 15 P 0 8 0;1,3=4,5=0
P 5.94153002 2.205 15 P 0 8 0;1,3=10,5=1
P 6.01901998 2.001 15 P 0 8 0;1,3=10,5=1
P 5.87 1.84 15 P 0 8 0;3=4,5=0
L 3.4593 2.17 3.4493 2.18 3 P 0 
L 3.4493 2.18 3.435 2.18 3 P 0 
L 3.435 2.18 3.419 2.196 3 P 0 
L 3.419 2.196 3.419 2.21 3 P 0 
P 3.4593 2.17 15 P 0 8 0;1,3=10,5=1
P 3.419 2.21 36 P 0 8 0;0,3=0,5=0
L 3.371 2.21 3.44 2.141 3 P 0 
L 3.44 2.141 3.44 2.12 3 P 0 
P 3.44 2.12 15 P 0 8 0;1,3=1,5=1
P 3.371 2.21 36 P 0 8 0;0,3=0,5=0
P 4.34436998 1.94185 11 P 0 8 0;3=2,5=1
P 3.18 2.685 15 P 0 8 0;1,3=5,5=1
P 3.523 1.75 11 P 0 8 0;3=11,5=1
P 4.712 1.157 15 P 0 8 0;1,3=4,5=0
P 4.42311004 1.50878996 11 P 0 8 0;3=2,5=1
P 4.61996004 1.6269 15 P 0 8 0;1,3=4,5=0
P 4.29 1.235 15 P 0 8 0;1,3=4,5=0
P 4.38373996 1.46941998 11 P 0 8 0;3=2,5=1
P 4.15 1.235 15 P 0 8 0;1,3=4,5=0
P 4.34436998 1.50878996 11 P 0 8 0;3=2,5=1
P 5.035 1.49 15 P 0 8 0;1,3=4,5=0
P 4.65933002 1.58753002 11 P 0 8 0;3=2,5=1
P 4.185 1.17 15 P 0 8 0;1,3=4,5=0
P 4.34436998 1.46941998 11 P 0 8 0;3=2,5=1
P 4.816 1.258 15 P 0 8 0;1,3=4,5=0
P 4.665 1.104 15 P 0 8 0;1,3=4,5=0
P 4.38373996 1.3513 11 P 0 8 0;3=2,5=1
P 4.91 1.54 15 P 0 8 0;1,3=4,5=0
P 4.768 1.207 15 P 0 8 0;1,3=4,5=0
P 4.42311004 1.46941998 11 P 0 8 0;3=2,5=1
P 5.03 1.55 15 P 0 8 0;1,3=4,5=0
P 4.58058996 1.6269 11 P 0 8 0;3=2,5=1
P 4.828 1.103 15 P 0 8 0;1,3=4,5=0
P 4.42311004 1.43005 11 P 0 8 0;3=2,5=1
P 4.83 1.33 15 P 0 8 0;1,3=4,5=0
P 4.22 1.235 15 P 0 8 0;1,3=4,5=0
P 3.83128002 1.78371998 11 P 0 8 0;3=11,5=1
P 6.02558996 4.175 15 P 0 8 0;1,3=1,5=1
P 6.1437 4.175 15 P 0 8 0;1,3=1,5=1
P 3.87193002 1.86311004 11 P 0 8 0;3=2,5=1
P 4.14753002 2.05996004 11 P 0 8 0;3=2,5=1
P 5.83 2.97 12 P 0 8 0;3=3,5=1
P 5.89953002 2.366 15 P 0 8 0;1,3=10,5=1
L 3.256 3.475 3.256 3.49598996 3 P 0 
L 3.256 3.49598996 3.26501004 3.505 3 P 0 
L 3.26501004 3.505 3.60251998 3.505 3 P 0 
L 3.60251998 3.505 3.60876004 3.49876004 3 P 0 
L 3.60876004 3.49876004 3.61123996 3.49876004 3 P 0 
P 3.256 3.475 36 P 0 8 0;0,3=0,5=0
P 3.61123996 3.49876004 15 P 0 8 0;1,3=5,5=1
P 4.54121998 1.94185 11 P 0 8 0;3=2,5=1
L 4.22626998 1.94185 4.20541998 1.921 3 P 0 
L 4.20541998 1.921 4.178 1.921 3 P 0 
L 4.178 1.921 4.17 1.913 3 P 0 
L 4.17 1.913 4.17 1.858 3 P 0 
L 4.17 1.858 4.158 1.846 3 P 0 
L 4.158 1.846 4.095 1.846 3 P 0 
L 4.095 1.846 4.0878 1.8388 3 P 0 
L 4.0878 1.8388 4.0878 1.7778 3 P 0 
L 4.0878 1.7778 4.0766 1.7666 3 P 0 
L 4.0766 1.7666 3.9834 1.7666 3 P 0 
L 3.9834 1.7666 3.97 1.78 3 P 0 
L 3.97 1.78 3.97 1.795 3 P 0 
L 3.97 1.795 3.96133002 1.80366998 3 P 0 
L 3.96133002 1.80366998 3.80566998 1.80366998 3 P 0 
L 3.80566998 1.80366998 3.77433996 1.835 3 P 0 
L 3.77433996 1.835 3.662 1.835 3 P 0 
L 3.662 1.835 3.544 1.717 3 P 0 
L 3.544 1.717 3.29701004 1.717 3 P 0 
L 3.29701004 1.717 3.15001004 1.57 3 P 0 
L 3.15001004 1.57 2.6971 1.57 3 P 0 
L 2.6971 1.57 1.96496998 0.83786998 3 P 0 
L 1.96496998 0.83786998 1.96496998 0.76501998 3 P 0 
P 4.22626998 1.94185 11 P 0 8 0;3=2,5=1
P 1.96496998 0.76501998 15 P 0 8 0;1,3=10,5=1
P 4.1869 1.98121998 11 P 0 8 0;3=2,5=1
P 3.12 2.565 12 P 0 8 0;3=3,5=1
P 3.119 2.299 15 P 0 8 0;1,3=1,5=1
P 4.26563996 1.90248002 11 P 0 8 0;3=2,5=1
L 3.385 2.59 3.385 2.567 3 P 0 
L 3.385 2.567 3.371 2.553 3 P 0 
L 3.371 2.553 3.335 2.553 3 P 0 
P 3.335 2.553 32 P 0 8 0;0,3=0,5=0
P 3.385 2.59 15 P 0 8 0;1,3=1,5=1
L 4.1869 2.05996004 4.20703996 2.0801 3 P 0 
L 4.20703996 2.0801 4.2751 2.0801 3 P 0 
L 4.2751 2.0801 4.295 2.1 3 P 0 
L 4.295 2.1 4.295 2.20541004 3 P 0 
L 4.295 2.20541004 4.32273996 2.23315 3 P 0 
L 4.32273996 2.23315 4.32273996 2.51773996 3 P 0 
L 4.32273996 2.51773996 4.335 2.53 3 P 0 
L 4.335 2.53 4.635 2.53 3 P 0 
L 4.635 2.53 4.645 2.52 3 P 0 
L 4.645 2.52 4.645 2.31 3 P 0 
L 4.645 2.31 4.685 2.27 3 P 0 
L 4.685 2.27 4.78816004 2.27 3 P 0 
L 4.78816004 2.27 4.86816004 2.19 3 P 0 
L 4.86816004 2.19 4.965 2.19 3 P 0 
L 4.965 2.19 5.075 2.08 3 P 0 
L 5.075 2.08 5.075 2.04893996 3 P 0 
L 5.075 2.04893996 5.11393996 2.01 3 P 0 
L 5.11393996 2.01 5.155 2.01 3 P 0 
P 5.155 2.01 12 P 0 8 0;3=3,5=1
L 6.025 1.83 6.025 1.84 3 P 0 
L 6.025 1.84 6.01901998 1.84598002 3 P 0 
L 6.01901998 1.84598002 6.01901998 1.90865 3 P 0 
P 6.025 1.83 15 P 0 8 0;1,3=1,5=1
P 6.01901998 1.90865 32 P 0 8 0;0,3=0,5=0
P 4.1869 2.05996004 11 P 0 8 0;3=2,5=1
P 4.34436998 1.90248002 11 P 0 8 0;3=2,5=1
L 2.554 2.901 2.554 2.803 3 P 0 
L 2.554 2.803 2.52 2.769 3 P 0 
L 2.52 2.769 2.52 2.497 3 P 0 
L 2.52 2.497 2.551 2.466 3 P 0 
L 2.551 2.466 2.551 2.375 3 P 0 
P 2.599 2.375 36 P 0 8 0;0,3=0,5=0
L 2.599 2.375 2.551 2.375 3 P 0 
P 2.551 2.375 36 P 0 8 0;0,3=0,5=0
P 2.554 2.901 15 P 0 8 0;1,3=1,5=1
P 4.75 1.63 15 P 0 8 0;1,3=6,5=1
P 3.205 1.7 15 P 0 8 0;1,3=1,5=1
P 4.775 1.705 12 P 0 8 0;3=3,5=1
L 4.84 1.855 4.884 1.855 3 P 0 
P 4.884 1.855 36 P 0 8 0;0,3=0,5=0
P 4.84 1.855 15 P 0 8 0;1,3=1,5=1
P 4.58058996 1.82373996 11 P 0 8 0;3=2,5=1
L 4.5609 1.84343002 4.58058996 1.82373996 3 P 0 
P 4.5609 1.84343002 14 P 0 8 0;0,3=19,5=0
L 4.67901998 1.88281004 4.75281004 1.88281004 3 P 0 
L 4.75281004 1.88281004 4.75946004 1.88946004 3 P 0 
L 4.75946004 1.88946004 4.77446004 1.88946004 3 P 0 
L 4.77446004 1.88946004 4.815 1.93 3 P 0 
P 4.67901998 1.88281004 14 P 0 8 0;0,3=19,5=0
L 4.67901998 1.88281004 4.67901998 1.8828 3 P 0 
L 4.67901998 1.8828 4.65933002 1.86311004 3 P 0 
P 4.885 3.504 32 P 0 8 0;0,3=0,5=0
L 4.885 3.504 4.885 3.46 3 P 0 
P 4.65933002 1.86311004 11 P 0 8 0;3=2,5=1
P 4.815 1.93 15 P 0 8 0;1,3=1,5=1
P 4.885 3.46 12 P 0 8 0;3=3,5=1
P 4.60028996 1.8828 14 P 0 8 0;0,3=19,5=0
L 4.60028996 1.8828 4.60028996 1.88278002 3 P 0 
L 4.60028996 1.88278002 4.61996004 1.86311004 3 P 0 
P 4.61996004 1.86311004 11 P 0 8 0;3=2,5=1
P 4.83501004 3.46 15 P 0 8 0;1,3=1,5=1
P 3.125 2.254 12 P 0 8 0;3=3,5=1
P 4.26563996 1.86311004 15 P 0 8 0;1,3=6,5=1
P 3.12 2.69 12 P 0 8 0;3=3,5=1
L 4.3 3.81 4.3 3.795 3 P 0 
L 4.3 3.795 4.28 3.775 3 P 0 
L 4.28 3.775 4.28 3.53 3 P 0 
L 4.28 3.53 4.32 3.49 3 P 0 
L 4.32 3.49 4.32 3.4539 3 P 0 
L 4.32 3.4539 4.29 3.4239 3 P 0 
L 4.29 3.4239 4.29 3.26 3 P 0 
L 4.29 3.26 4.415 3.135 3 P 0 
L 4.415 3.135 4.415 3.09 3 P 0 
L 4.415 3.09 4.475 3.03 3 P 0 
L 4.475 3.03 4.54 3.03 3 P 0 
L 4.54 3.03 4.565 3.055 3 P 0 
L 5.41 0.96 5.41 0.768 3 P 0 
L 5.41 0.768 5.346 0.704 3 P 0 
L 5.346 0.704 5.346 0.654 3 P 0 
L 5.346 0.654 5.36 0.64 3 P 0 
L 5.36 0.64 5.404 0.64 3 P 0 
P 4.565 3.055 12 P 0 8 0;3=3,5=1
P 4.3 3.81 15 P 0 8 0;1,3=1,5=1
P 1.3825 3.7225 11 P 0 8 0;3=11,5=1
P 5.905 3.015 15 P 0 8 0;1,3=10,5=1
P 5.41 0.96 15 P 0 8 0;3=4,5=0
L 4.85033002 1.74933996 4.86833996 1.74933996 3 P 0 
L 4.86833996 1.74933996 4.884 1.765 3 P 0 
P 5.404 0.64 36 P 0 8 0;0,3=0,5=0
P 4.884 1.765 36 P 0 8 0;0,3=0,5=0
P 4.85033002 1.74933996 12 P 0 8 0;3=3,5=1
P 4.54121998 1.78436998 11 P 0 8 0;3=2,5=1
P 5.26 2.955 12 P 0 8 0;3=3,5=1
P 3.625 0.92 11 P 0 8 0;3=13,5=1
P 6.19961004 2.27673996 11 P 0 8 0;3=13,5=1
P 3.657 0.92 11 P 0 8 0;3=13,5=1
P 6.19961004 2.24473996 11 P 0 8 0;3=13,5=1
P 3.3255 2.1355 15 P 0 8 0;1,3=1,5=1
L 3.44 2.906 3.44 2.95 3 P 0 
P 3.35153002 2.17875 12 P 0 8 0;3=3,5=1
P 3.44 2.95 15 P 0 8 0;1,3=5,5=1
P 3.44 2.906 32 P 0 8 0;0,3=0,5=0
P 3.35 2.864 32 P 0 8 0;0,3=0,5=0
L 3.35 2.864 3.35 2.8265 3 P 0 
L 3.35 2.8265 3.3435 2.82 3 P 0 
P 3.27923002 2.21576998 12 P 0 8 0;3=3,5=1
P 3.3435 2.82 15 P 0 8 0;1,3=5,5=1
P 4.46 2.94 15 P 0 8 0;1,3=1,5=1
L 4.47 2.83 4.485 2.845 3 P 0 
L 4.485 2.845 4.524 2.845 3 P 0 
P 4.47 2.83 15 P 0 8 0;1,3=1,5=1
P 4.524 2.945 36 P 0 8 0;0,3=0,5=0
L 4.524 2.945 4.524 2.895 3 P 0 
L 4.524 2.845 4.524 2.795 3 P 0 
P 4.524 2.795 36 P 0 8 0;0,3=0,5=0
P 4.524 2.845 36 P 0 8 0;0,3=0,5=0
L 4.524 2.845 4.524 2.895 3 P 0 
P 4.524 2.895 36 P 0 8 0;0,3=0,5=0
P 5.995 1.165 12 P 0 8 0;3=3,5=1
L 3.068 3.35 3.106 3.35 10 P 0 
L 3.068 3.26 3.106 3.26 10 P 0 
P 3.106 3.26 12 P 0 8 0;3=3,5=1
P 3.068 3.26 36 P 0 8 0;0,3=0,5=0
P 3.256 3.385 36 P 0 8 0;0,3=0,5=0
L 3.256 3.34 3.256 3.385 10 P 0 
P 3.256 3.34 36 P 0 8 0;0,3=0,5=0
L 3.256 3.385 3.222 3.385 10 P 0 
P 3.222 3.385 11 P 0 8 0;3=11,5=1
P 3.068 3.35 36 P 0 8 0;0,3=0,5=0
P 3.106 3.35 11 P 0 8 0;3=11,5=1
P 1.959 3.325 12 P 0 8 0;3=3,5=1
P 3.256 3.205 36 P 0 8 0;0,3=0,5=0
L 3.256 3.205 3.222 3.205 10 P 0 
P 3.222 3.205 11 P 0 8 0;3=11,5=1
L 3.49 2.955 3.485 2.95 10 P 0 
L 3.485 2.95 3.485 2.906 10 P 0 
P 3.485 2.906 32 P 0 8 0;0,3=0,5=0
P 3.49 2.955 12 P 0 8 0;3=3,5=1
L 3.98 3.429 3.98 3.365 10 P 0 
P 3.98 3.429 32 P 0 8 0;0,3=0,5=0
P 3.98 3.365 12 P 0 8 0;3=3,5=1
P 3.744 3.37 36 P 0 8 0;0,3=0,5=0
L 3.744 3.37 3.7 3.37 10 P 0 
P 3.7 3.37 12 P 0 8 0;3=3,5=1
L 3.506 3.37 3.55 3.37 10 P 0 
P 3.506 3.37 36 P 0 8 0;0,3=0,5=0
P 3.55 3.37 12 P 0 8 0;3=3,5=1
P 4.17 3.429 32 P 0 8 0;0,3=0,5=0
L 4.17 3.429 4.17 3.375 10 P 0 
L 4.17 3.375 4.175 3.37 10 P 0 
P 4.175 3.37 12 P 0 8 0;3=3,5=1
L 3.973 3.291 3.973 3.358 10 P 0 
L 3.973 3.358 3.98 3.365 10 P 0 
P 3.973 3.291 36 P 0 8 0;0,3=0,5=0
L 3.744 3.28 3.73 3.28 10 P 0 
L 3.73 3.28 3.71 3.26 10 P 0 
P 3.744 3.28 36 P 0 8 0;0,3=0,5=0
L 3.744 3.235 3.744 3.28 10 P 0 
P 3.744 3.235 36 P 0 8 0;0,3=0,5=0
P 3.71 3.26 12 P 0 8 0;3=3,5=1
L 3.506 3.28 3.55 3.28 10 P 0 
P 3.506 3.28 36 P 0 8 0;0,3=0,5=0
P 3.55 3.28 11 P 0 8 0;3=11,5=1
P 3.414 3.235 12 P 0 8 0;3=3,5=1
P 3.41 3.04 12 P 0 8 0;3=3,5=1
P 3.548 2.856 11 P 0 8 0;3=11,5=1
P 3.5768 2.7178 12 P 0 8 0;3=3,5=1
P 3.395 2.864 32 P 0 8 0;0,3=0,5=0
P 3.395 2.82 12 P 0 8 0;3=3,5=1
L 3.395 2.864 3.395 2.82 10 P 0 
P 3.58 2.615 15 P 0 8 0;1,3=4,5=0
P 3.485 2.6 12 P 0 8 0;3=3,5=1
P 3.525 2.6 12 P 0 8 0;3=3,5=1
P 3.335 2.589 12 P 0 8 0;3=3,5=1
L 3.24 2.2075 3.24 2.22 10 P 0 
L 3.24 2.22 3.305 2.285 10 P 0 
L 3.305 2.285 3.356 2.285 10 P 0 
L 3.356 2.285 3.371 2.27 10 P 0 
L 3.371 2.27 3.371 2.255 10 P 0 
P 3.24 2.2075 12 P 0 8 0;3=3,5=1
P 3.419 2.255 36 P 0 8 0;0,3=0,5=0
L 3.419 2.255 3.371 2.255 10 P 0 
P 3.371 2.255 36 P 0 8 0;0,3=0,5=0
P 4.905 2.1675 12 P 0 8 0;3=3,5=1
L 4.884 2.025 4.85238996 2.025 10 P 0 
L 4.85238996 2.025 4.85 2.02738996 10 P 0 
P 4.884 2.025 36 P 0 8 0;0,3=0,5=0
P 4.85 2.02738996 12 P 0 8 0;3=3,5=1
P 4.926 1.975 36 P 0 8 0;0,3=0,5=0
L 4.926 1.975 4.965 1.975 10 P 0 
P 4.965 1.975 12 P 0 8 0;3=3,5=1
P 3.49128002 1.86628002 12 P 0 8 0;3=3,5=1
L 3.505 1.831 3.505 1.85256004 10 P 0 
L 3.505 1.85256004 3.49128002 1.86628002 10 P 0 
P 3.505 1.831 32 P 0 8 0;0,3=0,5=0
P 4.65933002 1.66626998 11 P 0 8 0;3=2,5=1
P 4.63965 1.68595 14 P 0 8 0;0,3=19,5=0
L 4.63965 1.68595 4.65933002 1.66626998 10 P 0 
P 3.795 2.375 12 P 0 8 0;3=3,5=1
P 3.99005 2.02058996 11 P 0 8 0;3=2,5=1
L 3.99005 2.02058996 3.97036998 2.00091004 10 P 0 
L 3.97036998 2.00091004 3.97036004 2.00091004 10 P 0 
L 3.97035 2.04028002 3.97036004 2.04028002 10 P 0 
L 3.97036004 2.04028002 3.99005 2.02058996 10 P 0 
P 3.97036004 2.00091004 14 P 0 8 0;0,3=19,5=0
P 3.97035 2.04028002 14 P 0 8 0;0,3=19,5=0
P 4.34436998 1.86311004 11 P 0 8 0;3=2,5=1
L 4.34436998 1.86311004 4.31826004 1.837 10 P 0 
L 4.31826004 1.837 4.306 1.837 10 P 0 
L 4.31006004 1.8978 4.31006004 1.89741998 10 P 0 
L 4.31006004 1.89741998 4.34436998 1.86311004 10 P 0 
P 4.306 1.837 32 P 0 8 0;0,3=0,5=0
P 4.31006004 1.8978 14 P 0 8 0;0,3=19,5=0
L 4.00973002 1.92216998 4.02941998 1.90248002 10 P 0 
P 4.02941998 1.90248002 11 P 0 8 0;3=2,5=1
P 4.0491 1.92216998 14 P 0 8 0;0,3=19,5=0
L 4.0491 1.92216998 4.0491 1.92216004 10 P 0 
L 4.0491 1.92216004 4.02941998 1.90248002 10 P 0 
P 4.00973002 1.92216998 14 P 0 8 0;0,3=19,5=0
P 3.855 1.96153996 11 P 0 8 0;3=2,5=1
P 3.93098002 1.84343002 14 P 0 8 0;0,3=19,5=0
L 3.93098002 1.84343002 3.9113 1.86311004 10 P 0 
P 3.9113 1.86311004 11 P 0 8 0;3=2,5=1
P 4.06878996 1.78436998 11 P 0 8 0;3=2,5=1
P 4.1869 1.82373996 11 P 0 8 0;3=2,5=1
L 4.1869 1.82373996 4.19508002 1.83191998 10 P 0 
L 4.19508002 1.83191998 4.19508002 1.83193002 10 P 0 
L 4.19508002 1.83193002 4.20658002 1.84343002 10 P 0 
P 4.20658002 1.84343002 14 P 0 8 0;0,3=19,5=0
S P 0
OB 4.183 2.977 I
OS 4.261 2.977
OS 4.272 2.966
OS 4.272 2.77003996063
OC 4.25885 2.756 4.290001574803 2.740001279528 N
OS 4.188 2.756
OS 4.1785 2.7655
OS 4.1785 2.8755
OS 4.178 2.876
OS 4.178 2.972
OS 4.183 2.977
OE
SE
P 3.86 2.5925 12 P 0 8 0;3=3,5=1
P 4.60028002 1.84343002 14 P 0 8 0;0,3=19,5=0
L 4.60028002 1.84343002 4.60028002 1.84341998 10 P 0 
L 4.60028002 1.84341998 4.61996004 1.82373996 10 P 0 
L 4.575 2.461 4.575 2.5 10 P 0 
L 4.324 2.975 4.278 2.929 10 P 0 
L 4.278 2.929 4.249 2.929 10 P 0 
P 4.324 2.975 36 P 0 8 0;0,3=0,5=0
P 4.48216004 1.92216004 14 P 0 8 0;0,3=19,5=0
L 4.48216004 1.92216004 4.46248002 1.90248002 10 P 0 
P 3.758 2.552 12 P 0 8 0;3=3,5=1
P 4.209 2.59 12 P 0 8 0;3=3,5=1
P 4.65933002 2.09933002 11 P 0 8 0;3=2,5=1
P 4.54121998 2.05996004 11 P 0 8 0;3=2,5=1
P 4.50185 2.17806998 11 P 0 8 0;3=2,5=1
P 4.46248002 1.90248002 11 P 0 8 0;3=2,5=1
P 4.42311004 2.02058996 11 P 0 8 0;3=2,5=1
P 4.38373996 2.1387 11 P 0 8 0;3=2,5=1
P 4.26563996 1.98121998 11 P 0 8 0;3=2,5=1
P 4.22626998 2.09933002 11 P 0 8 0;3=2,5=1
P 4.14753002 1.94185 11 P 0 8 0;3=2,5=1
P 4.10816004 2.05996004 11 P 0 8 0;3=2,5=1
P 4.06878996 2.17806998 11 P 0 8 0;3=2,5=1
P 3.95066998 2.1387 11 P 0 8 0;3=2,5=1
P 4.6987 1.98121998 11 P 0 8 0;3=2,5=1
P 4.58058996 1.94185 11 P 0 8 0;3=2,5=1
P 4.73806998 1.86311004 11 P 0 8 0;3=2,5=1
P 4.61996004 1.82373996 11 P 0 8 0;3=2,5=1
P 4.50185 1.78436998 11 P 0 8 0;3=2,5=1
L 4.61996004 1.82373996 4.63963996 1.80406004 10 P 0 
L 4.63963996 1.80406004 4.63965 1.80406004 10 P 0 
L 4.50185 2.17806998 4.49685 2.18306998 10 P 0 
L 4.49685 2.18306998 4.49685 2.22 10 P 0 
L 4.58058996 1.94185 4.60026998 1.92216998 10 P 0 
L 4.60026998 1.92216998 4.60028002 1.92216998 10 P 0 
L 4.60028002 1.96153996 4.58058996 1.94185 10 P 0 
L 4.46248002 1.90248002 4.4428 1.92216004 10 P 0 
L 4.4428 1.92216004 4.4428 1.92216998 10 P 0 
L 4.50185 1.78436998 4.50185 1.76626004 10 P 0 
L 4.50185 1.76626004 4.51311004 1.755 10 P 0 
L 4.52153996 1.80406004 4.50185 1.78436998 10 P 0 
L 4.26563996 1.98121998 4.27141998 1.987 10 P 0 
L 4.27141998 1.987 4.3 1.987 10 P 0 
L 4.22626998 2.09933002 4.24595 2.11901004 10 P 0 
L 4.24595 2.11901004 4.24595 2.11901998 10 P 0 
L 4.14753002 1.94185 4.16721004 1.96153002 10 P 0 
L 4.16721004 1.96153002 4.16721004 1.96153996 10 P 0 
L 3.95066998 2.1387 3.93098996 2.11901998 10 P 0 
L 3.93098996 2.11901998 3.93098002 2.11901998 10 P 0 
P 4.2 2.936 39 P 0 8 0;0,3=12,5=0
P 4.2 2.855 39 P 0 8 0;0,3=12,5=0
P 4.249 2.929 15 P 0 8 0;1,3=1,5=1
P 4.239 2.785 15 P 0 8 0;1,3=1,5=1
P 4.249 2.843 15 P 0 8 0;1,3=1,5=1
P 4.575 2.461 32 P 0 8 0;0,3=0,5=0
L 4.575 2.461 4.53 2.461 10 P 0 
P 4.53 2.461 32 P 0 8 0;0,3=0,5=0
P 4.575 2.5 12 P 0 8 0;3=3,5=1
P 4.395 2.461 32 P 0 8 0;0,3=0,5=0
L 4.395 2.461 4.395 2.5 10 P 0 
P 4.395 2.5 12 P 0 8 0;3=3,5=1
P 4.77 2.39 12 P 0 8 0;3=3,5=1
P 4.71 2.39 12 P 0 8 0;3=3,5=1
P 4.51311004 1.755 36 P 0 8 0;0,3=0,5=0
P 4.52153996 1.80406004 14 P 0 8 0;0,3=19,5=0
L 4.63965 1.84343002 4.61996004 1.82373996 10 P 0 
P 4.63965 1.84343002 14 P 0 8 0;0,3=19,5=0
P 4.63965 1.80406004 14 P 0 8 0;0,3=19,5=0
L 4.12783996 1.96153996 4.14753002 1.94185 10 P 0 
P 4.12783996 1.96153996 14 P 0 8 0;0,3=19,5=0
P 4.16721004 1.96153996 14 P 0 8 0;0,3=19,5=0
P 4.3 1.987 32 P 0 8 0;0,3=0,5=0
P 4.4428 1.92216998 14 P 0 8 0;0,3=19,5=0
P 4.60028002 1.92216998 14 P 0 8 0;0,3=19,5=0
P 4.60028002 1.96153996 14 P 0 8 0;0,3=19,5=0
L 4.78 1.86311004 4.73806998 1.86311004 10 P 0 
P 4.78 1.86311004 32 P 0 8 0;0,3=0,5=0
L 4.71838996 2.00091004 4.6987 1.98121998 10 P 0 
P 4.71838996 2.00091004 14 P 0 8 0;0,3=19,5=0
L 3.93098002 2.15838996 3.95066998 2.1387 10 P 0 
P 3.93098002 2.15838996 14 P 0 8 0;0,3=19,5=0
P 3.93098002 2.11901998 14 P 0 8 0;0,3=19,5=0
P 4.066 2.215 36 P 0 8 0;0,3=0,5=0
L 4.06878996 2.17806998 4.06878996 2.21221004 10 P 0 
L 4.06878996 2.21221004 4.066 2.215 10 P 0 
L 4.12783996 2.04028002 4.10816004 2.05996004 10 P 0 
P 4.12783996 2.04028002 14 P 0 8 0;0,3=19,5=0
P 4.24595 2.11901998 14 P 0 8 0;0,3=19,5=0
L 4.40343002 2.15838996 4.38373996 2.1387 10 P 0 
P 4.40343002 2.15838996 14 P 0 8 0;0,3=19,5=0
P 4.49685 2.22 36 P 0 8 0;0,3=0,5=0
P 4.52153996 2.07965 14 P 0 8 0;0,3=19,5=0
L 4.54121998 2.05996004 4.52153996 2.07963996 10 P 0 
L 4.52153996 2.07963996 4.52153996 2.07965 10 P 0 
L 4.67901998 2.11901998 4.65933002 2.09933002 10 P 0 
P 4.67901998 2.11901998 14 P 0 8 0;0,3=19,5=0
P 4.0875 2.325 42 P 0 8 0;0,3=21,5=0
P 4.075 2.25 12 P 0 8 0;3=3,5=1
L 4.075 2.25 4.075 2.3125 10 P 0 
L 4.075 2.3125 4.0875 2.325 10 P 0 
P 3.735 2.47 12 P 0 8 0;3=3,5=1
P 5.0395 1.335 12 P 0 8 0;3=3,5=1
P 4.926 1.765 36 P 0 8 0;0,3=0,5=0
P 4.97 1.75 15 P 0 8 0;1,3=1,5=1
P 4.926 1.63 36 P 0 8 0;0,3=0,5=0
L 4.926 1.63 4.96 1.63 10 P 0 
P 4.96 1.63 12 P 0 8 0;3=3,5=1
L 4.97 1.75 4.955 1.765 10 P 0 
L 4.955 1.765 4.926 1.765 10 P 0 
P 6.22 1.27063002 12 P 0 8 0;3=3,5=1
L 3.839 3.81 3.839 3.846 10 P 0 
P 3.839 3.846 12 P 0 8 0;3=3,5=1
P 3.839 3.81 36 P 0 8 0;0,3=0,5=0
P 4.384 3.824 12 P 0 8 0;3=3,5=1
L 4.95 3.46 4.9325 3.4425 10 P 0 
L 4.9325 3.4425 4.9325 3.39446004 10 P 0 
L 4.9325 3.39446004 4.95446004 3.3725 10 P 0 
L 4.95446004 3.3725 4.9925 3.3725 10 P 0 
L 4.9925 3.3725 5.19 3.175 10 P 0 
L 5.19 3.175 5.19 3.075 10 P 0 
P 4.989 3.455 36 P 0 8 0;0,3=0,5=0
L 4.989 3.455 4.955 3.455 10 P 0 
L 4.955 3.455 4.95 3.46 10 P 0 
L 6.1865 2.493 5.917 2.493 10 P 0 
L 5.917 2.493 5.865 2.545 10 P 0 
L 5.865 2.545 5.6237 2.545 10 P 0 
L 5.6237 2.545 5.62 2.5487 10 P 0 
L 5.375 3.04 5.4 3.065 10 P 0 
L 5.4 3.065 5.448 3.065 10 P 0 
L 5.448 3.065 5.452 3.061 10 P 0 
P 4.95 3.46 12 P 0 8 0;3=3,5=1
P 5.94003002 1.87 12 P 0 8 0;3=3,5=1
P 6.379 1.169 12 P 0 8 0;3=3,5=1
L 6.105 1.905 6.105 1.94 10 P 0 
L 6.105 1.94 6.09435 1.95065 10 P 0 
L 6.09435 1.95065 6.06901998 1.95065 10 P 0 
P 6.105 1.905 12 P 0 8 0;3=3,5=1
P 6.01901998 1.95065 32 P 0 8 0;0,3=0,5=0
L 6.01901998 1.95065 6.06901998 1.95065 10 P 0 
P 6.06901998 1.95065 32 P 0 8 0;0,3=0,5=0
P 5.92 1.27063002 12 P 0 8 0;3=3,5=1
P 5.88 0.965 12 P 0 8 0;3=3,5=1
P 6.47 1.08 12 P 0 8 0;3=3,5=1
P 5.19 3.075 12 P 0 8 0;3=3,5=1
P 5.375 3.04 12 P 0 8 0;3=3,5=1
P 5.452 3.061 32 P 0 8 0;0,3=0,5=0
P 5.41 2.815 12 P 0 8 0;3=3,5=1
P 5.452 2.813 32 P 0 8 0;0,3=0,5=0
P 5.544 2.675 12 P 0 8 0;3=3,5=1
L 5.544 2.721 5.544 2.675 10 P 0 
P 5.544 2.721 36 P 0 8 0;0,3=0,5=0
P 6.1865 2.493 12 P 0 8 0;3=3,5=1
P 6.141 2.364 12 P 0 8 0;3=3,5=1
P 5.85 2.265 12 P 0 8 0;3=3,5=1
P 5.62 2.5487 12 P 0 8 0;3=3,5=1
L 5.452 2.9645 5.42 2.9645 10 P 0 
P 5.42 2.9645 12 P 0 8 0;3=3,5=1
P 5.452 2.9645 32 P 0 8 0;0,3=0,5=0
P 5.91901998 1.90865 32 P 0 8 0;0,3=0,5=0
L 5.91901998 1.90865 5.91901998 1.89101004 10 P 0 
L 5.91901998 1.89101004 5.94003002 1.87 10 P 0 
P 4.645 2.985 12 P 0 8 0;3=3,5=1
L 5.452 2.813 5.412 2.813 10 P 0 
L 5.412 2.813 5.41 2.815 10 P 0 
P 4.61 3.025 12 P 0 8 0;3=3,5=1
P 4.43 3.865 11 P 0 8 0;3=11,5=1
P 5.273 4.20101004 32 P 0 8 0;0,3=0,5=0
L 5.273 4.20101004 5.23601004 4.20101004 10 P 0 
L 5.23601004 4.20101004 5.221 4.186 10 P 0 
L 5.221 4.186 5.221 4.165 10 P 0 
P 5.221 4.165 12 P 0 8 0;3=3,5=1
P 4.354 3.965 36 P 0 8 0;0,3=0,5=0
L 4.354 3.965 4.32 3.965 10 P 0 
P 4.32 3.965 11 P 0 8 0;3=11,5=1
P 4.535 3.815 12 P 0 8 0;3=3,5=1
P 4.509 3.309 12 P 0 8 0;3=3,5=1
P 4.235 4.155 12 P 0 8 0;3=3,5=1
L 4.224 4.115 4.224 4.144 10 P 0 
L 4.224 4.144 4.235 4.155 10 P 0 
P 4.224 4.065 36 P 0 8 0;0,3=0,5=0
L 4.224 4.065 4.224 4.115 10 P 0 
P 4.224 4.115 36 P 0 8 0;0,3=0,5=0
P 4.505 3.685 12 P 0 8 0;3=3,5=1
L 6.027 4.219 5.975 4.219 10 P 0 
L 6.14 4.219 6.027 4.219 10 P 0 
P 5.975 4.219 12 P 0 8 0;3=3,5=1
P 6.14 4.219 32 P 0 8 0;0,3=0,5=0
P 6.027 4.219 32 P 0 8 0;0,3=0,5=0
L 5.79 4.219 5.84 4.219 10 P 0 
P 5.84 4.219 12 P 0 8 0;3=3,5=1
L 5.67 4.219 5.79 4.219 10 P 0 
P 5.79 4.219 32 P 0 8 0;0,3=0,5=0
L 5.555 4.219 5.67 4.219 10 P 0 
P 5.67 4.219 32 P 0 8 0;0,3=0,5=0
L 5.435 4.219 5.555 4.219 10 P 0 
P 5.555 4.219 32 P 0 8 0;0,3=0,5=0
P 5.435 4.219 32 P 0 8 0;0,3=0,5=0
L 5.435 4.219 5.435 4.166 10 P 0 
P 5.435 4.166 32 P 0 8 0;0,3=0,5=0
P 6.145 3.98 12 P 0 8 0;3=3,5=1
P 4.655 0.785 12 P 0 8 0;3=3,5=1
P 4.694 0.965 36 P 0 8 0;0,3=0,5=0
P 4.635 0.92 12 P 0 8 0;3=3,5=1
P 5.249 0.99 12 P 0 8 0;3=3,5=1
P 5.53 1.085 12 P 0 8 0;3=3,5=1
L 5.249 0.99 5.249 1.009 10 P 0 
L 5.249 1.009 5.325 1.085 10 P 0 
L 5.325 1.085 5.53 1.085 10 P 0 
L 4.694 0.965 4.68 0.965 10 P 0 
L 4.68 0.965 4.635 0.92 10 P 0 
P 5.33 0.82 12 P 0 8 0;3=3,5=1
P 5.265 0.675 12 P 0 8 0;3=3,5=1
L 5.265 0.675 5.265 0.755 10 P 0 
L 5.265 0.755 5.33 0.82 10 P 0 
P 2.964 0.702 12 P 0 8 0;3=3,5=1
L 5.555 0.608 5.528 0.608 10 P 0 
L 5.528 0.608 5.51596998 0.59596998 10 P 0 
L 5.51596998 0.59596998 5.515 0.59596998 10 P 0 
P 5.555 0.608 32 P 0 8 0;0,3=0,5=0
P 5.515 0.59596998 12 P 0 8 0;3=3,5=1
P 2.0477 0.6778 12 P 0 8 0;3=3,5=1
P 2.285 0.79 12 P 0 8 0;3=3,5=1
P 2.285 0.755 12 P 0 8 0;3=3,5=1
P 3.09 1.645 12 P 0 8 0;3=3,5=1
L 1.25 0.765 1.2682 0.765 10 P 0 
L 1.2682 0.765 1.2802 0.753 10 P 0 
L 1.2802 0.753 1.309 0.753 10 P 0 
P 1.605 0.715 12 P 0 8 0;3=3,5=1
P 1.605 0.755 12 P 0 8 0;3=3,5=1
P 1.826 2.895 12 P 0 8 0;3=3,5=1
P 1.401 3.069 12 P 0 8 0;3=3,5=1
P 3.119 2.434 12 P 0 8 0;3=3,5=1
P 2.245 3.02 11 P 0 8 0;3=11,5=1
P 2.49 2.903 12 P 0 8 0;3=3,5=1
P 2.509 2.375 36 P 0 8 0;0,3=0,5=0
L 2.509 2.375 2.481 2.375 10 P 0 
L 2.481 2.375 2.461 2.355 10 P 0 
P 2.46558996 2.287 29 P 0 8 0;0,3=22,5=0
L 2.46558996 2.287 2.46558996 2.35041004 8 P 0 
L 2.46558996 2.35041004 2.461 2.355 8 P 0 
P 2.461 2.355 36 P 0 8 0;0,3=0,5=0
L 2.49 2.903 2.49 2.46 10 P 0 
L 2.49 2.46 2.509 2.441 10 P 0 
L 2.509 2.441 2.509 2.375 10 P 0 
P 2.128 2.895 11 P 0 8 0;3=11,5=1
P 0.11976004 3.23523996 12 P 0 8 0;3=3,5=1
P 0.78 2.915 12 P 0 8 0;3=3,5=1
P 0.741 2.915 36 P 0 8 0;0,3=0,5=0
L 0.741 2.915 0.78 2.915 10 P 0 
P 0.241 3.075 36 P 0 8 0;0,3=0,5=0
P 0.3695 3.0284 46 P 0 8 0;0,3=18,5=0
L 0.241 3.075 0.241 3.109 10 P 0 
P 0.241 3.109 12 P 0 8 0;3=3,5=1
L 0.3695 3.0284 0.3416 3.0284 10 P 0 
L 0.3416 3.0284 0.295 3.075 10 P 0 
L 0.295 3.075 0.241 3.075 10 P 0 
P 0.199 2.975 36 P 0 8 0;0,3=0,5=0
P 0.16 2.975 12 P 0 8 0;3=3,5=1
L 0.199 2.925 0.199 2.975 10 P 0 
P 0.199 2.925 36 P 0 8 0;0,3=0,5=0
L 0.199 2.975 0.16 2.975 10 P 0 
P 0.335 2.829 32 P 0 8 0;0,3=0,5=0
L 0.335 2.829 0.374 2.829 10 P 0 
P 0.374 2.829 12 P 0 8 0;3=3,5=1
L 0.5459 2.6687 0.6067 2.6079 10 P 0 
L 0.6067 2.6079 0.6067 2.4732 10 P 0 
L 0.6067 2.4732 0.677 2.4029 10 P 0 
L 0.677 2.4029 0.677 2.402 10 P 0 
P 0.5459 2.6687 12 P 0 8 0;3=3,5=1
L 0.674 2.271 0.6484 2.2966 10 P 0 
L 0.6484 2.2966 0.6484 2.3769 10 P 0 
L 0.6484 2.3769 0.6735 2.402 10 P 0 
L 0.6735 2.402 0.677 2.402 10 P 0 
P 0.674 2.271 12 P 0 8 0;3=3,5=1
P 0.85 2.402 32 P 0 8 0;0,3=0,5=0
L 0.896 2.402 0.85 2.402 10 P 0 
P 0.896 2.402 32 P 0 8 0;0,3=0,5=0
L 0.85 2.402 0.85 2.372 10 P 0 
L 0.85 2.372 0.857 2.365 10 P 0 
P 0.857 2.365 12 P 0 8 0;3=3,5=1
P 0.677 2.402 12 P 0 8 0;3=3,5=1
L 0.715 2.402 0.677 2.402 10 P 0 
P 0.715 2.402 32 P 0 8 0;0,3=0,5=0
P 0.11963002 2.66436998 12 P 0 8 0;3=3,5=1
P 0.51451998 2.199 12 P 0 8 0;3=3,5=1
P 0.58 2.135 12 P 0 8 0;3=3,5=1
P 0.125 2.095 12 P 0 8 0;3=3,5=1
P 0.64445 1.68945 12 P 0 8 0;3=3,5=1
P 0.884 1.549 12 P 0 8 0;3=3,5=1
L 0.85 1.549 0.884 1.549 10 P 0 
P 0.85 1.549 36 P 0 8 0;0,3=0,5=0
P 0.883 1.639 11 P 0 8 0;3=11,5=1
L 0.883 1.639 0.85 1.639 10 P 0 
P 0.85 1.639 36 P 0 8 0;0,3=0,5=0
P 0.514 1.616 12 P 0 8 0;3=3,5=1
P 0.605 1.52 12 P 0 8 0;3=3,5=1
P 0.11263996 1.52263996 12 P 0 8 0;3=3,5=1
P 0.625 1.17 12 P 0 8 0;3=3,5=1
P 0.59 0.965 15 P 0 8 0;1,3=1,5=1
P 0.505 1.048 12 P 0 8 0;3=3,5=1
P 0.125 0.96 12 P 0 8 0;3=3,5=1
P 0.821 0.793 12 P 0 8 0;3=3,5=1
L 0.86 0.791 0.823 0.791 10 P 0 
L 0.823 0.791 0.821 0.793 10 P 0 
P 0.86 0.791 32 P 0 8 0;0,3=0,5=0
P 0.743 0.911 32 P 0 8 0;0,3=0,5=0
L 0.743 0.911 0.788 0.911 10 P 0 
P 0.788 0.911 32 P 0 8 0;0,3=0,5=0
P 0.764 0.872 12 P 0 8 0;3=3,5=1
L 0.788 0.911 0.788 0.896 10 P 0 
L 0.788 0.896 0.764 0.872 10 P 0 
P 1.25 0.765 12 P 0 8 0;3=3,5=1
P 1.309 0.753 36 P 0 8 0;0,3=0,5=0
P 1.1133 0.5981 12 P 0 8 0;3=3,5=1
L 1.1738 0.6587 1.1738 0.6586 10 P 0 
L 1.1738 0.6586 1.1133 0.5981 10 P 0 
P 1.1738 0.6587 36 P 0 8 0;0,3=0,5=0
P 0.851 0.665 36 P 0 8 0;0,3=0,5=0
P 0.86 0.631 12 P 0 8 0;3=3,5=1
L 0.851 0.665 0.851 0.655 10 P 0 
L 0.851 0.655 0.86 0.646 10 P 0 
L 0.86 0.646 0.86 0.631 10 P 0 
P 0.577 0.697 32 P 0 8 0;0,3=0,5=0
P 0.601 0.73 12 P 0 8 0;3=3,5=1
L 0.601 0.73 0.577 0.706 10 P 0 
L 0.577 0.706 0.577 0.697 10 P 0 
P 0.596 0.602 12 P 0 8 0;3=3,5=1
P 0.635 0.615 36 P 0 8 0;0,3=0,5=0
L 0.596 0.602 0.609 0.615 11 P 0 
L 0.609 0.615 0.635 0.615 11 P 0 
P 1.5327 0.584 12 P 0 8 0;3=3,5=1
P 4.6987 1.54816004 11 P 0 8 0;3=2,5=1
P 4.67901998 1.56783996 14 P 0 8 0;0,3=19,5=0
L 4.67901998 1.56783996 4.6987 1.54816004 10 P 0 
P 4.58058996 1.50878996 11 P 0 8 0;3=2,5=1
L 4.58058996 1.50878996 4.60026998 1.52846998 10 P 0 
L 4.60026998 1.52846998 4.60028002 1.52846998 10 P 0 
P 4.60028002 1.52846998 14 P 0 8 0;0,3=19,5=0
L 4.16721004 1.4891 4.16721004 1.48911004 10 P 0 
L 4.16721004 1.48911004 4.14753002 1.50878996 10 P 0 
P 4.14753002 1.50878996 11 P 0 8 0;3=2,5=1
L 4.16721004 1.52846998 4.14753002 1.50878996 10 P 0 
P 4.16721004 1.52846998 14 P 0 8 0;0,3=19,5=0
P 4.16721004 1.4891 14 P 0 8 0;0,3=19,5=0
P 4.73806998 1.43005 11 P 0 8 0;3=2,5=1
L 4.73806998 1.43005 4.74006998 1.42805 10 P 0 
L 4.74006998 1.42805 4.76666004 1.42805 10 P 0 
P 4.76666004 1.42805 14 P 0 8 0;0,3=19,5=0
P 4.61996004 1.39066998 11 P 0 8 0;3=2,5=1
P 4.60028002 1.41035 14 P 0 8 0;0,3=19,5=0
L 4.60028002 1.41035 4.61996004 1.39066998 10 P 0 
P 4.50185 1.3513 11 P 0 8 0;3=2,5=1
L 4.50185 1.3513 4.52151998 1.37096998 10 P 0 
L 4.52151998 1.37096998 4.52153996 1.37096998 10 P 0 
P 4.52153996 1.37096998 14 P 0 8 0;0,3=19,5=0
P 4.46248002 1.46941998 11 P 0 8 0;3=2,5=1
L 4.46248002 1.46941998 4.4428 1.44973996 10 P 0 
L 4.4428 1.44973996 4.4428 1.44973002 10 P 0 
P 4.4428 1.44973002 14 P 0 8 0;0,3=19,5=0
P 4.38373996 1.31193002 11 P 0 8 0;3=2,5=1
L 4.38373996 1.31193002 4.40341998 1.33161004 10 P 0 
L 4.40341998 1.33161004 4.40343002 1.33161004 10 P 0 
P 4.40343002 1.33161004 14 P 0 8 0;0,3=19,5=0
P 4.34436998 1.43005 11 P 0 8 0;3=2,5=1
L 4.34436998 1.43005 4.36405 1.44973002 10 P 0 
L 4.36405 1.44973002 4.36406004 1.44973002 10 P 0 
P 4.36406004 1.44973002 14 P 0 8 0;0,3=19,5=0
L 4.309 1.44531004 4.32426004 1.43005 10 P 0 
L 4.32426004 1.43005 4.34436998 1.43005 10 P 0 
P 4.309 1.44531004 14 P 0 8 0;0,3=19,5=0
P 4.1869 1.39066998 11 P 0 8 0;3=2,5=1
P 4.20658002 1.41035 14 P 0 8 0;0,3=19,5=0
L 4.20658002 1.41035 4.1869 1.39066998 10 P 0 
L 4.06878996 1.3513 4.04911004 1.37098002 10 P 0 
L 4.04911004 1.37098002 4.0491 1.37098002 10 P 0 
P 4.0491 1.37098002 14 P 0 8 0;0,3=19,5=0
P 4.06878996 1.3513 11 P 0 8 0;3=2,5=1
P 3.91828996 1.29361004 36 P 0 8 0;0,3=0,5=0
L 3.91828996 1.29361004 3.93235 1.29361004 10 P 0 
L 3.93235 1.29361004 3.95066998 1.31193002 10 P 0 
P 3.95066998 1.31193002 11 P 0 8 0;3=2,5=1
L 5.0386 1.2415 5.0205 1.2415 10 P 0 
L 5.0205 1.2415 4.999 1.263 10 P 0 
L 5.039 1.2869 5.0229 1.2869 10 P 0 
L 5.0229 1.2869 4.999 1.263 10 P 0 
P 4.999 1.263 39 P 0 8 0;0,3=12,5=0
P 5.039 1.2869 12 P 0 8 0;3=3,5=1
P 5.0386 1.2415 12 P 0 8 0;3=3,5=1
P 4.625 1.17 12 P 0 8 0;3=3,5=1
P 4.37 1.079 32 P 0 8 0;0,3=0,5=0
L 4.37 1.079 4.415 1.079 10 P 0 
P 4.415 1.079 32 P 0 8 0;0,3=0,5=0
L 4.415 1.079 4.451 1.079 10 P 0 
L 4.451 1.079 4.485 1.045 10 P 0 
L 4.485 1.045 4.485 1.005 10 P 0 
P 4.485 1.005 12 P 0 8 0;3=3,5=1
P 3.69171998 1.02828002 12 P 0 8 0;3=3,5=1
L 3.69171998 1.02828002 3.70028002 1.02828002 10 P 0 
L 3.70028002 1.02828002 3.732 1.06 10 P 0 
L 3.6931 1.095 3.6981 1.09 10 P 0 
L 3.6981 1.09 3.702 1.09 10 P 0 
L 3.702 1.09 3.732 1.06 10 P 0 
P 3.732 1.06 39 P 0 8 0;0,3=12,5=0
P 3.6931 1.095 12 P 0 8 0;3=3,5=1
P 6.04 3.98 12 P 0 8 0;3=3,5=1
P 5.445 0.795 15 P 0 8 0;1,3=4,5=0
P 5.494 0.816 12 P 0 8 0;3=3,5=1
P 5.443 0.871 12 P 0 8 0;3=3,5=1
P 5.49 0.78223002 12 P 0 8 0;3=3,5=1
P 3.795 4.175 12 P 0 8 0;3=3,5=1
P 3.66 3.5085 12 P 0 8 0;3=3,5=1
P 3.105 3.21 12 P 0 8 0;3=3,5=1
L 3.068 3.21 3.105 3.21 10 P 0 
P 3.068 3.21 36 P 0 8 0;0,3=0,5=0
L 5.529 4.07 5.529 4.041 10 P 0 
L 5.529 4.041 5.55 4.02 10 P 0 
P 5.55 4.02 12 P 0 8 0;3=3,5=1
P 5.529 4.07 36 P 0 8 0;0,3=0,5=0
P 5.01 2.635 15 P 0 8 0;1,3=1,5=1
P 5 2.78798996 15 P 0 8 0;1,3=10,5=1
P 5.226 2.762 15 P 0 8 0;1,3=10,5=1
P 3.775 2.235 12 P 0 8 0;3=3,5=1
P 3.775 2.265 15 P 0 8 0;1,3=1,5=1
P 3.775 2.21 12 P 0 8 0;3=3,5=1
P 3.775 2.185 12 P 0 8 0;3=3,5=1
P 4.42311004 1.755 36 P 0 8 0;0,3=0,5=0
L 4.42311004 1.78436998 4.42311004 1.755 10 P 0 
P 4.42311004 1.78436998 11 P 0 8 0;3=2,5=1
P 4.46248002 1.70563996 11 P 0 8 0;3=2,5=1
L 4.46248002 1.70563996 4.4428 1.68596004 10 P 0 
L 4.4428 1.68596004 4.4428 1.68595 10 P 0 
P 4.4428 1.68595 14 P 0 8 0;0,3=19,5=0
P 4.36406004 1.80406004 14 P 0 8 0;0,3=19,5=0
L 4.36406004 1.80406004 4.34436998 1.78436998 10 P 0 
P 4.34436998 1.78436998 11 P 0 8 0;3=2,5=1
L 4.34436998 1.78436998 4.365 1.76373996 10 P 0 
L 4.365 1.76373996 4.365 1.741 10 P 0 
P 4.365 1.741 36 P 0 8 0;0,3=0,5=0
P 4.24595 1.80406004 14 P 0 8 0;0,3=19,5=0
P 4.241 1.75 36 P 0 8 0;0,3=0,5=0
L 4.241 1.75 4.241 1.76963996 10 P 0 
L 4.241 1.76963996 4.22626998 1.78436998 10 P 0 
L 4.22626998 1.78436998 4.24595 1.80405 10 P 0 
L 4.24595 1.80405 4.24595 1.80406004 10 P 0 
P 4.22626998 1.78436998 11 P 0 8 0;3=2,5=1
P 4.22626998 1.66626998 11 P 0 8 0;3=2,5=1
P 4.20658002 1.64658002 14 P 0 8 0;0,3=19,5=0
L 4.20658002 1.64658002 4.22626998 1.66626998 10 P 0 
L 4.14753002 1.78436998 4.14 1.77683996 10 P 0 
L 4.14 1.77683996 4.14 1.75 10 P 0 
P 4.14753002 1.78436998 11 P 0 8 0;3=2,5=1
P 4.14 1.75 36 P 0 8 0;0,3=0,5=0
L 4.02941998 1.78436998 4.0491 1.80405 10 P 0 
L 4.0491 1.80405 4.0491 1.80406004 10 P 0 
P 4.0491 1.80406004 14 P 0 8 0;0,3=19,5=0
P 4.02941998 1.78436998 11 P 0 8 0;3=2,5=1
L 4.25 3.81 4.26 3.8 3 P 0 
L 4.26 3.8 4.26 3.42501004 3 P 0 
L 4.26 3.42501004 4.275 3.41001004 3 P 0 
L 4.275 3.41001004 4.275 3.245 3 P 0 
L 4.275 3.245 4.385 3.135 3 P 0 
L 4.385 3.135 4.385 3.095 3 P 0 
L 4.385 3.095 4.49 2.99 3 P 0 
L 4.49 2.99 4.54565 2.99 3 P 0 
L 4.54565 2.99 4.566 2.96965 3 P 0 
L 4.566 2.96965 4.566 2.945 3 P 0 
P 5.775 0.796 32 P 0 8 0;0,3=0,5=0
P 5.765 0.98 15 P 0 8 0;1,3=4,5=0
L 5.765 0.98 5.775 0.97 3 P 0 
L 5.775 0.97 5.775 0.796 3 P 0 
L 1.385 3.875 1.395 3.885 3 P 0 
L 1.395 3.885 1.419 3.885 3 P 0 
L 1.419 3.885 1.435 3.901 3 P 0 
P 1.385 3.875 15 P 0 8 0;1,3=10,5=1
L 4.608 2.942 4.569 2.942 3 P 0 
L 4.569 2.942 4.566 2.945 3 P 0 
P 4.566 2.945 36 P 0 8 0;0,3=0,5=0
P 5.31 2.855 12 P 0 8 0;3=3,5=1
P 4.608 2.942 12 P 0 8 0;3=3,5=1
P 4.25 3.81 12 P 0 8 0;3=3,5=1
P 1.435 3.901 36 P 0 8 0;0,3=0,5=0
P 0.99 2.60025 12 P 0 8 0;3=3,5=1
P 0.985 2.56661004 12 P 0 8 0;3=3,5=1
S P 0
OB 3.62 2.27 I
OS 3.63 2.26
OS 3.63 2.21
OS 3.615 2.195
OS 3.615 2.16
OS 3.55 2.16
OS 3.54 2.17
OS 3.54 2.265
OS 3.545 2.27
OS 3.62 2.27
OE
SE
P 3.555 2.23 12 P 0 8 0;3=3,5=1
P 3.555 2.255 12 P 0 8 0;3=3,5=1
P 3.612 2.23 39 P 0 8 0;0,3=12,5=0
P 3.609 2.17 36 P 0 8 0;0,3=0,5=0
P 3.555 2.205 12 P 0 8 0;3=3,5=1
P 3.555 2.18 12 P 0 8 0;3=3,5=1
P 5.345 2.536 15 P 0 8 0;1,3=4,5=0
P 5.22 2.47 12 P 0 8 0;3=3,5=1
P 5.254 2.47 12 P 0 8 0;3=3,5=1
P 5.239 2.571 12 P 0 8 0;3=3,5=1
P 5.243 2.617 12 P 0 8 0;3=3,5=1
P 5.224 2.707 15 P 0 8 0;1,3=10,5=1
P 5.278 2.653 32 P 0 8 0;0,3=0,5=0
L 5.278 2.653 5.224 2.707 9 P 0 
P 5.005 2.711 15 P 0 8 0;1,3=10,5=1
L 4.961 2.686 4.98 2.686 3 P 0 
L 4.98 2.686 5.005 2.711 3 P 0 
P 4.961 2.686 32 P 0 8 0;0,3=0,5=0
P 3.793 3.05 15 P 0 8 0;1,3=5,5=1
L 3.793 3.092 3.793 3.05 9 P 0 
P 3.793 3.092 36 P 0 8 0;0,3=0,5=0
P 3.96981004 3.04481998 15 P 0 8 0;1,3=1,5=1
P 3.948 2.813 15 P 0 8 0;1,3=1,5=1
P 4.831 2.728 15 P 0 8 0;1,3=4,5=0
S P 0
OB 3.6 1.45 I
OS 3.62 1.43
OS 3.62 1.355
OS 3.56 1.355
OS 3.545 1.37
OS 3.438 1.37
OS 3.43 1.378
OS 3.43 1.445
OS 3.435 1.45
OS 3.6 1.45
OE
SE
P 3.52 1.376 32 P 0 8 0;0,3=0,5=0
P 3.618 1.395 37 P 0 8 0;0,3=8,5=0
P 3.46 1.378 43 P 0 8 0;0,3=12,5=0
P 3.55 1.415 12 P 0 8 0;3=3,5=1
P 3.525 1.415 12 P 0 8 0;3=3,5=1
P 3.5 1.415 12 P 0 8 0;3=3,5=1
P 3.475 1.415 12 P 0 8 0;3=3,5=1
P 3.655 2.795 15 P 0 8 0;1,3=4,5=0
P 3.745 2.76 12 P 0 8 0;3=3,5=1
P 3.7 2.76 12 P 0 8 0;3=3,5=1
P 3.822 2.81 12 P 0 8 0;3=3,5=1
P 3.78 2.81 12 P 0 8 0;3=3,5=1
P 3.894 2.811 15 P 0 8 0;1,3=1,5=1
L 3.891 3.092 3.835 3.092 3 P 0 
P 3.835 3.092 36 P 0 8 0;0,3=0,5=0
P 3.891 3.092 36 P 0 8 0;0,3=0,5=0
L 3.891 3.092 3.891 3.073 3 P 0 
L 3.891 3.073 3.916 3.048 3 P 0 
P 3.916 3.048 15 P 0 8 0;1,3=5,5=1
L 5.589 1.98 5.589 2.025 10 P 0 
P 5.589 2.025 15 P 0 8 0;1,3=1,5=1
P 5.546 2.024 12 P 0 8 0;3=3,5=1
L 5.51 2.024 5.546 2.024 10 P 0 
P 5.51 2.024 32 P 0 8 0;0,3=0,5=0
P 5.589 1.98 36 P 0 8 0;0,3=0,5=0
P 5.69943002 2.233 15 P 0 8 0;1,3=1,5=1
L 5.431 2.275 5.436 2.28 3 P 0 
L 5.436 2.28 5.48125 2.28 3 P 0 
L 5.48125 2.28 5.48158002 2.28033002 3 P 0 
P 5.431 2.275 36 P 0 8 0;0,3=0,5=0
P 5.48158002 2.28033002 15 P 0 8 0;1,3=10,5=1
P 4.50185 1.66626998 11 P 0 8 0;3=2,5=1
P 4.52153996 1.68595 14 P 0 8 0;0,3=19,5=0
L 4.50185 1.66626998 4.52153002 1.68595 10 P 0 
L 4.52153002 1.68595 4.52153996 1.68595 10 P 0 
P 4.42311004 1.66626998 11 P 0 8 0;3=2,5=1
L 4.40343002 1.68595 4.42311004 1.66626998 10 P 0 
P 4.40343002 1.68595 14 P 0 8 0;0,3=19,5=0
P 4.38373996 1.70563996 11 P 0 8 0;3=2,5=1
P 4.26563996 1.70563996 11 P 0 8 0;3=2,5=1
L 4.26563996 1.70563996 4.28028002 1.691 10 P 0 
L 4.28028002 1.691 4.305 1.691 10 P 0 
L 4.24595 1.68595 4.26563996 1.70563996 10 P 0 
P 4.305 1.691 32 P 0 8 0;0,3=0,5=0
P 4.24595 1.68595 14 P 0 8 0;0,3=19,5=0
L 4.14753002 1.66626998 4.12785 1.68595 10 P 0 
L 4.12785 1.68595 4.12783996 1.68595 10 P 0 
P 4.12783996 1.68595 14 P 0 8 0;0,3=19,5=0
P 4.14753002 1.66626998 11 P 0 8 0;3=2,5=1
P 4.1869 1.70563996 11 P 0 8 0;3=2,5=1
P 4.50185 1.58753002 11 P 0 8 0;3=2,5=1
P 4.46248002 1.6269 11 P 0 8 0;3=2,5=1
L 4.46248002 1.6269 4.4428 1.64658002 10 P 0 
P 4.48216998 1.60721004 14 P 0 8 0;0,3=19,5=0
L 4.48216998 1.60721004 4.46248002 1.6269 10 P 0 
P 4.4428 1.64658002 14 P 0 8 0;0,3=19,5=0
P 4.46248002 1.54816004 11 P 0 8 0;3=2,5=1
L 4.4428 1.56783996 4.46248002 1.54816004 10 P 0 
P 4.4428 1.56783996 14 P 0 8 0;0,3=19,5=0
P 4.38373996 1.54816004 11 P 0 8 0;3=2,5=1
L 4.36406004 1.56783996 4.38373996 1.54816004 10 P 0 
P 4.36406004 1.56783996 14 P 0 8 0;0,3=19,5=0
P 4.42311004 1.58753002 11 P 0 8 0;3=2,5=1
L 4.40343002 1.60721004 4.42311004 1.58753002 10 P 0 
P 4.40343002 1.60721004 14 P 0 8 0;0,3=19,5=0
P 4.34436998 1.58753002 11 P 0 8 0;3=2,5=1
L 4.34436998 1.58753002 4.36405 1.60721004 10 P 0 
L 4.36405 1.60721004 4.36406004 1.60721004 10 P 0 
P 4.36406004 1.60721004 14 P 0 8 0;0,3=19,5=0
P 4.26563996 1.54816004 11 P 0 8 0;3=2,5=1
L 4.26563996 1.54816004 4.26648002 1.549 10 P 0 
L 4.26648002 1.549 4.305 1.549 10 P 0 
P 4.305 1.549 32 P 0 8 0;0,3=0,5=0
P 4.22626998 1.58753002 11 P 0 8 0;3=2,5=1
L 4.24595 1.60721004 4.22626998 1.58753002 10 P 0 
P 4.24595 1.60721004 14 P 0 8 0;0,3=19,5=0
P 4.14753002 1.58753002 11 P 0 8 0;3=2,5=1
L 4.16721004 1.60721004 4.14753002 1.58753002 10 P 0 
P 4.16721004 1.60721004 14 P 0 8 0;0,3=19,5=0
P 4.1869 1.6269 11 P 0 8 0;3=2,5=1
L 4.1869 1.6269 4.16721998 1.64658002 10 P 0 
L 4.16721998 1.64658002 4.16721004 1.64658002 10 P 0 
P 4.16721004 1.64658002 14 P 0 8 0;0,3=19,5=0
P 4.1869 1.54816004 11 P 0 8 0;3=2,5=1
L 4.1869 1.54816004 4.20658002 1.52848002 10 P 0 
L 4.20658002 1.52848002 4.20658002 1.52846998 10 P 0 
L 4.20658002 1.56783996 4.1869 1.54816004 10 P 0 
P 4.20658002 1.52846998 14 P 0 8 0;0,3=19,5=0
P 4.20658002 1.56783996 14 P 0 8 0;0,3=19,5=0
P 5.145 1.57 12 P 0 8 0;3=3,5=1
P 5.145 1.54 12 P 0 8 0;3=3,5=1
P 5.145 1.44 15 P 0 8 0;1,3=1,5=1
P 5.145 1.48 12 P 0 8 0;3=3,5=1
P 5.145 1.51 12 P 0 8 0;3=3,5=1
L 4.2136 3.5997 4.1149 3.501 3 P 0 
L 4.1149 3.501 4.041 3.501 3 P 0 
L 4.041 3.501 3.997 3.545 3 P 0 
L 3.997 3.545 3.9594 3.545 3 P 0 
L 3.9594 3.545 3.92273002 3.50833002 3 P 0 
L 3.92273002 3.50833002 3.82656998 3.50833002 3 P 0 
L 3.82656998 3.50833002 3.79323996 3.475 3 P 0 
L 3.79323996 3.475 3.76 3.475 3 P 0 
L 3.76 3.475 3.66765 3.38265 3 P 0 
L 3.66765 3.38265 3.66765 3.17735 3 P 0 
L 3.66765 3.17735 3.753 3.092 3 P 0 
L 3.753 3.092 3.755 3.092 3 P 0 
P 5.76 2.465 15 P 0 8 0;3=4,5=0
P 4.2136 3.5997 15 P 0 8 0;1,3=5,5=1
P 3.755 3.092 12 P 0 8 0;3=3,5=1
L 3.99005 1.66626998 4.00973002 1.64658996 10 P 0 
L 4.00973002 1.64658996 4.00973002 1.64658002 10 P 0 
P 4.00973002 1.64658002 14 P 0 8 0;0,3=19,5=0
P 3.99005 1.66626998 11 P 0 8 0;3=2,5=1
P 4.08846998 1.56783996 14 P 0 8 0;0,3=19,5=0
L 4.08846998 1.56783996 4.06878996 1.54816004 10 P 0 
P 4.06878996 1.54816004 11 P 0 8 0;3=2,5=1
L 4.06878996 1.6269 4.08846998 1.60721998 10 P 0 
L 4.08846998 1.60721998 4.08846998 1.60721004 10 P 0 
P 4.08846998 1.60721004 14 P 0 8 0;0,3=19,5=0
P 4.06878996 1.6269 11 P 0 8 0;3=2,5=1
P 4.0491 1.60721004 14 P 0 8 0;0,3=19,5=0
L 4.0491 1.60721004 4.02941998 1.58753002 10 P 0 
P 4.02941998 1.58753002 11 P 0 8 0;3=2,5=1
P 3.99005 1.50878996 11 P 0 8 0;3=2,5=1
P 4.00973002 1.4891 14 P 0 8 0;0,3=19,5=0
L 3.99005 1.50878996 4.00973002 1.48911004 10 P 0 
L 4.00973002 1.48911004 4.00973002 1.4891 10 P 0 
L 4.00973002 1.52846998 3.99005 1.50878996 10 P 0 
P 4.00973002 1.52846998 14 P 0 8 0;0,3=19,5=0
P 3.679 1.54228002 12 P 0 8 0;3=3,5=1
P 3.714 1.543 12 P 0 8 0;3=3,5=1
P 3.784 1.543 12 P 0 8 0;3=3,5=1
P 3.749 1.54228002 12 P 0 8 0;3=3,5=1
P 3.605 1.545 12 P 0 8 0;3=3,5=1
P 3.50085 1.543 12 P 0 8 0;3=3,5=1
P 3.53481998 1.54156998 12 P 0 8 0;3=3,5=1
P 3.57 1.542 12 P 0 8 0;3=3,5=1
S P 0
OB 5.445 1.645 I
OS 5.44 1.64
OS 5.37 1.64
OS 5.365 1.645
OS 5.365 1.8
OS 5.37 1.805
OS 5.44 1.805
OS 5.445 1.8
OS 5.445 1.645
OE
SE
P 5.4227 1.724 12 P 0 8 0;3=3,5=1
P 5.3977 1.724 12 P 0 8 0;3=3,5=1
P 5.58 1.615 15 P 0 8 0;1,3=4,5=0
P 5.3977 1.699 12 P 0 8 0;3=3,5=1
P 5.3977 1.749 12 P 0 8 0;3=3,5=1
P 5.4227 1.699 12 P 0 8 0;3=3,5=1
P 5.39 1.646 32 P 0 8 0;0,3=0,5=0
P 5.4 1.787 43 P 0 8 0;0,3=12,5=0
P 5.4352 1.7497 12 P 0 8 0;3=3,5=1
P 5.654 2.447 12 P 0 8 0;3=3,5=1
L 5.667 2.275 5.667 2.287 8 P 0 
L 5.667 2.287 5.698 2.318 8 P 0 
L 5.698 2.318 5.7 2.318 8 P 0 
P 5.754 2.324 32 P 0 8 0;0,3=0,5=0
L 5.754 2.324 5.748 2.318 8 P 0 
L 5.748 2.318 5.7 2.318 8 P 0 
P 5.7 2.318 38 P 0 8 0;0,3=8,5=0
P 5.667 2.275 15 P 0 8 0;1,3=10,5=1
L 5.595 2.28 5.6 2.285 8 P 0 
L 5.6 2.285 5.6 2.324 8 P 0 
P 5.6 2.324 32 P 0 8 0;0,3=0,5=0
P 5.595 2.28 15 P 0 8 0;1,3=10,5=1
P 5.51 2.171 32 P 0 8 0;0,3=0,5=0
L 5.51 2.171 5.51 2.199 10 P 0 
L 5.51 2.199 5.483 2.226 10 P 0 
P 5.483 2.226 15 P 0 8 0;1,3=1,5=1
L 5.6695 2.2 5.6314 2.2381 8 P 0 
L 5.6314 2.2381 5.6314 2.2914 8 P 0 
L 5.6314 2.2914 5.645 2.305 8 P 0 
L 5.645 2.305 5.645 2.33456998 8 P 0 
S P 0
OB 5.679 2.203 I
OS 5.679 2.178
OS 5.673 2.172
OS 5.624 2.172
OS 5.622 2.174
OS 5.622 2.212
OS 5.626 2.216
OS 5.666 2.216
OS 5.679 2.203
OE
SE
P 5.64 2.1745 33 P 0 8 0;0,3=23,5=0
P 5.754 2.366 32 P 0 8 0;0,3=0,5=0
L 5.754 2.366 5.748 2.372 10 P 0 
L 5.748 2.372 5.7 2.372 10 P 0 
P 5.6695 2.2 12 P 0 8 0;3=3,5=1
P 5.771 2.279 15 P 0 8 0;1,3=10,5=1
P 5.789 2.366 12 P 0 8 0;3=3,5=1
L 5.789 2.366 5.754 2.366 10 P 0 
P 5.7 2.372 38 P 0 8 0;0,3=8,5=0
P 5.6 2.4 12 P 0 8 0;3=3,5=1
P 5.645 2.33456998 30 P 0 8 0;0,3=24,5=0
P 5.6 4.01 15 P 0 8 0;3=4,5=0
P 5.55568996 3.88051004 15 P 0 8 0;1,3=5,5=1
S P 0
OB 5.730580019685 2.217 I
OS 5.762 2.217
OS 5.769 2.21
OS 5.769 2.145
OS 5.755 2.131
OS 5.699019980315 2.131
OS 5.699019980315 2.19451003937
OS 5.69905 2.19468996063
OC 5.69945 2.197980019685 5.669494389764 2.19995265748 N
OC 5.730580019685 2.217 5.699429035433 2.232999606299 N
OE
SE
L 5.465 2.366 5.465 2.405 10 P 0 
P 5.465 2.366 32 P 0 8 0;0,3=0,5=0
P 5.765 2.197 15 P 0 8 0;1,3=1,5=1
P 5.71 2.179 12 P 0 8 0;3=3,5=1
P 5.41 2.164 15 P 0 8 0;1,3=1,5=1
P 5.458 2.165 12 P 0 8 0;3=3,5=1
P 5.465 2.405 12 P 0 8 0;3=3,5=1
L 5.6435 2.38443002 5.62043002 2.38443002 8 P 0 
L 5.62043002 2.38443002 5.602 2.366 8 P 0 
L 5.602 2.366 5.6 2.366 8 P 0 
L 5.645 2.35543002 5.645 2.38293002 8 P 0 
L 5.645 2.38293002 5.6435 2.38443002 8 P 0 
P 5.6435 2.38443002 15 P 0 8 0;1,3=14,5=1
P 5.645 2.35543002 30 P 0 8 0;0,3=24,5=0
P 5.6 2.366 32 P 0 8 0;0,3=0,5=0
P 5.465 2.324 32 P 0 8 0;0,3=0,5=0
L 5.51 2.324 5.465 2.324 3 P 0 
L 5.555 2.324 5.51 2.324 3 P 0 
P 5.51 2.324 32 P 0 8 0;0,3=0,5=0
P 5.555 2.324 32 P 0 8 0;0,3=0,5=0
L 5.555 2.324 5.555 2.30356998 3 P 0 
L 5.555 2.30356998 5.53121998 2.27978996 3 P 0 
P 5.53121998 2.27978996 15 P 0 8 0;1,3=10,5=1
P 5.687 1.99 39 P 0 8 0;0,3=12,5=0
L 5.687 1.99 5.641 1.99 10 P 0 
L 5.641 1.99 5.631 1.98 10 P 0 
P 5.631 1.98 36 P 0 8 0;0,3=0,5=0
L 5.51 2.129 5.49 2.129 10 P 0 
L 5.49 2.129 5.47211004 2.11111004 10 P 0 
L 5.47211004 2.11111004 5.47211004 2.098 10 P 0 
L 5.47211004 2.098 5.47211004 2.08101004 10 P 0 
L 5.47211004 2.08101004 5.48711998 2.066 10 P 0 
L 5.48711998 2.066 5.51 2.066 10 P 0 
P 5.47211004 2.098 15 P 0 8 0;1,3=14,5=1
P 5.51 2.129 32 P 0 8 0;0,3=0,5=0
P 5.51 2.066 32 P 0 8 0;0,3=0,5=0
P 3.817 0.924 15 P 0 8 0;1,3=10,5=1
L 3.77 0.917 3.81 0.917 3 P 0 
L 3.81 0.917 3.817 0.924 3 P 0 
P 3.77 0.917 38 P 0 8 0;0,3=8,5=0
L 4.27 0.832 4.32 0.882 10 P 0 
L 4.32 0.882 4.32 0.919 10 P 0 
L 4.275 0.919 4.274 0.919 10 P 0 
L 4.274 0.919 4.25 0.895 10 P 0 
L 4.25 0.895 4.25 0.877 10 P 0 
L 4.32 0.919 4.275 0.919 11 P 0 
P 4.27 0.832 38 P 0 8 0;0,3=8,5=0
P 4.25 0.877 15 P 0 8 0;1,3=1,5=1
P 4.275 0.919 32 P 0 8 0;0,3=0,5=0
P 4.32 0.919 32 P 0 8 0;0,3=0,5=0
L 5.446 0.69 5.45 0.694 3 P 0 
L 5.45 0.694 5.495 0.694 3 P 0 
P 5.446 0.69 36 P 0 8 0;0,3=0,5=0
P 5.557 0.705 32 P 0 8 0;0,3=0,5=0
L 5.557 0.705 5.506 0.705 3 P 0 
L 5.506 0.705 5.495 0.694 3 P 0 
P 5.495 0.694 15 P 0 8 0;1,3=10,5=1
L 5.49 0.635 5.485 0.64 3 P 0 
L 5.485 0.64 5.446 0.64 3 P 0 
L 5.555 0.65 5.515 0.65 3 P 0 
L 5.515 0.65 5.5 0.635 3 P 0 
L 5.5 0.635 5.49 0.635 3 P 0 
P 5.49 0.635 15 P 0 8 0;1,3=1,5=1
P 5.446 0.64 36 P 0 8 0;0,3=0,5=0
P 5.555 0.65 32 P 0 8 0;0,3=0,5=0
P 5.725 0.60301004 15 P 0 8 0;1,3=10,5=1
P 5.686 0.76 15 P 0 8 0;1,3=10,5=1
L 5.772 0.7 5.735 0.7 3 P 0 
L 5.735 0.7 5.7287 0.6937 3 P 0 
L 5.7287 0.6937 5.7287 0.6757 3 P 0 
P 5.7287 0.6757 15 P 0 8 0;1,3=10,5=1
P 5.772 0.7 32 P 0 8 0;0,3=0,5=0
L 5.772 0.7 5.772 0.751 3 P 0 
L 5.772 0.751 5.775 0.754 3 P 0 
P 5.825 0.754 32 P 0 8 0;0,3=0,5=0
L 5.825 0.754 5.775 0.754 3 P 0 
P 5.775 0.754 32 P 0 8 0;0,3=0,5=0
L 5.811 4.075 5.845 4.075 3 P 0 
L 5.845 4.075 5.855 4.085 3 P 0 
L 5.855 4.085 5.855 4.095 3 P 0 
P 5.855 4.095 15 P 0 8 0;1,3=14,5=1
L 5.811 4.12 5.84 4.12 3 P 0 
L 5.84 4.12 5.855 4.105 3 P 0 
L 5.855 4.105 5.855 4.095 3 P 0 
P 5.811 4.12 36 P 0 8 0;0,3=0,5=0
P 5.811 4.075 36 P 0 8 0;0,3=0,5=0
L 5.61731004 4.085 5.61731004 4.09268996 3 P 0 
L 5.61731004 4.09268996 5.595 4.115 3 P 0 
L 5.595 4.115 5.571 4.115 3 P 0 
P 5.61731004 4.085 15 P 0 8 0;1,3=14,5=1
L 5.571 4.07 5.61261004 4.07 3 P 0 
L 5.61261004 4.07 5.61731004 4.0747 3 P 0 
L 5.61731004 4.0747 5.61731004 4.085 3 P 0 
P 5.571 4.115 36 P 0 8 0;0,3=0,5=0
P 5.571 4.07 36 P 0 8 0;0,3=0,5=0
L 5.38558002 4.13778996 5.39936998 4.124 3 P 0 
L 5.39936998 4.124 5.435 4.124 3 P 0 
P 5.435 4.124 32 P 0 8 0;0,3=0,5=0
P 5.38558002 4.13778996 15 P 0 8 0;1,3=1,5=1
L 5.485 4.11 5.49 4.115 3 P 0 
L 5.49 4.115 5.529 4.115 3 P 0 
P 5.529 4.115 36 P 0 8 0;0,3=0,5=0
P 5.485 4.11 15 P 0 8 0;1,3=1,5=1
L 5.725 4.135 5.74 4.12 3 P 0 
L 5.74 4.12 5.769 4.12 3 P 0 
P 5.769 4.12 36 P 0 8 0;0,3=0,5=0
P 5.725 4.135 15 P 0 8 0;1,3=1,5=1
L 5.6218 4.13778996 5.63358996 4.126 3 P 0 
L 5.63358996 4.126 5.675 4.126 3 P 0 
P 5.675 4.126 32 P 0 8 0;0,3=0,5=0
P 5.6218 4.13778996 15 P 0 8 0;1,3=1,5=1
P 5.323 4.257 15 P 0 8 0;1,3=10,5=1
L 5.323 4.20101004 5.323 4.257 3 P 0 
P 5.323 4.20101004 32 P 0 8 0;0,3=0,5=0
L 3.83 3.335 3.83 3.36 3 P 0 
L 3.83 3.36 3.82 3.37 3 P 0 
L 3.82 3.37 3.786 3.37 3 P 0 
P 3.786 3.37 36 P 0 8 0;0,3=0,5=0
L 3.786 3.37 3.786 3.415 3 P 0 
P 3.786 3.415 36 P 0 8 0;0,3=0,5=0
P 3.83 3.335 15 P 0 8 0;1,3=5,5=1
P 3.415 3.285 15 P 0 8 0;1,3=5,5=1
L 3.415 3.285 3.42 3.28 3 P 0 
L 3.42 3.28 3.464 3.28 3 P 0 
P 3.464 3.235 36 P 0 8 0;0,3=0,5=0
L 3.464 3.235 3.464 3.28 3 P 0 
P 3.464 3.28 36 P 0 8 0;0,3=0,5=0
L 3.83 3.285 3.825 3.28 3 P 0 
L 3.825 3.28 3.786 3.28 3 P 0 
P 3.786 3.28 36 P 0 8 0;0,3=0,5=0
L 3.786 3.28 3.786 3.325 3 P 0 
P 3.786 3.325 36 P 0 8 0;0,3=0,5=0
P 3.83 3.285 15 P 0 8 0;1,3=5,5=1
P 3.415 3.385 15 P 0 8 0;1,3=5,5=1
P 3.464 3.415 36 P 0 8 0;0,3=0,5=0
L 3.464 3.415 3.464 3.37 3 P 0 
L 3.415 3.385 3.43 3.37 3 P 0 
L 3.43 3.37 3.464 3.37 3 P 0 
P 3.464 3.37 36 P 0 8 0;0,3=0,5=0
L 4.884 1.975 4.84611998 1.975 3 P 0 
L 4.84611998 1.975 4.83871004 1.98241004 3 P 0 
P 4.83871004 1.98241004 15 P 0 8 0;1,3=1,5=1
P 4.884 1.975 36 P 0 8 0;0,3=0,5=0
P 4.80288002 2.03788002 15 P 0 8 0;1,3=1,5=1
L 4.97 3.41 5.005 3.41 3 P 0 
L 5.005 3.41 5.031 3.436 3 P 0 
L 5.031 3.436 5.031 3.455 3 P 0 
P 4.97 3.41 15 P 0 8 0;1,3=1,5=1
L 4.985 3.504 5.011 3.504 3 P 0 
L 5.011 3.504 5.031 3.484 3 P 0 
L 5.031 3.484 5.031 3.455 3 P 0 
P 4.985 3.504 32 P 0 8 0;0,3=0,5=0
P 5.031 3.455 36 P 0 8 0;0,3=0,5=0
P 4.38373996 1.90248002 11 P 0 8 0;3=2,5=1
L 4.81 3.41 4.86661004 3.41 3 P 0 
L 4.86661004 3.41 4.935 3.47838996 3 P 0 
L 4.935 3.47838996 4.935 3.504 3 P 0 
P 4.81 3.41 12 P 0 8 0;3=3,5=1
P 4.935 3.504 32 P 0 8 0;0,3=0,5=0
P 4.42311004 2.09933002 15 P 0 8 0;1,3=6,5=1
L 3.539 4.13 3.555 4.146 3 P 0 
L 3.555 4.146 3.555 4.175 3 P 0 
L 3.555 4.175 3.552 4.178 3 P 0 
L 3.552 4.178 3.552 4.197 3 P 0 
L 3.48863002 4.105 3.514 4.105 3 P 0 
L 3.514 4.105 3.539 4.13 3 P 0 
P 3.552 4.197 36 P 0 8 0;0,3=0,5=0
P 3.539 4.13 36 P 0 8 0;0,3=0,5=0
P 3.48863002 4.105 15 P 0 8 0;1,3=1,5=1
P 2.987 3.235 11 P 0 8 0;3=11,5=1
L 0.718 1.599 0.7595 1.6405 3 P 0 
L 0.7595 1.6405 0.7595 1.642 3 P 0 
L 0.808 1.594 0.776 1.594 3 P 0 
L 0.776 1.594 0.7595 1.6105 3 P 0 
L 0.7595 1.6105 0.7595 1.6405 3 P 0 
P 0.718 1.599 36 P 0 8 0;0,3=0,5=0
P 0.7595 1.642 15 P 0 8 0;1,3=10,5=1
P 0.808 1.594 36 P 0 8 0;0,3=0,5=0
L 0.808 1.639 0.808 1.594 3 P 0 
P 0.808 1.639 36 P 0 8 0;0,3=0,5=0
L 0.808 1.684 0.808 1.639 3 P 0 
P 0.808 1.684 36 P 0 8 0;0,3=0,5=0
P 2.987 3.27 11 P 0 8 0;3=11,5=1
L 0.761 1.544 0.717 1.544 3 P 0 
L 0.808 1.549 0.7657 1.549 3 P 0 
L 0.7657 1.549 0.761 1.5443 3 P 0 
L 0.761 1.5443 0.761 1.544 3 P 0 
P 0.761 1.544 15 P 0 8 0;1,3=10,5=1
P 0.804 1.5 36 P 0 8 0;0,3=0,5=0
L 0.804 1.5 0.808 1.504 3 P 0 
L 0.808 1.504 0.808 1.549 3 P 0 
P 0.808 1.549 36 P 0 8 0;0,3=0,5=0
P 0.716 1.495 36 P 0 8 0;0,3=0,5=0
L 0.716 1.495 0.716 1.543 3 P 0 
L 0.716 1.543 0.717 1.544 3 P 0 
P 0.717 1.544 36 P 0 8 0;0,3=0,5=0
P 4.54121998 1.82373996 11 P 0 8 0;3=2,5=1
P 4.79246004 1.78463996 15 P 0 8 0;1,3=1,5=1
L 4.79246004 1.78463996 4.85863996 1.78463996 3 P 0 
L 4.85863996 1.78463996 4.884 1.81 3 P 0 
P 4.884 1.81 36 P 0 8 0;0,3=0,5=0
L 4.54121998 2.17806998 4.54121998 2.24301998 3 P 0 
L 4.54121998 2.24301998 4.536 2.24823996 3 P 0 
L 4.536 2.24823996 4.536 2.29178002 3 P 0 
L 4.536 2.29178002 4.54121998 2.297 3 P 0 
L 4.54121998 2.297 4.54121998 2.38521998 3 P 0 
L 4.54121998 2.38521998 4.575 2.419 3 P 0 
P 4.62 2.419 32 P 0 8 0;0,3=0,5=0
L 4.62 2.419 4.575 2.419 3 P 0 
P 4.575 2.419 32 P 0 8 0;0,3=0,5=0
P 4.54121998 2.17806998 15 P 0 8 0;1,3=6,5=1
L 0.85 1.594 0.88408996 1.594 3 P 0 
L 0.88408996 1.594 0.911 1.56708996 3 P 0 
L 0.911 1.56708996 0.911 1.514 3 P 0 
L 0.911 1.514 0.92 1.505 3 P 0 
L 0.92 1.505 0.92 1.49 3 P 0 
L 0.92 1.49 0.955 1.455 3 P 0 
L 1.3505 0.658 1.42841004 0.658 3 P 0 
L 1.42841004 0.658 1.45235 0.68193996 3 P 0 
L 1.45235 0.68193996 1.45235 0.69226004 3 P 0 
L 1.45235 0.69226004 1.512 0.75191004 3 P 0 
P 0.955 1.455 15 P 0 8 0;1,3=1,5=1
P 1.3505 0.658 36 P 0 8 0;0,3=0,5=0
P 1.512 0.75191004 12 P 0 8 0;3=3,5=1
P 0.85 1.594 36 P 0 8 0;0,3=0,5=0
P 1.8091 0.6339 15 P 0 8 0;1,3=10,5=1
L 1.459 0.752 1.4632 0.7478 3 P 0 
L 1.4632 0.7478 1.4632 0.7345 3 P 0 
L 1.4632 0.7345 1.4585 0.7298 3 P 0 
L 1.4585 0.7298 1.4433 0.7298 3 P 0 
L 1.4433 0.7298 1.4386 0.7345 3 P 0 
L 1.4386 0.7345 1.4386 0.7401 3 P 0 
L 1.4386 0.7401 1.4332 0.7455 3 P 0 
L 1.4332 0.7455 1.4113 0.7455 3 P 0 
L 1.4113 0.7455 1.4064 0.7406 3 P 0 
L 1.4064 0.7406 1.4064 0.728 3 P 0 
L 1.4064 0.728 1.3864 0.708 3 P 0 
L 1.3864 0.708 1.3864 0.6951 3 P 0 
L 1.3864 0.6951 1.3746 0.6833 3 P 0 
L 1.3746 0.6833 1.3554 0.6833 3 P 0 
L 1.3554 0.6833 1.3507 0.688 3 P 0 
L 1.3507 0.688 1.3507 0.708 3 P 0 
L 0.905 1.445 0.895 1.455 3 P 0 
L 0.895 1.455 0.86685 1.455 3 P 0 
L 0.86685 1.455 0.846 1.47585 3 P 0 
L 0.846 1.47585 0.846 1.5 3 P 0 
P 1.459 0.752 11 P 0 8 0;3=11,5=1
P 1.3507 0.708 36 P 0 8 0;0,3=0,5=0
P 0.905 1.445 12 P 0 8 0;3=3,5=1
P 0.846 1.5 36 P 0 8 0;0,3=0,5=0
P 2.40508002 0.731 11 P 0 8 0;3=11,5=1
L 2.40508002 0.731 2.40001004 0.72593002 1 P 0 
A 2.40001004 0.72593002 2.38908002 0.7214 2.38907992 0.73685098 1 P 0 Y
L 2.38908002 0.7214 2.3796 0.7214 1 P 0 
A 2.3796 0.7214 2.362 0.7038 2.3796 0.7038 1 P 0 N
L 2.362 0.7038 2.362 0.6652 1 P 0 
L 2.362 0.6652 2.36203002 0.65301998 1 P 0 
A 2.36203002 0.65301998 2.35635 0.63921004 2.34252215 0.65297047 1 P 0 Y
L 2.35635 0.63921004 2.3431 0.6259 1 P 0 
P 2.3431 0.6259 32 P 0 8 0;0,3=0,5=0
P 4.08846998 1.68595 14 P 0 8 0;0,3=19,5=0
L 4.08846998 1.68595 4.06878996 1.66626998 1 P 0 
P 4.06878996 1.66626998 11 P 0 8 0;3=25,5=1
P 2.40508002 0.699 11 P 0 8 0;3=11,5=1
L 4.02941998 1.66626998 4.04908996 1.68593996 1 P 0 
L 4.04908996 1.68593996 4.04908996 1.68595 1 P 0 
P 4.04908996 1.68595 14 P 0 8 0;0,3=19,5=0
P 4.02941998 1.66626998 11 P 0 8 0;3=25,5=1
L 2.39311004 0.626 2.37978002 0.63926998 1 P 0 
A 2.37978002 0.63926998 2.37403996 0.65303002 2.39353376 0.65308465 1 P 0 Y
L 2.37403996 0.65303002 2.374 0.66521998 1 P 0 
L 2.374 0.66521998 2.374 0.7038 1 P 0 
A 2.374 0.7038 2.3796 0.7094 2.3796 0.7038 1 P 0 Y
L 2.3796 0.7094 2.38771004 0.7094 1 P 0 
A 2.38771004 0.7094 2.39961004 0.70446998 2.38770994 0.69257293 1 P 0 Y
L 2.39961004 0.70446998 2.40508002 0.699 1 P 0 
P 2.39311004 0.626 32 P 0 8 0;0,3=0,5=0
L 4.4085 1.16598996 4.39915 1.15663996 1 P 0 
A 4.39915 1.15663996 4.398 1.15386998 4.40191102 1.15386988 1 P 0 N
L 4.398 1.15386998 4.398 1.13991998 1 P 0 
A 4.398 1.13991998 4.39936004 1.13663996 4.40263533 1.13991998 1 P 0 N
L 4.39936004 1.13663996 4.415 1.121 1 P 0 
P 4.415 1.121 32 P 0 8 0;0,3=0,5=0
P 4.4085 1.16598996 11 P 0 8 0;3=11,5=1
P 4.46248002 1.43005 11 P 0 8 0;3=25,5=1
L 4.48216998 1.44973002 4.48216004 1.44973002 1 P 0 
L 4.48216004 1.44973002 4.46248002 1.43005 1 P 0 
P 4.48216998 1.44973002 14 P 0 8 0;0,3=19,5=0
L 4.3765 1.16598996 4.38341004 1.15908002 1 P 0 
A 4.38341004 1.15908002 4.386 1.15283002 4.37716398 1.15283002 1 P 0 Y
L 4.386 1.15283002 4.386 1.13861998 1 P 0 
A 4.386 1.13861998 4.38485 1.13585 4.38208898 1.13861998 1 P 0 Y
L 4.38485 1.13585 4.37 1.121 1 P 0 
P 4.37 1.121 32 P 0 8 0;0,3=0,5=0
P 4.3765 1.16598996 11 P 0 8 0;3=11,5=1
P 4.50185 1.43005 11 P 0 8 0;3=25,5=1
L 4.52155 1.44973002 4.52153002 1.44973002 1 P 0 
L 4.52153002 1.44973002 4.50185 1.43005 1 P 0 
P 4.52155 1.44973002 14 P 0 8 0;0,3=19,5=0
P 4.0485 1.16098996 11 P 0 8 0;3=11,5=1
P 4.08846998 1.4891 14 P 0 8 0;0,3=19,5=0
L 4.08846998 1.4891 4.08846998 1.48911004 1 P 0 
L 4.08846998 1.48911004 4.06878996 1.50878996 1 P 0 
P 4.06878996 1.50878996 11 P 0 8 0;3=25,5=1
P 4.0165 1.16098996 11 P 0 8 0;3=11,5=1
P 4.04908996 1.4891 14 P 0 8 0;0,3=19,5=0
L 4.04908996 1.4891 4.04908996 1.48911998 1 P 0 
L 4.04908996 1.48911998 4.02941998 1.50878996 1 P 0 
P 4.02941998 1.50878996 11 P 0 8 0;3=25,5=1
P 4.82 2.125 15 P 0 8 0;1,3=4,5=0
P 4.38373996 1.78436998 11 P 0 8 0;3=2,5=1
P 3.54663996 1.04706998 11 P 0 8 0;3=11,5=1
P 4.6987 1.46941998 11 P 0 8 0;3=25,5=1
P 3.51463996 1.04706998 11 P 0 8 0;3=11,5=1
P 4.73806998 1.46941998 11 P 0 8 0;3=25,5=1
P 3.44998996 1.085 11 P 0 8 0;3=11,5=1
P 4.73806998 1.39066998 11 P 0 8 0;3=25,5=1
P 3.41798996 1.085 11 P 0 8 0;3=11,5=1
P 4.73806998 1.3513 11 P 0 8 0;3=25,5=1
P 3.445 1.815 12 P 0 8 0;3=3,5=1
L 2.49498996 2.04 2.49498996 1.94 3 P 0 
L 2.49498996 1.94 2.68768996 1.7473 3 P 0 
L 2.68768996 1.7473 2.8773 1.7473 3 P 0 
L 2.8773 1.7473 2.925 1.795 3 P 0 
L 2.925 1.795 3.425 1.795 3 P 0 
L 3.425 1.795 3.445 1.815 3 P 0 
P 4.58058996 1.90248002 11 P 0 8 0;3=2,5=1
L 2.46558996 2.193 2.46558996 2.0694 3 P 0 
L 2.46558996 2.0694 2.49498996 2.04 3 P 0 
P 2.49498996 2.04 15 P 0 8 0;1,3=14,5=1
L 2.46558996 2.193 2.46558996 2.21558996 3 P 0 
L 2.46558996 2.21558996 2.475 2.225 3 P 0 
L 2.475 2.225 2.495 2.225 3 P 0 
L 2.495 2.225 2.504 2.216 3 P 0 
L 2.504 2.216 2.54 2.216 3 P 0 
P 2.46558996 2.193 29 P 0 8 0;0,3=22,5=0
P 2.54 2.264 32 P 0 8 0;0,3=0,5=0
L 2.54 2.264 2.54 2.216 3 P 0 
P 2.54 2.216 32 P 0 8 0;0,3=0,5=0
P 4.65933002 1.94185 11 P 0 8 0;3=2,5=1
P 4.785 3.46 15 P 0 8 0;1,3=1,5=1
S P 0
OB 3.67 1.355 I
OS 3.6675 1.3575
OS 3.6675 1.42
OS 3.67 1.42
OS 3.67 1.45
OS 3.675 1.455
OS 3.825 1.455
OS 3.84 1.44
OS 3.84 1.365
OS 3.83 1.355
OS 3.67 1.355
OE
SE
P 3.9113 1.70563996 11 P 0 8 0;3=2,5=1
L 3.93098002 1.72531998 3.9113 1.70563996 10 P 0 
P 3.93098002 1.72531998 14 P 0 8 0;0,3=19,5=0
P 3.8863 1.745 36 P 0 8 0;0,3=0,5=0
L 3.9113 1.70563996 3.8863 1.73063996 10 P 0 
L 3.8863 1.73063996 3.8863 1.745 10 P 0 
P 3.674 1.744 12 P 0 8 0;3=3,5=1
L 3.674 1.744 3.6829 1.7351 10 P 0 
L 3.6829 1.7351 3.6889 1.7351 10 P 0 
L 3.6889 1.7351 3.704 1.72 10 P 0 
P 3.704 1.72 36 P 0 8 0;0,3=0,5=0
P 3.95066998 1.58753002 11 P 0 8 0;3=2,5=1
L 3.9113 1.54816004 3.93098002 1.52848002 10 P 0 
L 3.93098002 1.52848002 3.93098002 1.52846998 10 P 0 
P 3.93098002 1.52846998 14 P 0 8 0;0,3=19,5=0
P 3.9113 1.54816004 11 P 0 8 0;3=2,5=1
P 3.93098002 1.64658002 14 P 0 8 0;0,3=19,5=0
L 3.93098002 1.64658002 3.9113 1.6269 10 P 0 
P 3.9113 1.6269 11 P 0 8 0;3=2,5=1
P 3.97035 1.44973002 14 P 0 8 0;0,3=19,5=0
L 3.97035 1.44973002 3.95066998 1.43005 10 P 0 
P 3.95066998 1.43005 11 P 0 8 0;3=2,5=1
P 3.93098002 1.4891 14 P 0 8 0;0,3=19,5=0
L 3.93098002 1.4891 3.9113 1.46941998 10 P 0 
P 3.9113 1.46941998 11 P 0 8 0;3=2,5=1
P 3.82 1.42 15 P 0 8 0;1,3=1,5=1
P 3.79 1.41 12 P 0 8 0;3=3,5=1
P 3.74 1.41 12 P 0 8 0;3=3,5=1
P 3.765 1.41 12 P 0 8 0;3=3,5=1
P 3.672 1.395 37 P 0 8 0;0,3=8,5=0
P 3.785 1.368 43 P 0 8 0;0,3=12,5=0
P 4.54121998 1.6269 11 P 0 8 0;3=2,5=1
P 4.9097 1.385 15 P 0 8 0;1,3=10,5=1
P 4.54121998 1.66626998 11 P 0 8 0;3=2,5=1
L 4.84 1.66 4.855 1.675 3 P 0 
L 4.855 1.675 4.884 1.675 3 P 0 
P 4.884 1.63 36 P 0 8 0;0,3=0,5=0
L 4.884 1.63 4.884 1.675 3 P 0 
P 4.884 1.675 36 P 0 8 0;0,3=0,5=0
P 4.84 1.66 15 P 0 8 0;1,3=1,5=1
P 4.81 1.725 15 P 0 8 0;1,3=1,5=1
P 3.375 1.194 11 P 0 8 0;3=11,5=1
L 4.5413 1.22166998 4.55046004 1.21251004 1 P 0 
A 4.55046004 1.21251004 4.5515 1.21 4.54795108 1.21 1 P 0 Y
L 4.5515 1.21 4.5515 1.20631998 1 P 0 
A 4.5515 1.20631998 4.5488 1.1998 4.54227766 1.20631998 1 P 0 Y
L 4.5488 1.1998 4.53 1.181 1 P 0 
P 4.53 1.181 32 P 0 8 0;0,3=0,5=0
P 4.5413 1.22166998 11 P 0 8 0;3=11,5=1
P 4.61996004 1.31193002 11 P 0 8 0;3=25,5=1
L 4.60026998 1.29223996 4.61996004 1.31193002 1 P 0 
P 4.60026998 1.29223996 14 P 0 8 0;0,3=19,5=0
P 3.375 1.162 11 P 0 8 0;3=11,5=1
L 4.5733 1.22166998 4.56481998 1.21318996 1 P 0 
A 4.56481998 1.21318996 4.5635 1.21 4.56801457 1.2099999 1 P 0 N
L 4.5635 1.21 4.5635 1.20631998 1 P 0 
A 4.5635 1.20631998 4.5662 1.1998 4.57272234 1.20631998 1 P 0 N
L 4.5662 1.1998 4.585 1.181 1 P 0 
P 4.585 1.181 32 P 0 8 0;0,3=0,5=0
P 4.5733 1.22166998 11 P 0 8 0;3=11,5=1
P 4.65933002 1.31193002 11 P 0 8 0;3=25,5=1
L 4.63965 1.29223996 4.63965 1.29225 1 P 0 
L 4.63965 1.29225 4.65933002 1.31193002 1 P 0 
P 4.63965 1.29223996 14 P 0 8 0;0,3=19,5=0
L 5.323 4.15901004 5.323 4.088 3 P 0 
L 5.323 4.088 5.3 4.065 3 P 0 
P 5.3 4.065 15 P 0 8 0;1,3=4,5=0
P 5.323 4.15901004 32 P 0 8 0;0,3=0,5=0
L 5.273 4.15901004 5.323 4.15901004 3 P 0 
P 5.273 4.15901004 32 P 0 8 0;0,3=0,5=0
P 4.10816004 1.70563996 11 P 0 8 0;3=2,5=1
P 4.365 2.33 12 P 0 8 0;3=3,5=1
P 4.38373996 2.02058996 15 P 0 8 0;1,3=6,5=1
P 4.38373996 2.05996004 11 P 0 8 0;3=2,5=1
L 4.485 2.419 4.485 2.375 3 P 0 
P 4.485 2.375 15 P 0 8 0;1,3=1,5=1
P 4.485 2.419 32 P 0 8 0;0,3=0,5=0
L 4.485 2.419 4.53 2.419 3 P 0 
P 4.53 2.419 32 P 0 8 0;0,3=0,5=0
L 4.36748996 2.25 4.39735 2.27986004 3 P 0 
L 4.39735 2.27986004 4.39735 2.38841004 3 P 0 
L 4.39735 2.38841004 4.395 2.39076004 3 P 0 
L 4.395 2.39076004 4.395 2.419 3 P 0 
L 4.38373996 2.09933002 4.3651 2.11796998 3 P 0 
L 4.3651 2.11796998 4.3651 2.24761004 3 P 0 
L 4.3651 2.24761004 4.36748996 2.25 3 P 0 
P 4.38373996 2.09933002 11 P 0 8 0;3=2,5=1
P 4.36748996 2.25 15 P 0 8 0;1,3=14,5=1
P 4.44 2.419 32 P 0 8 0;0,3=0,5=0
L 4.44 2.419 4.395 2.419 3 P 0 
P 4.395 2.419 32 P 0 8 0;0,3=0,5=0
P 4.54121998 1.58753002 11 P 0 8 0;3=2,5=1
P 4.9097 1.335 15 P 0 8 0;1,3=10,5=1
P 4.26563996 1.78436998 11 P 0 8 0;3=2,5=1
L 4.35 2.419 4.35 2.39 3 P 0 
L 4.35 2.39 4.365 2.375 3 P 0 
P 4.365 2.375 15 P 0 8 0;1,3=1,5=1
P 4.35 2.419 32 P 0 8 0;0,3=0,5=0
P 3.465 1.74 12 P 0 8 0;3=3,5=1
P 3.44 1.03 15 P 0 8 0;1,3=1,5=1
L 2.44 2.193 2.44 1.95 3 P 0 
L 2.44 1.95 2.66 1.73 3 P 0 
L 2.66 1.73 2.88446998 1.73 3 P 0 
L 2.88446998 1.73 2.93216998 1.7777 3 P 0 
L 2.93216998 1.7777 3.4273 1.7777 3 P 0 
L 3.4273 1.7777 3.465 1.74 3 P 0 
P 2.44 2.193 29 P 0 8 0;0,3=22,5=0
L 6.255 1.96773996 6.255 1.925 3 P 0 
L 6.255 1.925 6.285 1.895 3 P 0 
P 6.285 1.895 12 P 0 8 0;3=3,5=1
P 6.255 1.96773996 32 P 0 8 0;0,3=0,5=0
L 6.3 1.96773996 6.255 1.96773996 3 P 0 
P 6.3 1.96773996 32 P 0 8 0;0,3=0,5=0
L 6.335 2.05906004 6.335 2.04873996 10 P 0 
L 6.335 2.04873996 6.3 2.01373996 10 P 0 
L 6.3 2.01373996 6.3 2.00973996 10 P 0 
L 6.258 2.15873996 6.275 2.14173996 10 P 0 
L 6.275 2.14173996 6.275 2.05373996 10 P 0 
P 6.258 2.15873996 11 P 0 8 0;3=11,5=1
P 6.3 2.00973996 32 P 0 8 0;0,3=0,5=0
P 6.275 2.05373996 12 P 0 8 0;3=3,5=1
P 6.335 2.05906004 15 P 0 8 0;1,3=10,5=1
L 1.8 4.024 1.8 3.995 10 P 0 
L 1.8 3.995 1.785 3.98 10 P 0 
L 1.785 3.98 1.77 3.98 10 P 0 
L 1.766 3.91 1.766 3.929 10 P 0 
L 1.766 3.929 1.75 3.945 10 P 0 
P 1.77 3.98 15 P 0 8 0;1,3=1,5=1
P 1.8 4.024 32 P 0 8 0;0,3=0,5=0
P 1.75 3.945 12 P 0 8 0;3=3,5=1
P 1.766 3.91 36 P 0 8 0;0,3=0,5=0
P 1.5315 3.9459 15 P 0 8 0;1,3=10,5=1
P 1.517 4.113 15 P 0 8 0;1,3=1,5=1
P 1.467 3.851 36 P 0 8 0;0,3=0,5=0
L 1.467 3.851 1.499 3.851 3 P 0 
L 1.499 3.851 1.511 3.863 3 P 0 
P 1.511 3.863 15 P 0 8 0;1,3=10,5=1
L 1.5153 4.063 1.499 4.063 8 P 0 
L 1.499 4.063 1.472 4.09 8 P 0 
P 1.477 4.142 36 P 0 8 0;0,3=0,5=0
P 1.5153 4.063 15 P 0 8 0;1,3=10,5=1
L 1.477 4.142 1.472 4.137 8 P 0 
L 1.472 4.137 1.472 4.09 8 P 0 
P 1.472 4.09 37 P 0 8 0;0,3=8,5=0
P 1.521 3.993 15 P 0 8 0;1,3=10,5=1
L 1.521 3.993 1.519 3.991 7 P 0 
L 1.519 3.991 1.477 3.991 7 P 0 
P 1.477 3.991 36 P 0 8 0;0,3=0,5=0
P 1.624 3.885 36 P 0 8 0;0,3=0,5=0
L 1.624 3.885 1.59 3.885 10 P 0 
L 1.59 3.885 1.579 3.874 10 P 0 
P 1.579 3.874 15 P 0 8 0;1,3=1,5=1
L 1.477 4.036 1.485 4.028 8 P 0 
L 1.485 4.028 1.539 4.028 8 P 0 
L 1.539 4.028 1.563 4.052 8 P 0 
L 1.563 4.052 1.585 4.052 8 P 0 
P 1.435 4.142 36 P 0 8 0;0,3=0,5=0
L 1.435 4.142 1.429 4.136 10 P 0 
L 1.429 4.136 1.429 4.101 10 P 0 
L 1.429 4.101 1.418 4.09 10 P 0 
L 1.435 4.18 1.435 4.142 10 P 0 
S P 0
OB 1.589 4.013 I
OS 1.585 4.017
OS 1.585 4.057
OS 1.585 4.065
OS 1.59 4.07
OS 1.623 4.07
OS 1.629 4.064
OS 1.629 4.057
OS 1.629 4.015
OS 1.627 4.013
OS 1.600069980315 4.013
OS 1.589 4.013
OE
SE
P 1.6265 4.031 45 P 0 8 0;0,3=23,5=0
P 1.585 4.052 12 P 0 8 0;3=3,5=1
P 1.477 4.036 36 P 0 8 0;0,3=0,5=0
P 1.435 4.18 12 P 0 8 0;3=3,5=1
P 1.418 4.09 37 P 0 8 0;0,3=8,5=0
P 1.522 4.163 15 P 0 8 0;1,3=10,5=1
P 1.4 4.01 12 P 0 8 0;3=3,5=1
P 5.14 3.74 12 P 0 8 0;3=3,5=1
P 5.175 3.74 12 P 0 8 0;3=3,5=1
P 5.18 3.825 12 P 0 8 0;3=3,5=1
P 5.675 4.084 32 P 0 8 0;0,3=0,5=0
L 5.675 4.084 5.675 4.03 10 P 0 
P 5.675 4.03 12 P 0 8 0;3=3,5=1
P 1.56 3.29 12 P 0 8 0;3=3,5=1
P 1.56 3.25 12 P 0 8 0;3=3,5=1
S P 0
OB 3.16 2.96 I
OS 3.17 2.97
OS 3.245 2.97
OS 3.255 2.96
OS 3.255 2.895
OS 3.22 2.895
OS 3.215 2.9
OS 3.16 2.9
OS 3.16 2.96
OE
SE
P 3.245 2.955 12 P 0 8 0;3=3,5=1
P 3.21 2.955 12 P 0 8 0;3=3,5=1
P 3.175 2.955 12 P 0 8 0;3=3,5=1
P 3.245 2.901 32 P 0 8 0;0,3=0,5=0
P 3.185 2.907 38 P 0 8 0;0,3=8,5=0
S P 0
OB 2.073 3.994 I
OS 2.26 3.994
OS 2.291 3.963
OS 2.291 3.881
OS 2.26 3.85
OS 2.18 3.85
OS 2.16888996063 3.83888996063
OS 2.168519980315 3.83873996063
OC 2.149980019685 3.811 2.18000265748 3.811 N
OC 2.16478996063 3.785119980315 2.179997244094 3.810999901575 N
OS 2.16501003937 3.78498996063
OS 2.194 3.756
OS 2.20723996063 3.756
OS 2.207480019685 3.75593996063
OC 2.215 3.754980019685 2.215010629921 3.784998622047 N
OC 2.222519980315 3.75593996063 2.214989370079 3.784998622047 N
OS 2.22276003937 3.756
OS 2.25223996063 3.756
OS 2.252480019685 3.75593996063
OC 2.26 3.754980019685 2.260010629921 3.784998622047 N
OC 2.267519980315 3.75593996063 2.259989370079 3.784998622047 N
OS 2.26776003937 3.756
OS 2.321 3.756
OS 2.418 3.659
OS 2.586 3.659
OS 2.62 3.625
OS 2.62 3.445
OS 2.61 3.435
OS 2.411 3.435
OS 2.40766003937 3.43833996063
OC 2.410019980315 3.45 2.380001377953 3.450006791339 N
OC 2.38 3.480019980315 2.38 3.45 N
OC 2.369519980315 3.478130019685 2.380003248031 3.450000590551 N
OS 2.368319980315 3.477680019685
OS 2.2535 3.5925
OS 2.0705 3.5925
OS 2.021 3.642
OS 2.021 3.942
OS 2.073 3.994
OE
SE
P 2.59 3.445 12 P 0 8 0;3=3,5=1
P 2.55 3.445 12 P 0 8 0;3=3,5=1
P 2.51 3.445 12 P 0 8 0;3=3,5=1
P 2.47 3.445 12 P 0 8 0;3=3,5=1
P 2.2 3.96 12 P 0 8 0;3=3,5=1
P 2.25 3.96 15 P 0 8 0;1,3=4,5=0
P 1.351 4.126 12 P 0 8 0;3=3,5=1
P 2.165 3.96 12 P 0 8 0;3=3,5=1
P 2.155 3.925 12 P 0 8 0;3=3,5=1
P 2.19 3.925 12 P 0 8 0;3=3,5=1
L 3.23 4.015 3.23 4.056 10 P 0 
L 3.23 4.056 3.244 4.07 10 P 0 
P 3.23 4.015 15 P 0 8 0;1,3=1,5=1
P 3.244 4.07 36 P 0 8 0;0,3=0,5=0
L 3.185 3.921 3.185 3.97 10 P 0 
L 3.185 3.97 3.2 3.985 10 P 0 
P 3.2 3.985 12 P 0 8 0;3=3,5=1
P 3.185 3.921 32 P 0 8 0;0,3=0,5=0
L 3.594 4.197 3.594 4.171 3 P 0 
L 3.594 4.171 3.605 4.16 3 P 0 
L 3.605 4.16 3.655 4.16 3 P 0 
L 3.655 4.16 3.68 4.185 3 P 0 
L 3.68 4.185 3.745 4.185 3 P 0 
L 5.9065 2.4568 5.8746 2.4249 3 P 0 
L 5.8746 2.4249 5.66351004 2.4249 3 P 0 
L 5.66351004 2.4249 5.66326004 2.42465 3 P 0 
L 5.66326004 2.42465 5.64473996 2.42465 3 P 0 
L 5.64473996 2.42465 5.64448996 2.4249 3 P 0 
L 5.64448996 2.4249 5.5147 2.4249 3 P 0 
L 5.5147 2.4249 5.51 2.4202 3 P 0 
L 5.51 2.4202 5.51 2.366 3 P 0 
P 5.9065 2.4568 12 P 0 8 0;3=3,5=1
P 5.51 2.366 32 P 0 8 0;0,3=0,5=0
P 3.745 4.185 15 P 0 8 0;1,3=4,5=0
P 3.594 4.197 36 P 0 8 0;0,3=0,5=0
L 3.516 3.887 3.491 3.912 8 P 0 
L 3.491 3.912 3.47 3.912 8 P 0 
P 3.47 3.912 15 P 0 8 0;1,3=1,5=1
P 3.516 3.887 37 P 0 8 0;0,3=8,5=0
P 3.69 4.135 15 P 0 8 0;1,3=4,5=0
P 3.48278996 4.05678002 12 P 0 8 0;3=3,5=1
L 3.522 4.032 3.522 4.077 3 P 0 
P 3.522 4.077 36 P 0 8 0;0,3=0,5=0
L 3.522 4.032 3.50756998 4.032 3 P 0 
L 3.50756998 4.032 3.48278996 4.05678002 3 P 0 
P 3.522 4.032 36 P 0 8 0;0,3=0,5=0
L 3.522 3.987 3.521 3.988 8 P 0 
L 3.521 3.988 3.476 3.988 8 P 0 
P 3.476 3.988 15 P 0 8 0;1,3=1,5=1
P 3.522 3.987 36 P 0 8 0;0,3=0,5=0
P 3.386 4.095 36 P 0 8 0;0,3=0,5=0
L 3.386 4.095 3.39 4.099 10 P 0 
L 3.39 4.099 3.437 4.099 10 P 0 
P 3.437 4.099 15 P 0 8 0;1,3=1,5=1
L 3.405 3.916 3.441 3.952 9 P 0 
L 3.441 3.952 3.512 3.952 9 P 0 
L 3.512 3.952 3.522 3.942 9 P 0 
P 3.598 3.977 12 P 0 8 0;3=3,5=1
P 3.57 3.887 37 P 0 8 0;0,3=8,5=0
L 3.598 3.977 3.598 3.915 10 P 0 
L 3.598 3.915 3.57 3.887 10 P 0 
P 3.477 3.816 15 P 0 8 0;1,3=1,5=1
P 3.3725 3.947 45 P 0 8 0;0,3=23,5=0
S P 0
OB 3.41 3.965 I
OS 3.414 3.961
OS 3.414 3.921
OS 3.414 3.913
OS 3.409 3.908
OS 3.376 3.908
OS 3.37 3.914
OS 3.37 3.921
OS 3.37 3.963
OS 3.372 3.965
OS 3.398930019685 3.965
OS 3.41 3.965
OE
SE
P 3.522 3.942 36 P 0 8 0;0,3=0,5=0
P 3.405 3.916 12 P 0 8 0;3=3,5=1
P 5.68326004 3.712 15 P 0 8 0;1,3=1,5=1
P 5.686 3.807 15 P 0 8 0;1,3=1,5=1
P 5.50643002 4.009 15 P 0 8 0;1,3=5,5=1
P 5.686 3.76 15 P 0 8 0;1,3=1,5=1
P 5.72 3.857 36 P 0 8 0;0,3=0,5=0
L 5.72 3.857 5.683 3.857 10 P 0 
L 5.683 3.857 5.675 3.865 10 P 0 
P 5.675 3.865 15 P 0 8 0;1,3=1,5=1
L 5.718 3.965 5.72 3.963 3 P 0 
L 5.72 3.963 5.72 3.907 3 P 0 
P 5.718 3.965 15 P 0 8 0;3=4,5=0
P 5.72 3.907 36 P 0 8 0;0,3=0,5=0
P 6.05315 3.67518996 25 P 0 8 0;1,3=26,5=0
P 6.05315 3.50983996 21 P 0 8 0;1,3=27,5=0
P 6.05315 3.34448996 21 P 0 8 0;1,3=27,5=0
P 0.865 3.645 12 P 0 8 0;3=3,5=1
P 0.905 3.645 12 P 0 8 0;3=3,5=1
P 0.945 3.645 12 P 0 8 0;3=3,5=1
P 0.945 3.69 12 P 0 8 0;3=3,5=1
P 0.945 3.73 12 P 0 8 0;3=3,5=1
P 0.945 3.765 12 P 0 8 0;3=3,5=1
P 0.865 3.845 12 P 0 8 0;3=3,5=1
P 0.905 3.845 12 P 0 8 0;3=3,5=1
P 0.94 3.845 12 P 0 8 0;3=3,5=1
P 0.945 3.805 15 P 0 8 0;1,3=1,5=1
P 0.828 3.846 12 P 0 8 0;3=3,5=1
P 0.828 3.646 12 P 0 8 0;3=3,5=1
P 5.66 3.47 15 P 0 8 0;1,3=4,5=0
P 5.68 3.567 15 P 0 8 0;1,3=5,5=1
P 5.406 3.863 15 P 0 8 0;1,3=1,5=1
P 3.46 4.16 12 P 0 8 0;3=3,5=1
P 3.495 4.15 12 P 0 8 0;3=3,5=1
P 3.5 4.195 12 P 0 8 0;3=3,5=1
P 3.53 4.165 12 P 0 8 0;3=3,5=1
P 5.769 4.075 36 P 0 8 0;0,3=0,5=0
L 5.769 4.075 5.769 4.031 10 P 0 
P 5.769 4.031 12 P 0 8 0;3=3,5=1
P 5.644 3.967 15 P 0 8 0;1,3=1,5=1
P 5.803 3.907 12 P 0 8 0;3=3,5=1
P 1.45 3.78 12 P 0 8 0;3=3,5=1
P 1.485 3.76 15 P 0 8 0;1,3=10,5=1
P 1.485 3.8 12 P 0 8 0;3=3,5=1
P 5.406 2.346 15 P 0 8 0;1,3=4,5=0
P 5.375 2.32 12 P 0 8 0;3=3,5=1
P 5.34 2.315 12 P 0 8 0;3=3,5=1
S P 0
OB 5.33143996063 3.7485 I
OS 5.4365 3.7485
OS 5.451 3.734
OS 5.451 3.597
OS 5.443 3.589
OS 5.38 3.589
OS 5.375 3.594
OS 5.375 3.625
OS 5.355 3.645
OS 5.265 3.645
OS 5.253 3.657
OS 5.253 3.744
OS 5.2575 3.7485
OS 5.27256003937 3.7485
OS 5.27286003937 3.74841003937
OC 5.282 3.746980019685 5.282014665354 3.77699773622 N
OC 5.29113996063 3.74841003937 5.281985334646 3.77699773622 N
OS 5.29143996063 3.7485
OS 5.31256003937 3.7485
OS 5.31286003937 3.74841003937
OC 5.322 3.746980019685 5.322014665354 3.77699773622 N
OC 5.33113996063 3.74841003937 5.321985334646 3.77699773622 N
OS 5.33143996063 3.7485
OE
SE
P 5.316 3.69401004 28 P 0 8 0;0,3=28,5=0
P 5.43 3.6 15 P 0 8 0;1,3=1,5=1
P 5.433 3.651 12 P 0 8 0;3=3,5=1
P 5.43 3.7 12 P 0 8 0;3=3,5=1
P 5.39 3.6 12 P 0 8 0;3=3,5=1
P 5.393 3.651 12 P 0 8 0;3=3,5=1
P 5.39 3.7 12 P 0 8 0;3=3,5=1
L 1.582 3.776 1.626 3.776 10 P 0 
L 1.626 3.776 1.636 3.786 10 P 0 
P 1.582 3.776 36 P 0 8 0;0,3=0,5=0
P 1.6055 4.134 12 P 0 8 0;3=3,5=1
P 1.60581998 4.1 12 P 0 8 0;3=3,5=1
P 1.606 4.174 15 P 0 8 0;1,3=10,5=1
P 1.636 3.786 12 P 0 8 0;3=3,5=1
P 1.591 3.826 12 P 0 8 0;3=3,5=1
P 1.633 3.829 15 P 0 8 0;1,3=10,5=1
P 3.408 4.152 12 P 0 8 0;3=3,5=1
P 3.363 4.192 12 P 0 8 0;3=3,5=1
P 3.363 4.152 12 P 0 8 0;3=3,5=1
P 3.363 4.232 15 P 0 8 0;1,3=1,5=1
P 3.393 3.877 12 P 0 8 0;3=3,5=1
P 3.393 3.84 12 P 0 8 0;3=3,5=1
P 3.392 3.803 12 P 0 8 0;3=3,5=1
P 3.564 4.077 36 P 0 8 0;0,3=0,5=0
L 3.564 4.077 3.579 4.062 10 P 0 
L 3.579 4.062 3.607 4.062 10 P 0 
P 3.607 4.062 12 P 0 8 0;3=3,5=1
L 3.0535 2.217 3.126 2.217 3 P 0 
L 3.126 2.217 3.155 2.188 3 P 0 
L 3.155 2.188 3.155 1.92 3 P 0 
L 3.155 1.92 3.05 1.815 3 P 0 
L 3.05 1.815 2.915 1.815 3 P 0 
L 2.915 1.815 2.865 1.765 3 P 0 
L 2.865 1.765 2.73 1.765 3 P 0 
L 2.73 1.765 2.665 1.83 3 P 0 
L 2.665 1.83 2.665 2.065 3 P 0 
P 3.0535 2.217 44 P 0 8 0;0,3=17,5=0
L 2.665 2.065 2.61 2.12 3 P 0 
L 2.61 2.12 2.61 2.21838996 3 P 0 
L 2.61 2.21838996 2.65208996 2.26048002 3 P 0 
L 2.65208996 2.26048002 2.65208996 2.30598996 3 P 0 
L 2.65208996 2.30598996 2.6521 2.306 3 P 0 
P 2.665 2.065 15 P 0 8 0;1,3=14,5=1
L 2.41441004 2.287 2.41441004 2.26058996 3 P 0 
L 2.41441004 2.26058996 2.42 2.255 3 P 0 
L 2.42 2.255 2.485 2.255 3 P 0 
L 2.485 2.255 2.505 2.275 3 P 0 
L 2.505 2.275 2.505 2.3 3 P 0 
L 2.505 2.3 2.511 2.306 3 P 0 
L 2.511 2.306 2.54 2.306 3 P 0 
P 2.41441004 2.287 29 P 0 8 0;0,3=22,5=0
L 2.59 2.306 2.54 2.306 3 P 0 
L 2.6521 2.306 2.59 2.306 3 P 0 
L 2.6526 2.3065 2.6521 2.306 3 P 0 
P 2.54 2.306 32 P 0 8 0;0,3=0,5=0
P 2.6526 2.3065 31 P 0 8 0;0,3=20,5=0
P 2.59 2.306 32 P 0 8 0;0,3=0,5=0
P 3.185 3.879 32 P 0 8 0;0,3=0,5=0
L 3.185 3.879 3.185 3.823 10 P 0 
P 3.185 3.823 43 P 0 8 0;0,3=12,5=0
L 3.344 4.095 3.326 4.113 10 P 0 
L 3.326 4.113 3.3 4.113 10 P 0 
L 3.3 4.113 3.286 4.099 10 P 0 
L 3.286 4.099 3.286 4.07 10 P 0 
P 3.3 4.113 15 P 0 8 0;1,3=14,5=1
P 3.344 4.095 36 P 0 8 0;0,3=0,5=0
P 3.286 4.07 36 P 0 8 0;0,3=0,5=0
L 3.564 3.942 3.564 3.987 10 P 0 
P 3.564 3.942 36 P 0 8 0;0,3=0,5=0
P 3.564 3.987 36 P 0 8 0;0,3=0,5=0
P 1.807 4.13 39 P 0 8 0;0,3=12,5=0
L 1.807 4.13 1.807 4.073 10 P 0 
L 1.807 4.073 1.8 4.066 10 P 0 
P 1.8 4.066 32 P 0 8 0;0,3=0,5=0
P 1.352 4.084 15 P 0 8 0;1,3=1,5=1
L 1.724 3.91 1.707 3.927 10 P 0 
L 1.707 3.927 1.678 3.927 10 P 0 
L 1.678 3.927 1.666 3.915 10 P 0 
L 1.666 3.915 1.666 3.885 10 P 0 
P 1.678 3.927 15 P 0 8 0;1,3=14,5=1
P 1.666 3.885 36 P 0 8 0;0,3=0,5=0
P 1.724 3.91 36 P 0 8 0;0,3=0,5=0
P 1.435 4.036 36 P 0 8 0;0,3=0,5=0
L 1.435 4.036 1.435 3.991 10 P 0 
P 1.435 3.991 36 P 0 8 0;0,3=0,5=0
P 1.95 0.5455 15 P 0 8 0;1,3=10,5=1
P 5.681 3.617 15 P 0 8 0;1,3=1,5=1
P 5.681 3.664 15 P 0 8 0;1,3=1,5=1
L 5.502 2.721 5.41981998 2.721 3 P 0 
L 5.41981998 2.721 5.40318002 2.70436004 3 P 0 
P 5.40318002 2.70436004 15 P 0 8 0;1,3=10,5=1
P 5.502 2.721 36 P 0 8 0;0,3=0,5=0
L 0.55921998 1.40543002 0.55921998 1.41478002 3 P 0 
L 0.55921998 1.41478002 0.53 1.444 3 P 0 
P 0.53 1.444 32 P 0 8 0;0,3=0,5=0
P 0.55921998 1.40543002 15 P 0 8 0;1,3=1,5=1
L 0.535 0.884 0.535 0.87 3 P 0 
L 0.535 0.87 0.57 0.835 3 P 0 
P 0.535 0.884 32 P 0 8 0;0,3=0,5=0
P 0.57 0.835 15 P 0 8 0;1,3=1,5=1
L 6.23 2.05375 6.21 2.03375 3 P 0 
L 6.21 2.03375 6.21 2.00973996 3 P 0 
L 6.255 2.00973996 6.255 2.03138996 3 P 0 
L 6.255 2.03138996 6.23263996 2.05375 3 P 0 
L 6.23263996 2.05375 6.23 2.05375 3 P 0 
P 6.23 2.05375 15 P 0 8 0;1,3=14,5=1
P 6.255 2.00973996 32 P 0 8 0;0,3=0,5=0
P 6.21 2.00973996 32 P 0 8 0;0,3=0,5=0
P 3.584 1.827 15 P 0 8 0;1,3=10,5=1
P 1.54 3.776 36 P 0 8 0;0,3=0,5=0
L 1.535 3.905 1.544 3.896 3 P 0 
L 1.544 3.896 1.544 3.827 3 P 0 
L 1.544 3.827 1.539 3.822 3 P 0 
P 1.535 3.905 11 P 0 8 0;3=11,5=1
L 1.535 3.905 1.529 3.899 3 P 0 
L 1.529 3.899 1.479 3.899 3 P 0 
L 1.479 3.899 1.477 3.901 3 P 0 
P 1.539 3.822 15 P 0 8 0;1,3=14,5=1
L 1.54 3.776 1.54 3.821 3 P 0 
L 1.54 3.821 1.539 3.822 3 P 0 
L 1.477 3.901 1.477 3.946 3 P 0 
P 1.477 3.946 36 P 0 8 0;0,3=0,5=0
P 1.477 3.901 36 P 0 8 0;0,3=0,5=0
P 1.98135 0.365 11 P 0 8 0;3=11,5=1
P 1.7317 0.7084 15 P 0 8 0;1,3=1,5=1
P 1.91535 0.412 11 P 0 8 0;3=11,5=1
P 1.8039 0.7072 15 P 0 8 0;1,3=10,5=1
L 3.533 1.88648996 3.52246004 1.89703002 5 P 0 
A 3.52246004 1.89703002 3.51651004 1.90076004 3.51134902 1.88591673 5 P 0 N
A 3.51651004 1.90076004 3.51208996 1.9004 3.51215187 1.92695089 5 P 0 Y
A 3.51208996 1.9004 3.50095 1.9027 3.51208012 1.92848051 5 P 0 Y
A 3.50095 1.9027 3.48983996 1.905 3.48982136 1.87692697 5 P 0 N
L 3.48983996 1.905 3.47243002 1.905 5 P 0 
A 3.47243002 1.905 3.46241998 1.90643996 3.47240571 1.94034439 5 P 0 Y
A 3.46241998 1.90643996 3.45743002 1.90341004 3.46615728 1.89466102 5 P 0 N
L 3.45743002 1.90341004 3.45301004 1.89898996 5 P 0 
L 3.45301004 1.89898996 3.44483996 1.89898996 5 P 0 
A 3.44483996 1.89898996 3.43536004 1.90291004 3.44483159 1.91239242 5 P 0 Y
A 3.43536004 1.90291004 3.42333996 1.9079 3.4233315 1.89090748 5 P 0 N
L 3.42333996 1.9079 3.41036998 1.9079 5 P 0 
A 3.41036998 1.9079 3.40186998 1.90438002 3.41036811 1.8958815 5 P 0 N
L 3.40186998 1.90438002 3.35496998 1.85748002 5 P 0 
A 3.35496998 1.85748002 3.3345 1.849 3.33450443 1.87793543 5 P 0 Y
L 3.3345 1.849 3.2698 1.849 5 P 0 
A 3.2698 1.849 3.25036004 1.85705 3.26979567 1.8764875 5 P 0 Y
L 3.25036004 1.85705 3.24136998 1.86603996 5 P 0 
A 3.24136998 1.86603996 3.2353 1.88068996 3.25601398 1.88068986 5 P 0 Y
L 3.2353 1.88068996 3.2353 1.88956004 5 P 0 
A 3.2353 1.88956004 3.2316 1.89848996 3.22267362 1.88955994 5 P 0 N
L 3.2316 1.89848996 3.2271 1.90298996 5 P 0 
P 3.2271 1.90298996 11 P 0 8 0;3=13,5=1
P 3.533 1.88648996 36 P 0 8 0;0,3=0,5=0
P 3.45301004 1.89898996 11 P 0 8 0;3=13,5=1
L 3.533 1.93148996 3.52031004 1.9188 5 P 0 
A 3.52031004 1.9188 3.5121 1.91541004 3.51213819 1.92695433 5 P 0 Y
A 3.5121 1.91541004 3.5069 1.91646998 3.51205827 1.92849114 5 P 0 Y
A 3.5069 1.91646998 3.48985 1.92 3.48982254 1.87692687 5 P 0 N
L 3.48985 1.92 3.47243002 1.92 5 P 0 
A 3.47243002 1.92 3.45803996 1.92596004 3.47242569 1.94034154 5 P 0 Y
L 3.45803996 1.92596004 3.45301004 1.93098996 5 P 0 
L 3.45301004 1.93098996 3.44483996 1.93098996 5 P 0 
A 3.44483996 1.93098996 3.436 1.92766998 3.44482982 1.91758789 5 P 0 N
A 3.436 1.92766998 3.42333002 1.9229 3.4233253 1.94212441 5 P 0 Y
L 3.42333002 1.9229 3.41036004 1.9229 5 P 0 
A 3.41036004 1.9229 3.39126004 1.91498996 3.41036211 1.89587992 5 P 0 N
L 3.39126004 1.91498996 3.34436004 1.86808996 5 P 0 
A 3.34436004 1.86808996 3.33451004 1.864 3.33449843 1.87793386 5 P 0 Y
L 3.33451004 1.864 3.2698 1.864 5 P 0 
A 3.2698 1.864 3.26096998 1.86766004 3.26980177 1.87648593 5 P 0 Y
L 3.26096998 1.86766004 3.25198002 1.87665 5 P 0 
A 3.25198002 1.87665 3.2503 1.88068996 3.25601152 1.88069577 5 P 0 Y
L 3.2503 1.88068996 3.2503 1.88956004 5 P 0 
A 3.2503 1.88956004 3.25028002 1.89078996 3.2226687 1.88972628 5 P 0 N
A 3.25028002 1.89078996 3.25415 1.89803996 3.26417776 1.88802933 5 P 0 Y
L 3.25415 1.89803996 3.2591 1.90298996 5 P 0 
P 3.2591 1.90298996 11 P 0 8 0;3=13,5=1
P 3.45301004 1.93098996 11 P 0 8 0;3=13,5=1
P 3.533 1.93148996 36 P 0 8 0;0,3=0,5=0
P 1.26066998 2.64043002 20 P 0 8 0;1,3=29,5=0
L 1.26066998 2.64043002 1.16611004 2.64043002 3 P 0 
L 1.16611004 2.64043002 0.97553996 2.831 3 P 0 
L 0.97553996 2.831 0.908 2.831 3 P 0 
P 0.908 2.831 32 P 0 8 0;0,3=0,5=0
P 5.7455 3.0095 40 P 0 8 0;0,3=15,5=0
P 5.7505 2.7245 40 P 0 8 0;0,3=15,5=0
S P 0
OB 5.03 3.965 I
OS 5.09 3.965
OS 5.095 3.96
OS 5.095 3.888019980315
OS 5.073 3.888019980315
OC 5.06288996063 3.885269980315 5.073015354331 3.868004232283 N
OS 5.062419980315 3.885
OS 5.057580019685 3.885
OS 5.05711003937 3.885269980315
OC 5.047 3.888019980315 5.046984645669 3.868004232283 N
OS 5.023 3.888019980315
OC 5.022830019685 3.88801003937 5.024081791339 3.868064074803 N
OS 5.02198996063 3.88801003937
OS 5.02 3.89
OS 5.02 3.955
OS 5.03 3.965
OE
SE
P 5.035 3.945 15 P 0 8 0;1,3=1,5=1
P 5.085 3.896 32 P 0 8 0;0,3=0,5=0
P 5.035 3.896 32 P 0 8 0;0,3=0,5=0
P 5.075 3.945 12 P 0 8 0;3=3,5=1
S P 0
OB 2.720019980315 2.215 I
OS 2.7266 2.215
OC 2.7526 2.199980019685 2.7526 2.229993307087 N
OC 2.75406003937 2.200019980315 2.752508956693 2.229997440945 N
OS 2.75493996063 2.20006003937
OS 2.757980019685 2.19701003937
OS 2.757980019685 2.192
OC 2.778 2.171980019685 2.778 2.192 N
OS 2.802 2.171980019685
OC 2.818019980315 2.18 2.802 2.191990059055 N
OS 2.865 2.18
OS 2.914969980315 2.130030019685
OS 2.91498996063 2.129230019685
OC 2.949230019685 2.09498996063 2.95 2.13 N
OS 2.950030019685 2.094969980315
OS 2.985 2.06
OS 3 2.06
OS 3.005 2.055
OS 3.005 1.98
OS 3.02 1.965
OS 3.02 1.86
OS 3.01796003937 1.85796003937
OC 3.01158996063 1.858930019685 3.015131988189 1.860789370079 Y
OC 2.985 1.875019980315 2.985 1.845003937008 N
OC 2.95668996063 1.855 2.984999901575 1.844993602362 N
OS 2.95 1.855
OS 2.885 1.92
OS 2.885 1.995
OS 2.865 2.015
OS 2.805 2.015
OS 2.72 2.1
OS 2.72 2.14893996063
OC 2.720019980315 2.15 2.690000688976 2.150035629921 N
OC 2.72 2.15106003937 2.690000688976 2.149964370079 N
OS 2.72 2.16926003937
OC 2.720019980315 2.17 2.700004625984 2.170170177165 N
OS 2.720019980315 2.215
OE
SE
P 2.97771998 1.88693996 12 P 0 8 0;3=3,5=1
P 3.00995 1.87611004 12 P 0 8 0;3=3,5=1
P 2.875 2.035 15 P 0 8 0;1,3=14,5=1
P 2.999 2.05 36 P 0 8 0;0,3=0,5=0
P 2.79 2.164 32 P 0 8 0;0,3=0,5=0
P 2.7274 2.1935 31 P 0 8 0;0,3=20,5=0
P 2.845 2.168 38 P 0 8 0;0,3=8,5=0
P 3.002 1.945 39 P 0 8 0;0,3=12,5=0
P 2.999 2.005 36 P 0 8 0;0,3=0,5=0
S P 0
OB 2.928019980315 2.86 I
OS 3.21 2.86
OS 3.21 2.81
OS 3.2 2.8
OS 3.125 2.8
OS 3.02 2.695
OS 3.02 2.35175
OS 3.01 2.345
OS 2.995 2.33
OS 2.93256003937 2.33
OC 2.922 2.333019980315 2.9219875 2.313003543307 N
OS 2.898 2.333019980315
OC 2.88743996063 2.33 2.8980125 2.313003543307 N
OS 2.825 2.33
OS 2.81765 2.32265
OS 2.816230019685 2.324069980315
OC 2.802 2.330019980315 2.80198976378 2.310004330709 N
OS 2.778 2.330019980315
OC 2.757980019685 2.31 2.778 2.31 N
OS 2.757980019685 2.307980019685
OS 2.735 2.285
OS 2.715 2.285
OS 2.715 2.39
OS 2.82 2.495
OS 2.82 2.51993996063
OS 2.820080019685 2.52021003937
OC 2.825680019685 2.559430019685 2.68566742126 2.559411811024 N
OC 2.820080019685 2.59865 2.68566742126 2.559448228346 N
OS 2.82 2.598919980315
OS 2.82 2.675
OS 2.81 2.685
OS 2.81 2.835
OS 2.83098996063 2.85598996063
OC 2.843 2.851980019685 2.843008858268 2.871996948819 N
OS 2.867 2.851980019685
OC 2.8775 2.85496003937 2.866991633858 2.871997637795 N
OC 2.888 2.851980019685 2.888008366142 2.871997637795 N
OS 2.912 2.851980019685
OC 2.928019980315 2.86 2.912 2.871990059055 N
OE
SE
P 2.86066998 2.64043002 20 P 0 8 0;1,3=29,5=0
P 3.185 2.853 38 P 0 8 0;0,3=8,5=0
P 2.9715 2.352 44 P 0 8 0;0,3=17,5=0
P 2.91 2.341 32 P 0 8 0;0,3=0,5=0
P 2.7274 2.3065 31 P 0 8 0;0,3=20,5=0
P 2.85 2.343 43 P 0 8 0;0,3=12,5=0
P 2.96 2.847 43 P 0 8 0;0,3=12,5=0
P 3.035 2.847 43 P 0 8 0;0,3=12,5=0
P 3.11 2.847 43 P 0 8 0;0,3=12,5=0
P 2.855 2.844 32 P 0 8 0;0,3=0,5=0
P 2.9 2.844 32 P 0 8 0;0,3=0,5=0
P 2.79 2.338 32 P 0 8 0;0,3=0,5=0
L 2.15156998 0.29343002 2.15156998 0.13781004 10 P 0 
S P 0
OB 2.22256003937 0.625 I
OS 2.285 0.625
OS 2.285 0.535
OS 2.16 0.41
OS 2.16 0.295
OS 2.15 0.285
OS 2.08 0.285
OS 2.075 0.29
OS 2.075 0.42
OS 2.145 0.49
OS 2.145 0.51168996063
OC 2.145 0.56831003937 2.134993602362 0.54 N
OS 2.145 0.621980019685
OS 2.167 0.621980019685
OC 2.1775 0.62496003937 2.166991633858 0.641997637795 N
OC 2.188 0.621980019685 2.188008366142 0.641997637795 N
OS 2.212 0.621980019685
OC 2.22256003937 0.625 2.2119875 0.641996456693 N
OE
SE
L 2.1122 0.2938 2.1122 0.13781004 10 P 0 
P 2.155 0.614 32 P 0 8 0;0,3=0,5=0
P 2.2 0.614 32 P 0 8 0;0,3=0,5=0
P 2.26 0.623 38 P 0 8 0;0,3=8,5=0
L 2.141 0.304 2.15156998 0.29343002 10 P 0 
L 2.105 0.305 2.105 0.301 10 P 0 
L 2.105 0.301 2.1122 0.2938 10 P 0 
P 2.105 0.305 11 P 0 8 0;3=11,5=1
P 2.1122 0.13781004 35 P 0 8 0;0,3=30,5=0
P 2.15156998 0.13781004 35 P 0 8 0;0,3=30,5=0
P 2.235 0.5825 12 P 0 8 0;3=3,5=1
P 3.405 0.635 12 P 0 8 0;3=3,5=1
P 5.295 0.605 15 P 0 8 0;1,3=1,5=1
P 5.91 4.04 15 P 0 8 0;1,3=1,5=1
L 5.91 4.089 5.91 4.04 10 P 0 
P 5.91 4.089 32 P 0 8 0;0,3=0,5=0
P 2.135 0.54 12 P 0 8 0;3=3,5=1
P 5.215 0.6 15 P 0 8 0;1,3=1,5=1
L 6.025 4.089 6.025 4.04 10 P 0 
P 6.025 4.04 15 P 0 8 0;1,3=1,5=1
P 6.025 4.089 32 P 0 8 0;0,3=0,5=0
P 3.36 0.6106 12 P 0 8 0;3=3,5=1
L 1.41 3.795 1.41 3.836 10 P 0 
L 1.41 3.836 1.425 3.851 10 P 0 
P 0.96 2.41 12 P 0 8 0;3=3,5=1
P 0.68 2.355 12 P 0 8 0;3=3,5=1
P 2.38 3.45 12 P 0 8 0;3=3,5=1
P 1.41 3.795 12 P 0 8 0;3=3,5=1
P 3.445 3.613 12 P 0 8 0;3=3,5=1
P 3.365 3.613 15 P 0 8 0;1,3=1,5=1
P 3.25 3.63 12 P 0 8 0;3=3,5=1
P 3.325 3.613 12 P 0 8 0;3=3,5=1
P 3.405 3.613 12 P 0 8 0;3=3,5=1
P 3.48418002 3.613 12 P 0 8 0;3=3,5=1
P 3.645 4.135 12 P 0 8 0;3=3,5=1
L 3.581 4.13 3.586 4.135 10 P 0 
L 3.586 4.135 3.645 4.135 10 P 0 
P 1.425 3.851 36 P 0 8 0;0,3=0,5=0
P 3.581 4.13 36 P 0 8 0;0,3=0,5=0
S P 0
OB 3.622630019685 3.121 I
OS 3.692369980315 3.121
OS 3.697 3.116369980315
OS 3.697 3.005
OS 3.691 2.999
OS 3.602 2.999
OS 3.598 3.003
OS 3.598 3.096369980315
OS 3.622630019685 3.121
OE
SE
P 3.655 3.059 12 P 0 8 0;3=3,5=1
P 3.614 3.099 12 P 0 8 0;3=3,5=1
P 3.614 3.058 12 P 0 8 0;3=3,5=1
P 3.614 3.015 12 P 0 8 0;3=3,5=1
P 3.662 3.018 43 P 0 8 0;0,3=12,5=0
P 5.236 2.811 12 P 0 8 0;3=3,5=1
P 4.3305 2.914 12 P 0 8 0;3=31,5=1
P 4.3815 2.838 12 P 0 8 0;3=31,5=1
L 4.355 2.745 4.355 2.725 10 P 0 
L 4.355 2.725 4.325 2.695 10 P 0 
L 4.325 2.695 4.04 2.695 10 P 0 
L 4.04 2.695 4 2.655 10 P 0 
P 4.29 2.74 15 P 0 8 0;3=4,5=0
L 4.456 2.783 4.489 2.75 10 P 0 
L 4.489 2.75 4.55 2.75 10 P 0 
L 4.55 2.75 4.566 2.766 10 P 0 
L 4.566 2.766 4.566 2.795 10 P 0 
P 4.456 2.783 12 P 0 8 0;3=3,5=1
P 4.355 2.745 12 P 0 8 0;3=3,5=1
P 4.346 2.783 12 P 0 8 0;3=3,5=1
P 4.4 2.785 12 P 0 8 0;3=3,5=1
P 4 2.655 12 P 0 8 0;3=3,5=1
P 4.566 2.795 36 P 0 8 0;0,3=0,5=0
S P 0
OB 4.922 2.49 I
OS 5.03 2.49
OS 5.035 2.485
OS 5.035 2.401
OS 5.024 2.39
OS 4.921 2.39
OS 4.91706003937 2.39393996063
OS 4.91706003937 2.48506003937
OS 4.922 2.49
OE
SE
P 5.014 2.454 39 P 0 8 0;0,3=12,5=0
P 5.022 2.407 12 P 0 8 0;3=3,5=1
P 4.923 2.408 12 P 0 8 0;3=3,5=1
P 4.972 2.406 12 P 0 8 0;3=3,5=1
P 4.971 2.447 12 P 0 8 0;3=3,5=1
L 5.2871 2.275 5.389 2.275 10 P 0 
P 5.2871 2.275 12 P 0 8 0;3=3,5=1
P 5.389 2.275 36 P 0 8 0;0,3=0,5=0
P 5.62533002 1.02001004 12 P 0 8 0;3=3,5=1
P 5.65933002 1.02 12 P 0 8 0;3=3,5=1
P 3.804 0.816 11 P 0 8 0;3=11,5=1
L 3.77 0.811 3.77 0.863 10 P 0 
P 3.77 0.863 38 P 0 8 0;0,3=8,5=0
L 3.804 0.816 3.775 0.816 10 P 0 
L 3.775 0.816 3.77 0.811 10 P 0 
P 3.77 0.811 32 P 0 8 0;0,3=0,5=0
P 4.269 0.73 36 P 0 8 0;0,3=0,5=0
P 4.27 0.778 38 P 0 8 0;0,3=8,5=0
P 4.23 0.7295 12 P 0 8 0;3=3,5=1
L 4.27 0.778 4.269 0.777 10 P 0 
L 4.269 0.777 4.269 0.73 10 P 0 
L 4.269 0.73 4.2305 0.73 10 P 0 
L 4.2305 0.73 4.23 0.7295 10 P 0 
S P 0
OB 2.301630019685 0.73 I
OS 2.315 0.73
OS 2.325 0.72
OS 2.325 0.67
OS 2.32 0.665
OS 2.235 0.665
OS 2.235 0.72
OS 2.245 0.73
OS 2.268380019685 0.73
OC 2.285 0.724980019685 2.285 0.755002362205 N
OC 2.30113996063 0.72968996063 2.285000098425 0.754988877953 N
OS 2.301630019685 0.73
OE
SE
P 2.26 0.677 38 P 0 8 0;0,3=8,5=0
P 2.31 0.715 12 P 0 8 0;3=3,5=1
P 2.31 0.68 12 P 0 8 0;3=3,5=1
P 2.595 0.547 12 P 0 8 0;3=3,5=1
S P 0
OB 1.905 0.325 I
OS 1.885 0.305
OS 1.885 0.285
OS 1.88 0.28
OS 1.83 0.28
OS 1.824 0.286
OS 1.824 0.382
OS 1.833 0.391
OS 1.874 0.391
OS 1.905 0.36
OS 1.905 0.325
OE
SE
P 1.87598002 0.289 11 P 0 8 0;3=11,5=1
P 1.86 0.33 11 P 0 8 0;3=11,5=1
L 1.83661004 0.13781004 1.83661004 0.289 10 P 0 
P 1.83661004 0.13781004 35 P 0 8 0;0,3=30,5=0
L 1.87598002 0.13781004 1.87598002 0.289 10 P 0 
P 1.87598002 0.13781004 35 P 0 8 0;0,3=30,5=0
P 1.895 0.33 11 P 0 8 0;3=11,5=1
P 1.87598002 0.369 11 P 0 8 0;3=11,5=1
P 0.705 3.82 12 P 0 8 0;3=3,5=1
P 0.665 3.82 12 P 0 8 0;3=3,5=1
P 0.625 3.82 12 P 0 8 0;3=3,5=1
P 0.625 3.78 15 P 0 8 0;1,3=1,5=1
P 0.625 3.73 15 P 0 8 0;1,3=1,5=1
P 0.66 3.65 12 P 0 8 0;3=3,5=1
P 0.695 3.65 12 P 0 8 0;3=3,5=1
P 0.73 3.65 12 P 0 8 0;3=3,5=1
P 0.625 3.69 12 P 0 8 0;3=3,5=1
P 0.625 3.65 12 P 0 8 0;3=3,5=1
P 3.47 2.376 32 P 0 8 0;0,3=0,5=0
L 3.47 2.376 3.504 2.376 3 P 0 
L 3.504 2.376 3.51 2.37 3 P 0 
P 3.51 2.37 12 P 0 8 0;3=3,5=1
L 0.5505 3.0284 0.5505 3.0724 3 P 0 
L 0.5505 3.0724 0.5552 3.0771 3 P 0 
L 0.5552 3.0771 0.5866 3.0771 3 P 0 
L 0.5866 3.0771 0.5913 3.0724 3 P 0 
L 0.5913 3.0724 0.5913 3.0517 3 P 0 
L 0.5913 3.0517 0.618 3.025 3 P 0 
L 0.66 3.014 0.629 3.014 3 P 0 
L 0.629 3.014 0.618 3.025 3 P 0 
P 0.618 3.025 15 P 0 8 0;1,3=14,5=1
P 0.5505 3.0284 46 P 0 8 0;0,3=18,5=0
P 0.66 3.014 32 P 0 8 0;0,3=0,5=0
L 0.29 2.915 0.29 2.92 3 P 0 
L 0.29 2.92 0.3216 2.9516 3 P 0 
L 0.3216 2.9516 0.3695 2.9516 3 P 0 
L 0.29 2.871 0.29 2.915 3 P 0 
P 0.29 2.915 15 P 0 8 0;1,3=1,5=1
P 0.3695 2.9516 46 P 0 8 0;0,3=18,5=0
P 0.29 2.871 32 P 0 8 0;0,3=0,5=0
L 0.29 2.871 0.335 2.871 3 P 0 
P 0.335 2.871 32 P 0 8 0;0,3=0,5=0
L 0.28 2.965 0.285 2.965 3 P 0 
L 0.285 2.965 0.2972 2.9772 3 P 0 
L 0.2972 2.9772 0.3695 2.9772 3 P 0 
L 0.241 2.925 0.245 2.925 3 P 0 
L 0.245 2.925 0.28 2.96 3 P 0 
L 0.28 2.96 0.28 2.965 3 P 0 
P 0.28 2.965 15 P 0 8 0;1,3=1,5=1
L 0.241 2.925 0.241 2.875 3 P 0 
P 0.241 2.875 36 P 0 8 0;0,3=0,5=0
P 0.3695 2.9772 46 P 0 8 0;0,3=18,5=0
P 0.241 2.925 36 P 0 8 0;0,3=0,5=0
L 0.285 3.02 0.29 3.02 3 P 0 
L 0.29 3.02 0.3072 3.0028 3 P 0 
L 0.3072 3.0028 0.3695 3.0028 3 P 0 
L 0.241 3.025 0.27 3.025 3 P 0 
L 0.27 3.025 0.275 3.02 3 P 0 
L 0.275 3.02 0.285 3.02 3 P 0 
P 0.285 3.02 15 P 0 8 0;1,3=1,5=1
P 0.3695 3.0028 46 P 0 8 0;0,3=18,5=0
P 0.241 2.975 36 P 0 8 0;0,3=0,5=0
L 0.241 3.025 0.241 2.975 3 P 0 
P 0.241 3.025 36 P 0 8 0;0,3=0,5=0
L 3.026 3.35 2.978 3.35 3 P 0 
L 2.978 3.35 2.977 3.351 3 P 0 
P 2.977 3.351 15 P 0 8 0;1,3=5,5=1
P 3.026 3.35 36 P 0 8 0;0,3=0,5=0
L 3.026 3.35 3.026 3.305 3 P 0 
P 3.026 3.305 36 P 0 8 0;0,3=0,5=0
P 3.298 3.34 36 P 0 8 0;0,3=0,5=0
L 3.298 3.34 3.298 3.295 3 P 0 
L 3.36525 3.255 3.338 3.255 3 P 0 
L 3.338 3.255 3.298 3.295 3 P 0 
P 3.298 3.295 36 P 0 8 0;0,3=0,5=0
P 3.36525 3.255 15 P 0 8 0;1,3=5,5=1
P 3.36525 3.205 15 P 0 8 0;1,3=5,5=1
L 3.298 3.205 3.298 3.25 3 P 0 
P 3.298 3.25 36 P 0 8 0;0,3=0,5=0
L 3.298 3.205 3.36525 3.205 3 P 0 
P 3.298 3.205 36 P 0 8 0;0,3=0,5=0
P 1.8062 0.7789 15 P 0 8 0;1,3=10,5=1
L 1.8646 0.6442 1.8646 0.7205 3 P 0 
L 1.8646 0.7205 1.8062 0.7789 3 P 0 
P 1.8646 0.6442 32 P 0 8 0;0,3=0,5=0
P 3.073 0.613 15 P 0 8 0;1,3=10,5=1
P 2.54526998 0.339 11 P 0 8 0;3=11,5=1
P 2.527 0.44 15 P 0 8 0;1,3=5,5=1
L 5.73991004 4.27558002 5.75448996 4.261 3 P 0 
L 5.75448996 4.261 5.79 4.261 3 P 0 
P 5.79 4.261 32 P 0 8 0;0,3=0,5=0
P 5.73991004 4.27558002 15 P 0 8 0;1,3=1,5=1
L 5.38558002 4.27558002 5.40016004 4.261 3 P 0 
L 5.40016004 4.261 5.435 4.261 3 P 0 
P 5.435 4.261 32 P 0 8 0;0,3=0,5=0
P 5.38558002 4.27558002 15 P 0 8 0;1,3=1,5=1
L 5.50368996 4.27558002 5.51826998 4.261 3 P 0 
L 5.51826998 4.261 5.555 4.261 3 P 0 
P 5.555 4.261 32 P 0 8 0;0,3=0,5=0
P 5.50368996 4.27558002 15 P 0 8 0;1,3=1,5=1
L 5.6218 4.27558002 5.63638002 4.261 3 P 0 
L 5.63638002 4.261 5.67 4.261 3 P 0 
P 5.67 4.261 32 P 0 8 0;0,3=0,5=0
P 5.6218 4.27558002 15 P 0 8 0;1,3=1,5=1
L 5.875 1.9 5.875 1.94595 3 P 0 
L 5.875 1.94595 5.8797 1.95065 3 P 0 
L 5.8797 1.95065 5.91901998 1.95065 3 P 0 
P 5.875 1.9 15 P 0 8 0;1,3=1,5=1
P 3.865 3.65 12 P 0 8 0;3=3,5=1
P 5.91901998 1.95065 32 P 0 8 0;0,3=0,5=0
L 6.06901998 1.90865 6.06901998 1.86 3 P 0 
P 6.06901998 1.86 15 P 0 8 0;1,3=1,5=1
P 6.06901998 1.90865 32 P 0 8 0;0,3=0,5=0
P 3.81 3.65 12 P 0 8 0;3=3,5=1
L 5.97 1.999 5.96901998 1.99801998 3 P 0 
L 5.96901998 1.99801998 5.96901998 1.95065 3 P 0 
P 5.96901998 1.95065 32 P 0 8 0;0,3=0,5=0
P 5.97 1.999 15 P 0 8 0;1,3=10,5=1
P 4.62 2.245 12 P 0 8 0;3=3,5=1
P 5.801 3.667 12 P 0 8 0;3=3,5=1
P 3.8 2.045 12 P 0 8 0;3=3,5=1
P 1.275 2.905 12 P 0 8 0;3=3,5=1
P 5.061 2.806 12 P 0 8 0;3=3,5=1
L 3.87193002 1.46941998 3.87193002 1.46943002 10 P 0 
L 3.87193002 1.46943002 3.8916 1.4891 10 P 0 
L 4.38373996 1.94185 4.36418996 1.9223 8 P 0 
L 4.36418996 1.9223 4.32493996 1.9223 8 P 0 
L 4.32493996 1.9223 4.31006004 1.93718002 8 P 0 
S P 0
OB 3.575 1.272 I
OS 3.566 1.263
OS 3.446 1.263
OS 3.435 1.274
OS 3.435 1.33
OS 3.4395 1.3345
OS 3.5545 1.3345
OS 3.575 1.314
OS 3.575 1.272
OE
SE
S P 0
OB 3.70998996063 1.334980019685 I
OS 3.74371003937 1.334980019685
OC 3.758 1.328980019685 3.758 1.348997047244 N
OS 3.80601003937 1.328980019685
OS 3.81 1.325
OS 3.81 1.295
OS 3.79 1.275
OS 3.71 1.275
OS 3.705 1.28
OS 3.705 1.33
OS 3.70998996063 1.334980019685
OE
SE
S P 0
OB 3.033019980315 2.06 I
OS 3.115 2.06
OS 3.125 2.05
OS 3.125 1.925
OS 3.12 1.92
OS 3.05 1.92
OS 3.05 1.98
OS 3.033019980315 1.996980019685
OS 3.033019980315 2.017
OC 3.03003996063 2.0275 3.013002362205 2.016991633858 N
OC 3.033019980315 2.038 3.013002362205 2.038008366142 N
OS 3.033019980315 2.06
OE
SE
P 3.785 1.302 43 P 0 8 0;0,3=12,5=0
P 3.52 1.334 32 P 0 8 0;0,3=0,5=0
P 3.46 1.312 43 P 0 8 0;0,3=12,5=0
P 3.995 1.2 12 P 0 8 0;3=3,5=1
P 4.07 1.2 12 P 0 8 0;3=3,5=1
P 4.0805 1.16098996 11 P 0 8 0;3=11,5=1
P 4.092 1.005 11 P 0 8 0;3=11,5=1
P 4.135 0.885 12 P 0 8 0;3=3,5=1
P 4.13621998 0.75 11 P 0 8 0;3=11,5=1
P 4.13401998 0.54196998 11 P 0 8 0;3=11,5=1
P 4.09401998 0.54196998 11 P 0 8 0;3=11,5=1
P 4.05401998 0.54196998 11 P 0 8 0;3=11,5=1
P 4.01401998 0.54196998 11 P 0 8 0;3=11,5=1
P 2.985 1.845 12 P 0 8 0;3=3,5=1
P 2.845 1.907 11 P 0 8 0;3=11,5=1
P 2.845 1.811 11 P 0 8 0;3=11,5=1
P 2.822 1.79121004 12 P 0 8 0;3=3,5=1
P 2.71 1.845 12 P 0 8 0;3=3,5=1
P 2.2 0.69 12 P 0 8 0;3=3,5=1
L 2.2 0.656 2.2 0.69 10 P 0 
P 2.2 0.656 32 P 0 8 0;0,3=0,5=0
P 2.15 0.69 12 P 0 8 0;3=3,5=1
L 2.155 0.656 2.155 0.685 10 P 0 
L 2.155 0.685 2.15 0.69 10 P 0 
P 2.155 0.656 32 P 0 8 0;0,3=0,5=0
P 1.9216 0.7784 12 P 0 8 0;3=3,5=1
P 2.0195 0.2905 11 P 0 8 0;3=11,5=1
P 1.91535 0.289 11 P 0 8 0;3=11,5=1
L 1.91535 0.13781004 1.91535 0.289 10 P 0 
P 1.91535 0.13781004 35 P 0 8 0;0,3=30,5=0
P 1.78196004 0.50601004 11 P 0 8 0;3=11,5=1
P 1.80341004 0.47225 11 P 0 8 0;3=11,5=1
P 1.63543002 0.52158996 11 P 0 8 0;3=11,5=1
P 3.65101004 1.85158996 11 P 0 8 0;3=11,5=1
P 3.45301004 1.86698996 11 P 0 8 0;3=11,5=1
P 3.473 1.79 12 P 0 8 0;3=3,5=1
L 3.473 1.79 3.474 1.789 10 P 0 
L 3.474 1.789 3.505 1.789 10 P 0 
P 3.505 1.789 32 P 0 8 0;0,3=0,5=0
P 3.1951 1.90298996 11 P 0 8 0;3=11,5=1
P 3.2911 1.90298996 11 P 0 8 0;3=11,5=1
L 2.958 0.289 2.93896998 0.26996998 10 P 0 
L 2.93896998 0.26996998 2.93896998 0.13781004 10 P 0 
P 2.93896998 0.13781004 35 P 0 8 0;0,3=30,5=0
P 2.958 0.289 11 P 0 8 0;3=11,5=1
L 2.88056998 0.289 2.8996 0.26996998 10 P 0 
L 2.8996 0.26996998 2.8996 0.13781004 10 P 0 
P 2.8996 0.13781004 35 P 0 8 0;0,3=30,5=0
P 2.88056998 0.289 11 P 0 8 0;3=11,5=1
P 2.95835 0.321 11 P 0 8 0;3=11,5=1
P 2.80051998 0.289 11 P 0 8 0;3=11,5=1
L 2.80051998 0.289 2.78148996 0.26996998 10 P 0 
L 2.78148996 0.26996998 2.78148996 0.13781004 10 P 0 
P 2.78148996 0.13781004 35 P 0 8 0;0,3=30,5=0
P 2.80086998 0.321 11 P 0 8 0;3=11,5=1
P 2.63506998 0.763 11 P 0 8 0;3=11,5=1
P 2.78655 0.763 11 P 0 8 0;3=11,5=1
P 2.73106998 0.763 11 P 0 8 0;3=11,5=1
P 2.7233 0.54871004 12 P 0 8 0;3=3,5=1
P 2.64338996 0.417 11 P 0 8 0;3=11,5=1
P 2.72308996 0.289 11 P 0 8 0;3=11,5=1
L 2.72308996 0.289 2.74211998 0.26996998 10 P 0 
L 2.74211998 0.26996998 2.74211998 0.13781004 10 P 0 
P 2.74211998 0.13781004 35 P 0 8 0;0,3=30,5=0
P 2.64303996 0.289 11 P 0 8 0;3=11,5=1
L 2.64303996 0.289 2.62401004 0.26996998 10 P 0 
L 2.62401004 0.26996998 2.62401004 0.13781004 10 P 0 
P 2.62401004 0.13781004 35 P 0 8 0;0,3=30,5=0
P 2.64338996 0.321 11 P 0 8 0;3=11,5=1
P 2.53421998 0.763 11 P 0 8 0;3=11,5=1
P 2.595 0.701 12 P 0 8 0;3=3,5=1
L 2.44618996 0.289 2.42716004 0.26996998 10 P 0 
L 2.42716004 0.26996998 2.42716004 0.13781004 10 P 0 
P 2.42716004 0.13781004 35 P 0 8 0;0,3=30,5=0
P 2.44618996 0.289 11 P 0 8 0;3=11,5=1
P 2.54526998 0.289 11 P 0 8 0;3=11,5=1
L 2.54526998 0.13781004 2.54526998 0.289 10 P 0 
P 2.54526998 0.13781004 35 P 0 8 0;0,3=30,5=0
P 2.43821998 0.763 11 P 0 8 0;3=11,5=1
P 2.40508002 0.667 11 P 0 8 0;3=11,5=1
P 2.40508002 0.763 11 P 0 8 0;3=11,5=1
P 2.327 0.291 11 P 0 8 0;3=11,5=1
L 2.30905 0.13781004 2.30905 0.27305 10 P 0 
L 2.30905 0.27305 2.327 0.291 10 P 0 
P 2.30905 0.13781004 35 P 0 8 0;0,3=30,5=0
P 3.56 1.305 12 P 0 8 0;3=3,5=1
P 3.535 1.305 12 P 0 8 0;3=3,5=1
P 3.51 1.305 12 P 0 8 0;3=3,5=1
P 3.54 1.28 12 P 0 8 0;3=3,5=1
P 3.57863996 1.04706998 11 P 0 8 0;3=11,5=1
P 3.593 0.92 11 P 0 8 0;3=11,5=1
P 3.65401998 0.54196998 11 P 0 8 0;3=11,5=1
P 3.61401998 0.54196998 11 P 0 8 0;3=11,5=1
P 3.57401998 0.54196998 11 P 0 8 0;3=11,5=1
P 3.53401998 0.54196998 11 P 0 8 0;3=11,5=1
P 3.49401998 0.54196998 11 P 0 8 0;3=11,5=1
P 3.375 1.226 11 P 0 8 0;3=11,5=1
P 3.375 1.13 11 P 0 8 0;3=11,5=1
P 3.48263996 1.04706998 11 P 0 8 0;3=11,5=1
P 3.48198996 1.085 11 P 0 8 0;3=11,5=1
P 3.38598996 1.085 11 P 0 8 0;3=11,5=1
P 3.33401998 0.54196998 11 P 0 8 0;3=11,5=1
P 3.45401998 0.54196998 11 P 0 8 0;3=11,5=1
P 3.41401998 0.54196998 11 P 0 8 0;3=11,5=1
P 3.37401998 0.54196998 11 P 0 8 0;3=11,5=1
P 3.17025 0.82975 11 P 0 8 0;3=11,5=1
P 3.17401998 0.54196998 11 P 0 8 0;3=11,5=1
P 3.21401998 0.54196998 11 P 0 8 0;3=11,5=1
P 3.25401998 0.54196998 11 P 0 8 0;3=11,5=1
P 3.29401998 0.54196998 11 P 0 8 0;3=11,5=1
P 3.10236998 0.89763002 11 P 0 8 0;3=11,5=1
P 3.035 0.694 12 P 0 8 0;3=3,5=1
P 2.98726004 0.49471004 11 P 0 8 0;3=11,5=1
P 2.98726004 0.43528996 11 P 0 8 0;3=11,5=1
P 3.07708002 0.289 11 P 0 8 0;3=11,5=1
L 3.05708002 0.13781004 3.05708002 0.269 10 P 0 
L 3.05708002 0.269 3.07708002 0.289 10 P 0 
P 3.05708002 0.13781004 35 P 0 8 0;0,3=30,5=0
P 2.88255 0.763 11 P 0 8 0;3=11,5=1
P 2.95835 0.417 11 P 0 8 0;3=11,5=1
P 2.80086998 0.417 11 P 0 8 0;3=11,5=1
P 3.9845 1.16098996 11 P 0 8 0;3=11,5=1
P 3.9 1.005 11 P 0 8 0;3=11,5=1
P 3.964 1.005 15 P 0 8 0;1,3=10,5=1
P 3.97401998 0.54196998 11 P 0 8 0;3=11,5=1
P 3.93401998 0.54196998 11 P 0 8 0;3=11,5=1
P 3.89401998 0.54196998 11 P 0 8 0;3=11,5=1
P 3.85401998 0.54196998 11 P 0 8 0;3=11,5=1
P 3.798 1.771 12 P 0 8 0;3=3,5=1
P 3.647 1.694 12 P 0 8 0;3=3,5=1
P 3.676 1.693 12 P 0 8 0;3=3,5=1
P 3.718 1.32 12 P 0 8 0;3=3,5=1
P 3.743 1.32 12 P 0 8 0;3=3,5=1
P 3.718 1.29 12 P 0 8 0;3=3,5=1
P 3.743 1.29 12 P 0 8 0;3=3,5=1
P 3.67 1.26 12 P 0 8 0;3=3,5=1
P 3.84 1.095 12 P 0 8 0;3=3,5=1
P 3.84 1.0298 12 P 0 8 0;3=3,5=1
L 3.84 1.0298 3.8282 1.0298 10 P 0 
L 3.8282 1.0298 3.798 1.06 10 P 0 
L 3.84 1.095 3.833 1.095 10 P 0 
L 3.833 1.095 3.798 1.06 10 P 0 
P 3.798 1.06 39 P 0 8 0;0,3=12,5=0
P 3.76838002 1.0023 12 P 0 8 0;3=3,5=1
P 3.735 0.94 11 P 0 8 0;3=11,5=1
P 3.689 0.92 11 P 0 8 0;3=11,5=1
P 3.805 0.774 11 P 0 8 0;3=11,5=1
L 3.77 0.769 3.775 0.774 10 P 0 
L 3.775 0.774 3.805 0.774 10 P 0 
P 3.77 0.769 32 P 0 8 0;0,3=0,5=0
P 3.735 0.78 11 P 0 8 0;3=11,5=1
P 3.795 0.725 15 P 0 8 0;1,3=10,5=1
P 3.81401998 0.54196998 11 P 0 8 0;3=11,5=1
P 3.77401998 0.54196998 11 P 0 8 0;3=11,5=1
P 3.73401998 0.54196998 11 P 0 8 0;3=11,5=1
P 3.69401998 0.54196998 11 P 0 8 0;3=11,5=1
P 3.551 1.694 12 P 0 8 0;3=3,5=1
P 3.576 1.694 12 P 0 8 0;3=3,5=1
P 3.526 1.694 12 P 0 8 0;3=3,5=1
P 3.501 1.694 12 P 0 8 0;3=3,5=1
P 3.636 1.766 12 P 0 8 0;3=3,5=1
L 4.02941998 1.43005 4.00975 1.44971998 10 P 0 
L 4.00975 1.44971998 4.00973002 1.44971998 10 P 0 
P 4.00973002 1.44971998 14 P 0 8 0;0,3=19,5=0
P 4.0491 1.41036004 14 P 0 8 0;0,3=19,5=0
L 4.0491 1.41036004 4.0491 1.41036998 10 P 0 
L 4.0491 1.41036998 4.02941998 1.43005 10 P 0 
L 4.10816004 1.78436998 4.10816004 1.76016004 10 P 0 
L 4.10816004 1.76016004 4.098 1.75 10 P 0 
L 3.99005 1.78436998 4.00971998 1.80403996 10 P 0 
L 4.00971998 1.80403996 4.00971998 1.80406004 10 P 0 
P 4.00971998 1.80406004 14 P 0 8 0;0,3=19,5=0
L 4.14753002 1.6269 4.12786004 1.64656998 10 P 0 
L 4.12786004 1.64656998 4.12783996 1.64656998 10 P 0 
P 4.12783996 1.64656998 14 P 0 8 0;0,3=19,5=0
L 4.10816004 1.54816004 4.12783002 1.52848996 10 P 0 
L 4.12783002 1.52848996 4.12783002 1.52846998 10 P 0 
P 4.12785 1.56783996 14 P 0 8 0;0,3=19,5=0
L 4.12785 1.56783996 4.12783996 1.56783996 10 P 0 
L 4.12783996 1.56783996 4.10816004 1.54816004 10 P 0 
L 4.10816004 1.46941998 4.12783002 1.48908996 10 P 0 
L 4.12783002 1.48908996 4.12783002 1.4891 10 P 0 
L 3.99005 1.58753002 4.00971998 1.6072 10 P 0 
L 4.00971998 1.6072 4.00973002 1.6072 10 P 0 
P 4.00973002 1.6072 14 P 0 8 0;0,3=19,5=0
L 4.02941998 1.6269 4.0491 1.64658002 10 P 0 
L 4.0491 1.64658002 4.0491 1.64658996 10 P 0 
P 4.0491 1.64658996 14 P 0 8 0;0,3=19,5=0
P 4.00973002 1.56785 14 P 0 8 0;0,3=19,5=0
L 4.00973002 1.56785 3.99005 1.58753002 10 P 0 
P 4.12785 1.60721004 14 P 0 8 0;0,3=19,5=0
L 4.12785 1.60721004 4.10816004 1.6269 10 P 0 
P 3.97036004 1.84343002 14 P 0 8 0;0,3=19,5=0
L 3.97036004 1.84343002 3.99005 1.82373996 10 P 0 
L 3.9113 1.78436998 3.93096998 1.7647 10 P 0 
L 3.93096998 1.7647 3.93098002 1.7647 10 P 0 
P 3.93098002 1.7647 14 P 0 8 0;0,3=19,5=0
L 3.87193002 1.78436998 3.855 1.76743996 10 P 0 
L 3.855 1.76743996 3.855 1.7557 10 P 0 
L 3.855 1.7557 3.8443 1.745 10 P 0 
P 3.8443 1.745 36 P 0 8 0;0,3=0,5=0
P 3.97036004 1.64658002 14 P 0 8 0;0,3=19,5=0
L 3.97036004 1.64658002 3.95066998 1.66626998 10 P 0 
L 3.95066998 1.50878996 3.97035 1.52846998 10 P 0 
L 3.97035 1.52846998 3.97036004 1.52846998 10 P 0 
P 3.97036004 1.52846998 14 P 0 8 0;0,3=19,5=0
P 3.97035 1.48911004 14 P 0 8 0;0,3=19,5=0
L 3.97035 1.48911004 3.95066998 1.50878996 10 P 0 
P 3.8916 1.4891 14 P 0 8 0;0,3=19,5=0
L 3.87193002 1.3513 3.87628996 1.34693996 10 P 0 
L 3.87628996 1.34693996 3.87628996 1.29361004 10 P 0 
P 3.87628996 1.29361004 36 P 0 8 0;0,3=0,5=0
P 2.86066998 1.04043002 20 P 0 8 0;1,3=29,5=0
L 4.16721004 1.56783002 4.1672 1.56783002 10 P 0 
L 4.1672 1.56783002 4.14753002 1.54816004 10 P 0 
P 4.6053 1.22166998 11 P 0 8 0;3=11,5=1
P 1.041 3.825 11 P 0 8 0;3=11,5=1
P 1.137 3.825 11 P 0 8 0;3=11,5=1
S P 0
OB 5.543 0.909 I
OS 5.637 0.909
OS 5.652 0.894
OS 5.652 0.824
OS 5.653 0.823
OS 5.653 0.771719980315
OC 5.653 0.748280019685 5.685989566929 0.76 N
OS 5.653 0.703
OS 5.635 0.685
OS 5.603 0.685
OS 5.593 0.695
OS 5.593 0.775
OS 5.583 0.785
OS 5.538 0.785
OS 5.53 0.793
OS 5.53 0.896
OS 5.543 0.909
OE
SE
S P 0
OB 4.069 2.785 I
OS 4.069 2.942
OS 4.096 2.969
OS 4.147 2.969
OS 4.154 2.962
OS 4.154 2.781
OS 4.147 2.774
OS 4.08 2.774
OS 4.069 2.785
OE
SE
S P 0
OB 5.23 3.565 I
OS 5.384 3.565
OS 5.485 3.464
OS 5.485 3.231019980315
OS 5.484980019685 3.231019980315
OS 5.484980019685 3.184980019685
OS 5.475 3.175
OS 5.245 3.175
OS 5.224 3.196
OS 5.224 3.214
OS 5.222 3.216
OS 5.222 3.557
OS 5.23 3.565
OE
SE
S P 0
OB 5.071 2.513 I
OS 5.207 2.513
OS 5.213 2.507
OS 5.213 2.499230019685
OS 5.21156003937 2.49881003937
OC 5.21156003937 2.44118996063 5.220001181102 2.47 N
OS 5.213 2.440769980315
OS 5.213 2.401
OS 5.205 2.393
OS 5.069 2.393
OS 5.06 2.402
OS 5.06 2.502
OS 5.071 2.513
OE
SE
S P 0
OB 5.644 2.099 I
OS 5.747 2.099
OS 5.7585 2.0875
OS 5.7585 2.0395
OS 5.751019980315 2.032019980315
OS 5.734 2.032019980315
OC 5.72888996063 2.031119980315 5.734010728346 2.017001870079 N
OS 5.72856003937 2.031
OS 5.7203 2.031
OC 5.706 2.037019980315 5.705990748031 2.017003838583 N
OS 5.668 2.037019980315
OC 5.6537 2.031 5.668009251969 2.017003838583 N
OS 5.643 2.031
OS 5.634 2.04
OS 5.634 2.089
OS 5.644 2.099
OE
SE
S P 0
OB 3.608 2.971 I
OS 3.717 2.971
OS 3.721 2.967
OS 3.721 2.855
OS 3.712 2.846
OS 3.604 2.846
OS 3.599 2.851
OS 3.599 2.935369980315
OC 3.605019980315 2.955 3.570005314961 2.954999901575 N
OC 3.60353996063 2.96506003937 3.570001870079 2.954987106299 N
OS 3.6032 2.9662
OS 3.608 2.971
OE
SE
S P 0
OB 2.845 2.925 I
OS 2.895 2.975
OS 3.125 2.975
OS 3.135 2.965
OS 3.135 2.895
OS 2.93 2.895
OS 2.92 2.885
OS 2.845 2.885
OS 2.845 2.925
OE
SE
S P 0
OB 3.66 2.255 I
OS 3.715 2.255
OS 3.73 2.24
OS 3.73 2.115
OS 3.725 2.11
OS 3.64 2.11
OS 3.635 2.115
OS 3.635 2.139980019685
OS 3.635019980315 2.139980019685
OS 3.635019980315 2.140019980315
OS 3.645 2.15
OS 3.645 2.185
OS 3.66 2.2
OS 3.66 2.255
OE
SE
S P 0
OB 4.53 3.98 I
OS 4.62 3.98
OS 4.624980019685 3.975019980315
OS 4.624980019685 3.96253996063
OC 4.621980019685 3.952 4.641995275591 3.952 N
OS 4.621980019685 3.928
OC 4.62496003937 3.9175 4.641997637795 3.928008366142 N
OC 4.621980019685 3.907 4.641997637795 3.906991633858 N
OS 4.621980019685 3.885
OS 4.52 3.885
OS 4.515 3.89
OS 4.515 3.965
OS 4.53 3.98
OE
SE
S P 0
OB 5.05755 3.864980019685 I
OS 5.06245 3.864980019685
OS 5.06291003937 3.86471003937
OC 5.073 3.861980019685 5.073000098425 3.881991141732 N
OS 5.097 3.861980019685
OC 5.097169980315 3.86198996063 5.095918208661 3.881935925197 N
OS 5.09801003937 3.86198996063
OS 5.1 3.86
OS 5.1 3.74
OS 5.095 3.735
OS 5.04 3.735
OS 5.025 3.75
OS 5.025 3.861980019685
OS 5.047 3.861980019685
OC 5.05708996063 3.86471003937 5.046999901575 3.881991141732 N
OS 5.05755 3.864980019685
OE
SE
S P 0
OB 5.41256003937 1.615 I
OS 5.45 1.615
OS 5.455 1.61
OS 5.455 1.58
OS 5.45 1.575
OS 5.385 1.575
OS 5.38 1.58
OS 5.38 1.611980019685
OS 5.402 1.611980019685
OC 5.41256003937 1.615 5.4019875 1.631996456693 N
OE
SE
S P 0
OB 5.375 1.915 I
OS 5.38 1.92
OS 5.44 1.92
OS 5.445 1.915
OS 5.445 1.845
OS 5.44 1.84
OS 5.375 1.84
OS 5.375 1.915
OE
SE
P 6.56038996 1.41205 11 P 0 8 0;3=11,5=1
P 6.56038996 1.37205 11 P 0 8 0;3=11,5=1
P 6.56038996 1.33205 11 P 0 8 0;3=11,5=1
P 6.56038996 1.29205 11 P 0 8 0;3=11,5=1
P 6.56038996 1.25205 11 P 0 8 0;3=11,5=1
P 6.56038996 1.21205 11 P 0 8 0;3=11,5=1
P 6.56038996 1.17205 11 P 0 8 0;3=11,5=1
P 6.56038996 1.13205 11 P 0 8 0;3=11,5=1
P 6.56038996 1.09205 11 P 0 8 0;3=11,5=1
P 5.9645 2.1035 12 P 0 8 0;3=31,5=1
P 6.0155 2.0845 12 P 0 8 0;3=31,5=1
P 0.22703996 0.43635 13 P 0 8 0;3=32,5=0
P 0.19878002 0.36811004 13 P 0 8 0;3=32,5=0
P 0.22703996 0.29986998 13 P 0 8 0;3=32,5=0
P 0.29528002 0.27161004 13 P 0 8 0;3=32,5=0
P 0.36351998 0.29986998 13 P 0 8 0;3=32,5=0
P 0.39178002 0.36811004 13 P 0 8 0;3=32,5=0
P 0.36351998 0.43635 13 P 0 8 0;3=32,5=0
P 0.29528002 0.46461004 13 P 0 8 0;3=32,5=0
P 6.33215 0.72178002 13 P 0 8 0;3=32,5=0
P 6.30388996 0.65353996 13 P 0 8 0;3=32,5=0
P 6.33215 0.5853 13 P 0 8 0;3=32,5=0
P 6.40038996 0.55703996 13 P 0 8 0;3=32,5=0
P 6.46863002 0.5853 13 P 0 8 0;3=32,5=0
P 6.49688996 0.65353996 13 P 0 8 0;3=32,5=0
P 6.46863002 0.72178002 13 P 0 8 0;3=32,5=0
P 6.40038996 0.75003996 13 P 0 8 0;3=32,5=0
P 6.33215 4.24658996 13 P 0 8 0;3=32,5=0
P 6.30388996 4.17835 13 P 0 8 0;3=32,5=0
P 6.33215 4.11011004 13 P 0 8 0;3=32,5=0
P 6.40038996 4.08185 13 P 0 8 0;3=32,5=0
P 6.46863002 4.11011004 13 P 0 8 0;3=32,5=0
P 6.49688996 4.17835 13 P 0 8 0;3=32,5=0
P 6.46863002 4.24658996 13 P 0 8 0;3=32,5=0
P 6.40038996 4.27485 13 P 0 8 0;3=32,5=0
P 5.92 1.36 15 P 0 8 0;3=1,5=1
P 6.22 1.36 12 P 0 8 0;3=3,5=1
L 0.99 3.5 0.99 3.559 10 P 0 
L 0.99 3.559 0.995 3.564 10 P 0 
P 5.99 0.925 12 P 0 8 0;3=3,5=1
P 4.24 3.983 32 P 0 8 0;0,3=0,5=0
L 4.24 3.983 4.24 3.991 10 P 0 
L 4.24 3.991 4.1915 4.0395 10 P 0 
P 1.265 3.606 32 P 0 8 0;0,3=0,5=0
L 1.265 3.606 1.265 3.625 10 P 0 
L 1.265 3.625 1.29 3.65 10 P 0 
L 5.762 3.857 5.803 3.857 10 P 0 
P 5.803 3.857 12 P 0 8 0;3=3,5=1
P 5.465 3.441 39 P 0 8 0;0,3=12,5=0
P 5.465 3.288 39 P 0 8 0;0,3=12,5=0
P 5.465 3.364 39 P 0 8 0;0,3=12,5=0
P 5.461 3.206 39 P 0 8 0;0,3=12,5=0
P 1.355 3.905 12 P 0 8 0;3=3,5=1
P 1.21168996 3.96891998 12 P 0 8 0;3=3,5=1
P 0.42 2.368 12 P 0 8 0;3=3,5=1
P 1.885 2.981 32 P 0 8 0;0,3=0,5=0
L 1.885 2.981 1.885 3 10 P 0 
L 1.885 3 1.9 3.015 10 P 0 
P 5.325 2.725 12 P 0 8 0;3=3,5=1
L 5.278 2.611 5.278 2.6013 10 P 0 
L 5.278 2.6013 5.3035 2.5758 10 P 0 
L 5.3035 2.5758 5.3035 2.5748 10 P 0 
P 1.6985 2.9895 12 P 0 8 0;3=31,5=1
P 1.6615 3.0405 12 P 0 8 0;3=31,5=1
P 5.6435 0.6535 12 P 0 8 0;3=31,5=1
P 5.1265 2.6815 12 P 0 8 0;3=31,5=1
P 5.0895 2.7325 12 P 0 8 0;3=31,5=1
P 4.1915 4.0395 12 P 0 8 0;3=31,5=1
P 4.0965 3.9445 12 P 0 8 0;3=31,5=1
P 4.1235 3.9715 12 P 0 8 0;3=31,5=1
P 4.1645 3.9715 12 P 0 8 0;3=31,5=1
P 4.1645 4.0125 12 P 0 8 0;3=31,5=1
P 4.1235 4.0125 12 P 0 8 0;3=31,5=1
P 4.0965 4.0395 12 P 0 8 0;3=31,5=1
P 4.1915 3.9445 12 P 0 8 0;3=31,5=1
P 4.5 4.07 12 P 0 8 0;3=3,5=1
P 4.31 4.16 12 P 0 8 0;3=3,5=1
P 1.41 2.985 12 P 0 8 0;3=3,5=1
P 1.479 3 36 P 0 8 0;0,3=0,5=0
L 1.479 3 1.479 2.994 10 P 0 
L 1.479 2.994 1.45 2.965 10 P 0 
P 1.45 2.965 12 P 0 8 0;3=3,5=1
L 2.173 2.895 2.173 2.931 10 P 0 
L 2.083 2.895 2.083 2.931 10 P 0 
P 1.51 3.242 12 P 0 8 0;3=3,5=1
P 1.89 3.26 12 P 0 8 0;3=3,5=1
P 1.895 3.19 12 P 0 8 0;3=3,5=1
P 1.9 3.055 12 P 0 8 0;3=3,5=1
P 1.9 3.015 12 P 0 8 0;3=3,5=1
P 1.65 2.94 12 P 0 8 0;3=3,5=1
P 1.685 2.94 12 P 0 8 0;3=3,5=1
P 4.7184 2.07965 14 P 0 8 0;0,3=19,5=0
L 4.7184 2.07965 4.7184 2.07963002 10 P 0 
L 4.7184 2.07963002 4.73806998 2.05996004 10 P 0 
P 4.71838996 2.1584 14 P 0 8 0;0,3=19,5=0
L 4.71838996 2.1584 4.71836998 2.1584 10 P 0 
L 4.71836998 2.1584 4.6987 2.17806998 10 P 0 
P 4.681 1.755 36 P 0 8 0;0,3=0,5=0
L 4.681 1.755 4.681 1.76666998 10 P 0 
L 4.681 1.76666998 4.6987 1.78436998 10 P 0 
P 5.17 2.125 12 P 0 8 0;3=3,5=1
P 4.71838996 1.68595 14 P 0 8 0;0,3=19,5=0
L 4.71838996 1.68595 4.73806998 1.66626998 10 P 0 
P 4.67901998 1.84343002 14 P 0 8 0;0,3=19,5=0
L 4.67901998 1.84343002 4.67901998 1.80406998 8 P 0 
L 4.67901998 1.80406998 4.67903002 1.80406004 8 P 0 
P 4.56091004 1.8828 14 P 0 8 0;0,3=19,5=0
L 4.56091004 1.8828 4.54121998 1.86311004 10 P 0 
P 4.96 1.79258002 12 P 0 8 0;3=3,5=1
P 4.59 3.26 12 P 0 8 0;3=3,5=1
P 2.866 1.987 11 P 0 8 0;3=11,5=1
P 2.77 1.987 11 P 0 8 0;3=11,5=1
L 4.44 2.26 4.45681004 2.24318996 10 P 0 
L 4.45681004 2.24318996 4.45681004 2.22196004 10 P 0 
L 4.45681004 2.22196004 4.45485 2.22 10 P 0 
L 0.575 2.89 0.5505 2.9145 10 P 0 
L 0.5505 2.9145 0.5505 2.9516 10 P 0 
L 4.44 2.461 4.44 2.5 10 P 0 
P 4.5093 1.22166998 11 P 0 8 0;3=11,5=1
L 0.199 3.025 0.16 3.025 10 P 0 
L 0.199 3.075 0.16 3.075 10 P 0 
P 0.04 2.85618996 11 P 0 8 0;3=11,5=1
P 0.04 2.81618996 11 P 0 8 0;3=11,5=1
P 0.04 3.13618996 11 P 0 8 0;3=11,5=1
P 0.04 3.09618996 11 P 0 8 0;3=11,5=1
P 0.04 3.05618996 11 P 0 8 0;3=11,5=1
P 0.04 3.01618996 11 P 0 8 0;3=11,5=1
L 4.62 2.461 4.62 2.5 10 P 0 
L 1.035 3.094 1.035 3.065 10 P 0 
L 1.035 3.065 1.045 3.055 10 P 0 
P 3.49 3.03 12 P 0 8 0;3=3,5=1
P 3.555 3.065 12 P 0 8 0;3=3,5=1
P 3.695 2.675 12 P 0 8 0;3=3,5=1
P 3.725 2.32 12 P 0 8 0;3=3,5=1
L 3.506 3.325 3.55 3.325 9 P 0 
L 3.98 3.471 3.98 3.52 10 P 0 
L 1.376 3.5 1.42 3.5 10 P 0 
L 1.196 3.475 1.235 3.475 10 P 0 
L 0.698 0.911 0.66 0.911 10 P 0 
L 4.635 0.865 4.644 0.865 10 P 0 
L 4.644 0.865 4.694 0.915 10 P 0 
P 0.945 1.05 12 P 0 8 0;3=3,5=1
P 4.635 0.865 12 P 0 8 0;3=3,5=1
P 4.694 0.915 36 P 0 8 0;0,3=0,5=0
L 1.2 3.68 1.19 3.68 10 P 0 
L 1.19 3.68 1.17 3.66 10 P 0 
L 1.17 3.66 1.17 3.611 10 P 0 
L 1.17 3.611 1.175 3.606 10 P 0 
L 1.22 3.606 1.215 3.611 10 P 0 
L 1.215 3.611 1.215 3.63 10 P 0 
L 1.215 3.63 1.2 3.645 10 P 0 
P 0.866 1.413 12 P 0 8 0;3=3,5=1
L 1.085 3.606 1.085 3.6161 10 P 0 
L 1.085 3.6161 1.0725 3.6286 10 P 0 
L 1.0725 3.6286 1.0725 3.6325 10 P 0 
L 1.0725 3.6325 1.065 3.64 10 P 0 
L 1.13 3.606 1.13 3.615 10 P 0 
L 1.13 3.615 1.105 3.64 10 P 0 
L 1.105 3.64 1.1 3.64 10 P 0 
P 2.885 3.17 12 P 0 8 0;3=3,5=1
P 0.83 4.17 12 P 0 8 0;3=3,5=1
P 0.455 1.26 12 P 0 8 0;3=3,5=1
P 0.175 0.91 12 P 0 8 0;3=3,5=1
P 0.17 2.045 12 P 0 8 0;3=3,5=1
P 0.455 1.61 12 P 0 8 0;3=3,5=1
P 1.32 3.755 12 P 0 8 0;3=3,5=1
P 1.25095 3.06095 12 P 0 8 0;3=3,5=1
P 0.95593002 3.33346998 12 P 0 8 0;3=3,5=1
P 0.575 2.89 15 P 0 8 0;1,3=1,5=1
P 0.5505 2.9516 46 P 0 8 0;0,3=18,5=0
P 0.16 3.025 12 P 0 8 0;3=3,5=1
P 0.199 3.025 36 P 0 8 0;0,3=0,5=0
P 0.16 3.075 12 P 0 8 0;3=3,5=1
P 0.199 3.075 36 P 0 8 0;0,3=0,5=0
P 0.7 3.384 32 P 0 8 0;0,3=0,5=0
L 0.7 3.384 0.7 3.37 10 P 0 
L 0.7 3.37 0.72 3.35 10 P 0 
P 0.72 3.35 12 P 0 8 0;3=3,5=1
P 0.635 3.596 12 P 0 8 0;3=3,5=1
P 0.671 3.575 11 P 0 8 0;3=11,5=1
P 0.767 3.575 11 P 0 8 0;3=11,5=1
P 1.4213 3.2563 12 P 0 8 0;3=3,5=1
P 4.472 3.475 12 P 0 8 0;3=3,5=1
L 0.677 0.615 0.677 0.65 11 P 0 
P 5.97703002 1.87 12 P 0 8 0;3=3,5=1
P 0.606 1.612 12 P 0 8 0;3=3,5=1
P 5.33 0.87 12 P 0 8 0;3=3,5=1
P 6.26988996 2.37988996 12 P 0 8 0;3=3,5=1
P 4.46 3.745 12 P 0 8 0;3=3,5=1
P 3.83 3.415 12 P 0 8 0;3=3,5=1
P 3.506 3.325 36 P 0 8 0;0,3=0,5=0
P 3.55 3.325 11 P 0 8 0;3=11,5=1
P 6.335 3.015 12 P 0 8 0;3=3,5=1
P 1.667 3.388 12 P 0 8 0;3=3,5=1
P 0.995 3.564 32 P 0 8 0;0,3=0,5=0
P 4.48216998 1.80405 14 P 0 8 0;0,3=19,5=0
L 4.48216998 1.80405 4.48216004 1.80405 10 P 0 
L 4.48216004 1.80405 4.46248002 1.78436998 10 P 0 
P 4.4428 1.80405 14 P 0 8 0;0,3=19,5=0
L 4.4428 1.80405 4.42311004 1.82373996 10 P 0 
P 4.40343996 1.80406004 14 P 0 8 0;0,3=19,5=0
L 4.40343996 1.80406004 4.40343996 1.80406998 10 P 0 
L 4.40343996 1.80406998 4.42311004 1.82373996 10 P 0 
P 4.48216004 1.96153996 14 P 0 8 0;0,3=19,5=0
L 4.48216004 1.96153996 4.48216998 1.96153996 10 P 0 
L 4.48216998 1.96153996 4.50185 1.98121998 10 P 0 
L 4.311 0.73 4.345 0.764 10 P 0 
L 4.345 0.764 4.345 0.77 10 P 0 
P 4.311 0.73 36 P 0 8 0;0,3=0,5=0
P 1.591 3.504 12 P 0 8 0;3=3,5=1
L 1.63 3.504 1.591 3.504 10 P 0 
P 1.63 3.504 32 P 0 8 0;0,3=0,5=0
P 1.035 3.094 32 P 0 8 0;0,3=0,5=0
P 1.045 3.055 12 P 0 8 0;3=3,5=1
P 1.42 3.5 12 P 0 8 0;3=3,5=1
P 1.376 3.5 36 P 0 8 0;0,3=0,5=0
P 1.235 3.475 12 P 0 8 0;3=3,5=1
P 1.196 3.475 36 P 0 8 0;0,3=0,5=0
P 1.085 3.606 32 P 0 8 0;0,3=0,5=0
P 1.375 3.559 32 P 0 8 0;0,3=0,5=0
L 1.375 3.559 1.404 3.559 10 P 0 
L 1.404 3.559 1.409 3.554 10 P 0 
P 1.2 3.715 12 P 0 8 0;3=3,5=1
P 1.175 3.606 32 P 0 8 0;0,3=0,5=0
P 1.22 3.606 32 P 0 8 0;0,3=0,5=0
P 1.13 3.606 32 P 0 8 0;0,3=0,5=0
P 1.409 3.554 12 P 0 8 0;3=3,5=1
P 1.2 3.68 12 P 0 8 0;3=3,5=1
P 1.155 3.89 12 P 0 8 0;3=3,5=1
P 1.17 3.97 12 P 0 8 0;3=3,5=1
P 1.27 3.97061004 12 P 0 8 0;3=3,5=1
P 1.29 3.705 12 P 0 8 0;3=3,5=1
P 1.355 3.83 12 P 0 8 0;3=3,5=1
P 1.355 3.96 12 P 0 8 0;3=3,5=1
P 1.185 3.79 12 P 0 8 0;3=3,5=1
P 1.32 3.79 12 P 0 8 0;3=3,5=1
P 1.29 3.65 12 P 0 8 0;3=3,5=1
P 5.803 3.567 12 P 0 8 0;3=3,5=1
P 5.43 3.967 12 P 0 8 0;3=3,5=1
P 6.165 1.94873996 12 P 0 8 0;3=3,5=1
P 6.21 1.96773996 32 P 0 8 0;0,3=0,5=0
L 6.21 1.96773996 6.184 1.96773996 10 P 0 
L 6.184 1.96773996 6.165 1.94873996 10 P 0 
L 1.038 0.718 1.038 0.7624 10 P 0 
P 1.038 0.7624 12 P 0 8 0;3=3,5=1
L 4.546 1.085 4.53 1.101 10 P 0 
L 4.53 1.101 4.53 1.139 10 P 0 
L 4.933 1.263 4.894 1.263 10 P 0 
L 4.037 2.552 4.037 2.593 10 P 0 
P 4.037 2.593 12 P 0 8 0;3=3,5=1
P 3.978 2.593 12 P 0 8 0;3=3,5=1
L 3.978 2.552 3.978 2.593 10 P 0 
L 4.15 2.552 4.209 2.552 10 P 0 
P 4.209 2.552 32 P 0 8 0;0,3=0,5=0
L 4.093 2.552 4.15 2.552 10 P 0 
P 4.15 2.552 32 P 0 8 0;0,3=0,5=0
L 4.037 2.552 4.093 2.552 10 P 0 
P 4.093 2.552 32 P 0 8 0;0,3=0,5=0
L 3.978 2.552 4.037 2.552 10 P 0 
P 4.037 2.552 32 P 0 8 0;0,3=0,5=0
L 3.919 2.552 3.978 2.552 10 P 0 
P 3.978 2.552 32 P 0 8 0;0,3=0,5=0
L 3.86 2.552 3.919 2.552 10 P 0 
P 3.919 2.552 32 P 0 8 0;0,3=0,5=0
P 3.801 2.552 32 P 0 8 0;0,3=0,5=0
L 3.801 2.552 3.86 2.552 10 P 0 
P 3.86 2.552 32 P 0 8 0;0,3=0,5=0
P 4.81 0.707 12 P 0 8 0;3=3,5=1
L 6.421 1.08 6.421 1.086 10 P 0 
L 6.421 1.086 6.47 1.135 10 P 0 
P 6.47 1.135 12 P 0 8 0;3=3,5=1
P 4.595 3.22 12 P 0 8 0;3=3,5=1
L 4.175 3.52 4.17 3.515 10 P 0 
L 4.17 3.515 4.17 3.471 10 P 0 
P 4.17 3.471 32 P 0 8 0;0,3=0,5=0
P 4.175 3.52 12 P 0 8 0;3=3,5=1
P 3.98 3.471 32 P 0 8 0;0,3=0,5=0
P 3.98 3.52 12 P 0 8 0;3=3,5=1
P 3.973 3.207 12 P 0 8 0;3=3,5=1
L 3.973 3.239 3.973 3.207 10 P 0 
P 3.973 3.239 36 P 0 8 0;0,3=0,5=0
P 4.075 3.05 12 P 0 8 0;3=3,5=1
L 3.839 3.758 3.839 3.726 10 P 0 
P 3.839 3.726 12 P 0 8 0;3=3,5=1
P 3.839 3.758 36 P 0 8 0;0,3=0,5=0
P 4.1 3.58543002 12 P 0 8 0;3=3,5=1
P 5.637 3.524 15 P 0 8 0;1,3=1,5=1
P 5.316 3.51998996 28 P 0 8 0;0,3=28,5=0
P 5.276 3.189 12 P 0 8 0;3=3,5=1
P 5.329 3.189 12 P 0 8 0;3=3,5=1
P 5.386 3.189 12 P 0 8 0;3=3,5=1
P 5.271 3.456 12 P 0 8 0;3=3,5=1
P 5.271 3.406 12 P 0 8 0;3=3,5=1
P 5.324 3.456 12 P 0 8 0;3=3,5=1
P 5.381 3.456 12 P 0 8 0;3=3,5=1
P 5.324 3.406 12 P 0 8 0;3=3,5=1
P 5.381 3.406 12 P 0 8 0;3=3,5=1
P 5.802 3.617 12 P 0 8 0;3=3,5=1
P 5.763 3.712 12 P 0 8 0;3=3,5=1
P 5.803 3.757 12 P 0 8 0;3=3,5=1
P 5.803 3.807 12 P 0 8 0;3=3,5=1
P 5.602 3.865 12 P 0 8 0;3=3,5=1
P 5.645 3.79 12 P 0 8 0;3=3,5=1
P 5.48556998 3.877 15 P 0 8 0;1,3=1,5=1
P 5.237 3.777 12 P 0 8 0;3=3,5=1
P 5.282 3.777 12 P 0 8 0;3=3,5=1
P 5.237 3.841 12 P 0 8 0;3=3,5=1
P 5.322 3.777 12 P 0 8 0;3=3,5=1
P 5.385 4.07875 12 P 0 8 0;3=3,5=1
L 0.199 2.83 0.199 2.875 10 P 0 
L 0.29 2.829 0.2 2.829 10 P 0 
L 0.2 2.829 0.199 2.83 10 P 0 
P 0.199 2.875 36 P 0 8 0;0,3=0,5=0
P 0.199 2.83 12 P 0 8 0;3=3,5=1
P 0.29 2.829 32 P 0 8 0;0,3=0,5=0
P 1.2 3.645 12 P 0 8 0;3=3,5=1
P 1.1 3.64 12 P 0 8 0;3=3,5=1
P 1.065 3.64 12 P 0 8 0;3=3,5=1
P 1.03 3.64 12 P 0 8 0;3=3,5=1
P 0.99 3.5 12 P 0 8 0;3=3,5=1
P 0.664 0.774 12 P 0 8 0;3=3,5=1
P 0.86 0.833 32 P 0 8 0;0,3=0,5=0
L 0.86 0.833 0.86 0.844 10 P 0 
L 0.86 0.844 0.833 0.871 10 P 0 
L 0.833 0.911 0.833 0.871 10 P 0 
P 0.833 0.871 12 P 0 8 0;3=3,5=1
P 0.833 0.911 32 P 0 8 0;0,3=0,5=0
L 0.833 0.911 0.878 0.911 10 P 0 
P 0.878 0.911 32 P 0 8 0;0,3=0,5=0
P 0.66 0.911 12 P 0 8 0;3=3,5=1
P 0.698 0.911 32 P 0 8 0;0,3=0,5=0
P 0.695 1 12 P 0 8 0;3=3,5=1
P 0.485 2.715 12 P 0 8 0;3=3,5=1
P 0.51771998 2.45073996 12 P 0 8 0;3=3,5=1
P 0.675 2.229 12 P 0 8 0;3=3,5=1
P 0.575 2.185 12 P 0 8 0;3=3,5=1
P 0.51771998 1.87986998 12 P 0 8 0;3=3,5=1
P 0.539 1.57 12 P 0 8 0;3=3,5=1
P 0.51771998 1.305 12 P 0 8 0;3=3,5=1
P 0.476 0.689 12 P 0 8 0;3=3,5=1
P 0.614 1.049 12 P 0 8 0;3=3,5=1
P 0.51771998 0.736 12 P 0 8 0;3=3,5=1
P 0.47 1 12 P 0 8 0;3=3,5=1
P 0.677 0.65 12 P 0 8 0;3=3,5=1
P 0.677 0.615 36 P 0 8 0;0,3=0,5=0
P 4.546 1.085 12 P 0 8 0;3=3,5=1
P 4.585 1.139 32 P 0 8 0;0,3=0,5=0
L 4.585 1.139 4.53 1.139 10 P 0 
P 4.53 1.139 32 P 0 8 0;0,3=0,5=0
L 4.815 1.82016004 4.8132 1.82016004 10 P 0 
L 4.8132 1.82016004 4.81225 1.82111004 10 P 0 
L 4.81225 1.82111004 4.78 1.82111004 10 P 0 
P 0.43705 3.51576004 26 P 0 8 0;3=33,5=0
P 0.43705 3.31655 26 P 0 8 0;3=33,5=0
P 0.24806998 3.47245 26 P 0 8 0;3=33,5=0
P 0.24806998 3.35985 26 P 0 8 0;3=33,5=0
P 0.24606004 3.4315 13 P 0 8 0;3=7,5=0
P 0.4587 3.4315 13 P 0 8 0;3=7,5=0
P 0.44098002 3.4008 13 P 0 8 0;3=7,5=0
P 0.22833996 3.4008 13 P 0 8 0;3=7,5=0
P 0.858 2.831 32 P 0 8 0;0,3=0,5=0
P 3.0535 2.143 44 P 0 8 0;0,3=17,5=0
L 3.0535 2.143 3.093 2.143 10 P 0 
L 3.093 2.143 3.12 2.17 10 P 0 
P 5.75071998 1.655 12 P 0 8 0;3=3,5=1
P 1.76 4.16 12 P 0 8 0;3=3,5=1
P 2.26 3.785 12 P 0 8 0;3=3,5=1
P 2.215 3.785 12 P 0 8 0;3=3,5=1
P 3.843 3.687 12 P 0 8 0;3=3,5=1
P 0.61488996 3.32328996 12 P 0 8 0;3=3,5=1
P 5.335 1.245 12 P 0 8 0;3=3,5=1
P 5.345 1.3 12 P 0 8 0;3=3,5=1
P 5.345 1.365 12 P 0 8 0;3=3,5=1
P 3.645 2.13 12 P 0 8 0;3=3,5=1
P 3.651 2.17 36 P 0 8 0;0,3=0,5=0
P 3.67 2.13 12 P 0 8 0;3=3,5=1
P 3.11 1.935 12 P 0 8 0;3=3,5=1
P 4.294 1.075 12 P 0 8 0;3=3,5=1
P 4.5 1.082 12 P 0 8 0;3=3,5=1
P 5.385 1.895 12 P 0 8 0;3=3,5=1
P 5.425 1.895 12 P 0 8 0;3=3,5=1
P 5.4 1.853 43 P 0 8 0;0,3=12,5=0
P 5.39 1.604 32 P 0 8 0;0,3=0,5=0
P 5.76458996 1.61971004 12 P 0 8 0;3=3,5=1
P 5.34 1.605 12 P 0 8 0;3=3,5=1
P 5.44 1.59 12 P 0 8 0;3=3,5=1
P 4.54123002 1.70563996 11 P 0 8 0;3=2,5=1
P 4.73806998 1.66626998 11 P 0 8 0;3=2,5=1
P 4.26563996 2.17806998 11 P 0 8 0;3=2,5=1
P 4.6987 1.3513 11 P 0 8 0;3=2,5=1
P 4.57843996 1.31408002 11 P 0 8 0;3=2,5=1
P 4.54121998 1.43005 11 P 0 8 0;3=2,5=1
P 4.42311004 1.54816004 11 P 0 8 0;3=2,5=1
P 4.42311004 1.39066998 11 P 0 8 0;3=2,5=1
P 4.38373996 1.58753002 11 P 0 8 0;3=2,5=1
P 4.38373996 1.50878996 11 P 0 8 0;3=2,5=1
P 4.38373996 1.6269 11 P 0 8 0;3=2,5=1
P 4.34436998 1.54816004 11 P 0 8 0;3=2,5=1
P 4.34436998 1.66626998 11 P 0 8 0;3=2,5=1
P 4.34436998 1.6269 11 P 0 8 0;3=2,5=1
P 4.26563996 1.58753002 11 P 0 8 0;3=2,5=1
P 4.26563996 1.3513 11 P 0 8 0;3=2,5=1
P 4.26563996 1.6269 11 P 0 8 0;3=2,5=1
P 4.26563996 1.66626998 11 P 0 8 0;3=2,5=1
P 4.22626998 1.54816004 11 P 0 8 0;3=2,5=1
P 4.22626998 1.46941998 11 P 0 8 0;3=2,5=1
P 4.22626998 1.6269 11 P 0 8 0;3=2,5=1
P 4.1869 1.58753002 11 P 0 8 0;3=2,5=1
P 4.14753002 1.54816004 11 P 0 8 0;3=2,5=1
P 4.14753002 1.31193002 11 P 0 8 0;3=2,5=1
P 4.10816004 1.54816004 11 P 0 8 0;3=2,5=1
P 4.10816004 1.50878996 11 P 0 8 0;3=2,5=1
P 4.10816004 1.46941998 11 P 0 8 0;3=2,5=1
P 4.06878996 1.46941998 11 P 0 8 0;3=2,5=1
P 4.02941998 1.46941998 11 P 0 8 0;3=2,5=1
P 4.02941998 1.43005 11 P 0 8 0;3=2,5=1
P 3.99005 1.43005 11 P 0 8 0;3=2,5=1
P 3.99005 1.39066998 11 P 0 8 0;3=2,5=1
P 3.95066998 1.39066998 11 P 0 8 0;3=2,5=1
P 3.87193002 2.17806998 11 P 0 8 0;3=2,5=1
P 3.9113 2.05996004 11 P 0 8 0;3=2,5=1
P 3.95066998 1.94185 11 P 0 8 0;3=2,5=1
P 4.10816004 1.86311004 11 P 0 8 0;3=2,5=1
P 3.99005 1.82373996 11 P 0 8 0;3=2,5=1
P 4.1869 1.78436998 11 P 0 8 0;3=2,5=1
P 4.10816004 1.78436998 11 P 0 8 0;3=2,5=1
P 3.99005 1.78436998 11 P 0 8 0;3=2,5=1
P 3.87193002 1.78436998 11 P 0 8 0;3=2,5=1
P 3.95066998 1.78436998 11 P 0 8 0;3=2,5=1
P 3.9113 1.78436998 11 P 0 8 0;3=2,5=1
P 4.22626998 1.70563996 11 P 0 8 0;3=2,5=1
P 4.14753002 1.70563996 11 P 0 8 0;3=2,5=1
P 4.06878996 1.70563996 11 P 0 8 0;3=2,5=1
P 4.02941998 1.70563996 11 P 0 8 0;3=2,5=1
P 3.87193002 1.70563996 11 P 0 8 0;3=2,5=1
P 4.1869 1.66626998 11 P 0 8 0;3=2,5=1
P 4.10816004 1.66626998 11 P 0 8 0;3=2,5=1
P 3.95066998 1.66626998 11 P 0 8 0;3=2,5=1
P 3.87193002 1.6269 11 P 0 8 0;3=2,5=1
P 4.14753002 1.6269 11 P 0 8 0;3=2,5=1
P 4.10816004 1.6269 11 P 0 8 0;3=2,5=1
P 4.02941998 1.6269 11 P 0 8 0;3=2,5=1
P 4.10816004 1.58753002 11 P 0 8 0;3=2,5=1
P 3.99005 1.58753002 11 P 0 8 0;3=2,5=1
P 3.87193002 1.54816004 11 P 0 8 0;3=2,5=1
P 4.02941998 1.54816004 11 P 0 8 0;3=2,5=1
P 3.95066998 1.50878996 11 P 0 8 0;3=2,5=1
P 3.87193002 1.46941998 11 P 0 8 0;3=2,5=1
P 3.87193002 1.39066998 11 P 0 8 0;3=2,5=1
P 3.9113 1.39066998 11 P 0 8 0;3=2,5=1
P 3.87193002 1.3513 11 P 0 8 0;3=2,5=1
P 4.6987 2.17806998 11 P 0 8 0;3=2,5=1
P 4.58058996 2.1387 11 P 0 8 0;3=2,5=1
P 4.50185 1.98121998 11 P 0 8 0;3=2,5=1
P 4.46248002 2.09933002 11 P 0 8 0;3=2,5=1
P 4.38373996 1.94185 11 P 0 8 0;3=2,5=1
P 4.34436998 2.05996004 11 P 0 8 0;3=2,5=1
P 4.22626998 1.90248002 11 P 0 8 0;3=2,5=1
P 4.1869 2.02058996 11 P 0 8 0;3=2,5=1
P 4.14753002 2.1387 11 P 0 8 0;3=2,5=1
P 4.06878996 1.98121998 11 P 0 8 0;3=2,5=1
P 4.02941998 2.09933002 11 P 0 8 0;3=2,5=1
P 4.73806998 2.05996004 11 P 0 8 0;3=2,5=1
P 4.61996004 2.02058996 11 P 0 8 0;3=2,5=1
P 4.65933002 1.90248002 11 P 0 8 0;3=2,5=1
P 4.54121998 1.86311004 11 P 0 8 0;3=2,5=1
P 4.42311004 1.82373996 11 P 0 8 0;3=2,5=1
P 4.6987 1.78436998 11 P 0 8 0;3=2,5=1
P 4.46248002 1.78436998 11 P 0 8 0;3=2,5=1
P 4.50185 1.70563996 11 P 0 8 0;3=2,5=1
P 4.42311004 1.70563996 11 P 0 8 0;3=2,5=1
P 4.34436998 1.70563996 11 P 0 8 0;3=2,5=1
P 4.46248002 1.66626998 11 P 0 8 0;3=2,5=1
P 4.58058996 1.66626998 11 P 0 8 0;3=2,5=1
P 4.38373996 1.66626998 11 P 0 8 0;3=2,5=1
P 4.50185 1.6269 11 P 0 8 0;3=2,5=1
P 4.42311004 1.6269 11 P 0 8 0;3=2,5=1
P 4.61996004 1.58753002 11 P 0 8 0;3=2,5=1
P 4.46248002 1.58753002 11 P 0 8 0;3=2,5=1
P 4.50185 1.54816004 11 P 0 8 0;3=2,5=1
P 4.65933002 1.46941998 11 P 0 8 0;3=2,5=1
L 4.6987 2.17806998 4.67903002 2.1584 10 P 0 
L 4.67903002 2.1584 4.67901998 2.1584 10 P 0 
L 4.65933002 1.90248002 4.63966004 1.92215 10 P 0 
L 4.63966004 1.92215 4.63966004 1.92216998 10 P 0 
L 4.63965 1.88281004 4.63966004 1.88281004 10 P 0 
L 4.63966004 1.88281004 4.65933002 1.90248002 10 P 0 
L 4.61996004 1.58753002 4.63963996 1.56785 10 P 0 
L 4.63963996 1.56785 4.63963996 1.56783996 10 P 0 
L 4.46511004 1.755 4.46511004 1.78173996 10 P 0 
L 4.46511004 1.78173996 4.46248002 1.78436998 10 P 0 
L 4.54121998 1.86311004 4.52155 1.84343996 10 P 0 
L 4.52155 1.84343996 4.52153996 1.84343996 10 P 0 
L 4.54123002 1.70563996 4.54123002 1.74111998 10 P 0 
L 4.54123002 1.74111998 4.55511004 1.755 10 P 0 
L 4.46248002 1.58753002 4.48216998 1.56783996 10 P 0 
L 4.48216998 1.56783996 4.48216998 1.56783002 10 P 0 
L 4.50185 1.6269 4.52151998 1.64656998 10 P 0 
L 4.52151998 1.64656998 4.52153996 1.64656998 10 P 0 
L 4.46248002 1.66626998 4.48216998 1.64658002 10 P 0 
L 4.48216998 1.64658002 4.48218002 1.64658002 10 P 0 
L 4.54121998 1.43005 4.5609 1.41036998 10 P 0 
L 4.5609 1.41036998 4.5609 1.41035 10 P 0 
L 4.52153996 1.41035 4.52153996 1.41036998 10 P 0 
L 4.52153996 1.41036998 4.54121998 1.43005 10 P 0 
L 4.34436998 2.05996004 4.31341004 2.029 10 P 0 
L 4.31341004 2.029 4.3 2.029 10 P 0 
L 4.42311004 1.6269 4.44278996 1.60721998 10 P 0 
L 4.44278996 1.60721998 4.4428 1.60721998 10 P 0 
L 4.26563996 1.6269 4.2829 1.6269 10 P 0 
L 4.2829 1.6269 4.305 1.649 10 P 0 
L 4.26563996 1.58753002 4.26911004 1.591 10 P 0 
L 4.26911004 1.591 4.305 1.591 10 P 0 
L 4.34436998 1.54816004 4.34436998 1.54236004 10 P 0 
L 4.34436998 1.54236004 4.309 1.50698996 10 P 0 
L 4.309 1.50698996 4.309 1.48468996 10 P 0 
L 4.38373996 1.6269 4.36406004 1.64658002 10 P 0 
L 4.36406004 1.64658002 4.36406004 1.64658996 10 P 0 
L 4.40343002 1.64656998 4.40341004 1.64656998 10 P 0 
L 4.40341004 1.64656998 4.38373996 1.6269 10 P 0 
L 4.42311004 1.54816004 4.40563996 1.56563996 10 P 0 
L 4.40563996 1.56563996 4.40343996 1.56783002 10 P 0 
L 4.40343996 1.56783002 4.40343002 1.56783002 10 P 0 
L 4.38373996 1.50878996 4.36406998 1.52846004 10 P 0 
L 4.36406998 1.52846004 4.36406004 1.52846004 10 P 0 
L 4.42311004 1.39066998 4.44278996 1.41035 10 P 0 
L 4.44278996 1.41035 4.4428 1.41035 10 P 0 
L 4.40343002 1.37098996 4.42311004 1.39066998 10 P 0 
L 4.06878996 1.98121998 4.08846004 1.96155 10 P 0 
L 4.08846004 1.96155 4.08846004 1.96153996 10 P 0 
L 4.0491 1.96155 4.04911998 1.96155 10 P 0 
L 4.04911998 1.96155 4.06878996 1.98121998 10 P 0 
L 4.1869 2.02058996 4.16723002 2.00091998 10 P 0 
L 4.16723002 2.00091998 4.16721004 2.00091998 10 P 0 
L 4.16721998 2.04028002 4.16721998 2.04026998 10 P 0 
L 4.16721998 2.04026998 4.1869 2.02058996 10 P 0 
L 4.22626998 1.90248002 4.2066 1.88281004 10 P 0 
L 4.2066 1.88281004 4.20658002 1.88281004 10 P 0 
L 4.1869 1.78436998 4.20656998 1.80403996 10 P 0 
L 4.20656998 1.80403996 4.20656998 1.80406004 10 P 0 
L 4.199 1.75 4.199 1.77226998 10 P 0 
L 4.199 1.77226998 4.1869 1.78436998 10 P 0 
L 4.1869 1.66626998 4.20656998 1.68593996 10 P 0 
L 4.20656998 1.68593996 4.20656998 1.68595 10 P 0 
L 4.1869 1.58753002 4.20656998 1.6072 10 P 0 
L 4.20656998 1.6072 4.20658002 1.6072 10 P 0 
L 4.22626998 1.6269 4.24595 1.64658002 10 P 0 
L 4.24595 1.64658002 4.24595 1.64658996 10 P 0 
L 4.22626998 1.54816004 4.24595 1.56783996 10 P 0 
L 4.24595 1.56783996 4.24596004 1.56783996 10 P 0 
L 4.22626998 1.46941998 4.2066 1.48908996 10 P 0 
L 4.2066 1.48908996 4.20658002 1.48908996 10 P 0 
L 3.9113 2.05996004 3.93096998 2.04028996 10 P 0 
L 3.93096998 2.04028996 3.93096998 2.04028002 10 P 0 
L 3.93098002 2.07963996 3.9113 2.05996004 10 P 0 
L 3.87193002 2.17806998 3.8916 2.1584 10 P 0 
L 3.8916 2.1584 3.8916 2.15838996 10 P 0 
S P 0
OB 0.5 4.33661003937 I
OS 0.5 3.5315
OS 0.039369980315 3.5315
OS 0.030119980315 3.5315
OS 0.030119980315 3.9179
OS 0.030119980315 4.337469980315
OS 0.03853996063 4.34588996063
OS 0.5 4.34588996063
OS 0.5 4.33661003937
OE
SE
S P 0
OB 0.047369980315 3.513330019685 I
OC 0.049980019685 3.511419980315 0.047979232283 3.511424212598 Y
OS 0.049980019685 2.775
OS 0.03003996063 2.775
OS 0.03003996063 3.511419980315
OC 0.03265 3.513319980315 0.03203976378 3.511415551181 Y
OC 0.03998996063 3.512169980315 0.039993503937 3.536191240157 N
OS 0.04 3.512169980315
OC 0.047369980315 3.513330019685 0.039995570866 3.536189862205 N
OE
SE
S P 0
OB 0.560430019685 0.5353 I
OS 0.560430019685 0.2166
OS 0.55126003937 0.207430019685
OS 0.071380019685 0.207430019685
OS 0.038269980315 0.207430019685
OS 0.030330019685 0.215369980315
OS 0.030330019685 0.5353
OS 0.560430019685 0.5353
OE
SE
S P 0
OB 0.03003996063 0.21653996063 I
OS 0.03003996063 0.545
OS 0.048980019685 0.545
OS 0.049980019685 0.544
OS 0.049980019685 0.22713996063
OS 0.540580019685 0.22713996063
OS 0.540580019685 0.4626
OC 0.629919980315 0.55193996063 0.629919980315 0.4626 Y
OS 1.273619980315 0.55193996063
OC 1.36296003937 0.4626 1.27362007874 0.4626 Y
OS 1.36296003937 0.22713996063
OS 1.577980019685 0.22713996063
OS 1.577980019685 0.430119980315
OC 1.6998 0.55193996063 1.6998 0.430119980315 Y
OC 1.81398996063 0.472580019685 1.6998 0.430106791339 Y
OS 1.80286003937 0.46145
OC 1.79623996063 0.46298996063 1.800028051181 0.46427519685 Y
OC 1.6998 0.53201003937 1.699799901575 0.430123326772 N
OC 1.59791003937 0.430119980315 1.6998 0.43012007874 N
OS 1.59791003937 0.21653996063
OC 1.588580019685 0.20721003937 1.58858011811 0.21653996063 Y
OS 1.35236003937 0.20721003937
OC 1.343030019685 0.21653996063 1.352359940945 0.21653996063 Y
OS 1.343030019685 0.4626
OC 1.273619980315 0.53201003937 1.273619980315 0.4626 N
OS 0.629919980315 0.53201003937
OC 0.56051003937 0.4626 0.629919980315 0.462600098425 N
OS 0.56051003937 0.21653996063
OC 0.551180019685 0.20721003937 0.55118011811 0.21653996063 Y
OS 0.039369980315 0.20721003937
OC 0.03003996063 0.21653996063 0.03936988189 0.21653996063 Y
OE
SE
S P 0
OB 1.673 4.013 I
OS 1.661930019685 4.013
OS 1.635 4.013
OS 1.633 4.015
OS 1.633 4.057
OS 1.635830019685 4.059830019685
OS 1.65703996063 4.059830019685
OC 1.65818996063 4.06 1.658193405512 4.056001574803 Y
OS 1.674 4.06
OS 1.677 4.057
OS 1.677 4.017
OS 1.673 4.013
OE
SE
P 1.6355 4.031 45 P 0 8 0;0,3=23,5=0
P 0.12878002 0.21716998 11 P 0 8 0;3=11,5=1
P 0.16878002 0.21716998 11 P 0 8 0;3=11,5=1
P 0.20878002 0.21716998 11 P 0 8 0;3=11,5=1
P 0.24878002 0.21716998 11 P 0 8 0;3=11,5=1
P 0.08413002 4.33598002 11 P 0 8 0;3=11,5=1
P 0.04413002 4.33598002 11 P 0 8 0;3=11,5=1
P 0.04 4.29618996 11 P 0 8 0;3=11,5=1
P 0.04 4.25618996 11 P 0 8 0;3=11,5=1
P 0.04 4.21618996 11 P 0 8 0;3=11,5=1
P 0.04 4.17618996 11 P 0 8 0;3=11,5=1
P 0.04 4.13618996 11 P 0 8 0;3=11,5=1
P 0.04 4.09618996 11 P 0 8 0;3=11,5=1
P 0.04 4.05618996 11 P 0 8 0;3=11,5=1
P 0.04 4.01618996 11 P 0 8 0;3=11,5=1
P 0.04 3.97618996 11 P 0 8 0;3=11,5=1
P 0.04 3.93618996 11 P 0 8 0;3=11,5=1
P 0.04 3.89618996 11 P 0 8 0;3=11,5=1
P 0.04 3.85618996 11 P 0 8 0;3=11,5=1
P 0.04 3.81618996 11 P 0 8 0;3=11,5=1
P 0.04 3.77618996 11 P 0 8 0;3=11,5=1
P 0.04 3.73618996 11 P 0 8 0;3=11,5=1
P 0.04 3.69618996 11 P 0 8 0;3=11,5=1
P 0.04 3.65618996 11 P 0 8 0;3=11,5=1
P 0.04 3.61618996 11 P 0 8 0;3=11,5=1
P 0.04 3.57618996 11 P 0 8 0;3=11,5=1
P 0.04 3.53618996 11 P 0 8 0;3=11,5=1
P 0.04 3.49618996 11 P 0 8 0;3=11,5=1
P 0.04 3.45618996 11 P 0 8 0;3=11,5=1
P 0.04 3.41618996 11 P 0 8 0;3=11,5=1
P 0.04 3.37618996 11 P 0 8 0;3=11,5=1
P 0.04 2.97618996 11 P 0 8 0;3=11,5=1
P 0.04 2.93618996 11 P 0 8 0;3=11,5=1
P 0.04 2.89618996 11 P 0 8 0;3=11,5=1
P 0.04 0.49618996 11 P 0 8 0;3=11,5=1
P 0.04 0.45618996 11 P 0 8 0;3=11,5=1
P 0.04 0.41618996 11 P 0 8 0;3=11,5=1
P 0.04 0.37618996 11 P 0 8 0;3=11,5=1
P 0.04 0.33618996 11 P 0 8 0;3=11,5=1
P 0.04 0.29618996 11 P 0 8 0;3=11,5=1
P 0.04 0.25618996 11 P 0 8 0;3=11,5=1
P 0.04878002 0.21716998 11 P 0 8 0;3=11,5=1
P 0.08878002 0.21716998 11 P 0 8 0;3=11,5=1
P 2.76413002 4.33598002 11 P 0 8 0;3=11,5=1
P 2.72413002 4.33598002 11 P 0 8 0;3=11,5=1
P 2.68413002 4.33598002 11 P 0 8 0;3=11,5=1
P 2.64413002 4.33598002 11 P 0 8 0;3=11,5=1
P 2.60413002 4.33598002 11 P 0 8 0;3=11,5=1
P 0.55055 0.45073002 11 P 0 8 0;3=11,5=1
P 0.55558002 0.49041004 11 P 0 8 0;3=11,5=1
P 0.57858996 0.52313002 11 P 0 8 0;3=11,5=1
P 0.61463002 0.54048002 11 P 0 8 0;3=11,5=1
P 0.55055 0.29073002 11 P 0 8 0;3=11,5=1
P 0.55055 0.33073002 11 P 0 8 0;3=11,5=1
P 0.55055 0.37073002 11 P 0 8 0;3=11,5=1
P 0.55055 0.41073002 11 P 0 8 0;3=11,5=1
P 0.48878002 0.21716998 11 P 0 8 0;3=11,5=1
P 0.52878002 0.21716998 11 P 0 8 0;3=11,5=1
P 0.55055 0.25073002 11 P 0 8 0;3=11,5=1
P 0.44413002 4.33598002 11 P 0 8 0;3=11,5=1
P 0.40413002 4.33598002 11 P 0 8 0;3=11,5=1
P 0.36413002 4.33598002 11 P 0 8 0;3=11,5=1
P 0.32413002 4.33598002 11 P 0 8 0;3=11,5=1
P 0.28878002 0.21716998 11 P 0 8 0;3=11,5=1
P 0.32878002 0.21716998 11 P 0 8 0;3=11,5=1
P 0.36878002 0.21716998 11 P 0 8 0;3=11,5=1
P 0.40878002 0.21716998 11 P 0 8 0;3=11,5=1
P 0.44878002 0.21716998 11 P 0 8 0;3=11,5=1
P 0.28413002 4.33598002 11 P 0 8 0;3=11,5=1
P 0.24413002 4.33598002 11 P 0 8 0;3=11,5=1
P 0.20413002 4.33598002 11 P 0 8 0;3=11,5=1
P 0.16413002 4.33598002 11 P 0 8 0;3=11,5=1
P 0.12413002 4.33598002 11 P 0 8 0;3=11,5=1
P 0.889 0.67 12 P 0 8 0;3=3,5=1
P 0.6546 0.54196998 11 P 0 8 0;3=11,5=1
P 0.6946 0.54196998 11 P 0 8 0;3=11,5=1
P 0.7346 0.54196998 11 P 0 8 0;3=11,5=1
P 0.7746 0.54196998 11 P 0 8 0;3=11,5=1
P 0.8146 0.54196998 11 P 0 8 0;3=11,5=1
P 0.64413002 4.33598002 11 P 0 8 0;3=11,5=1
P 0.60413002 4.33598002 11 P 0 8 0;3=11,5=1
P 0.56413002 4.33598002 11 P 0 8 0;3=11,5=1
P 0.52413002 4.33598002 11 P 0 8 0;3=11,5=1
P 0.48413002 4.33598002 11 P 0 8 0;3=11,5=1
P 0.8575 2.0275 12 P 0 8 0;3=3,5=1
P 1.195 0.57693996 12 P 0 8 0;3=3,5=1
P 0.8546 0.54196998 11 P 0 8 0;3=11,5=1
P 0.8946 0.54196998 11 P 0 8 0;3=11,5=1
P 0.9346 0.54196998 11 P 0 8 0;3=11,5=1
P 0.9746 0.54196998 11 P 0 8 0;3=11,5=1
P 0.80413002 4.33598002 11 P 0 8 0;3=11,5=1
P 0.76413002 4.33598002 11 P 0 8 0;3=11,5=1
P 0.72413002 4.33598002 11 P 0 8 0;3=11,5=1
P 0.68413002 4.33598002 11 P 0 8 0;3=11,5=1
P 0.66 4.19 12 P 0 8 0;3=3,5=1
P 0.67 2.831 11 P 0 8 0;3=11,5=1
P 0.79248002 2.661 11 P 0 8 0;3=11,5=1
P 0.80148002 2.53648002 12 P 0 8 0;3=3,5=1
P 0.715 2.478 12 P 0 8 0;3=3,5=1
P 0.714 2.217 12 P 0 8 0;3=3,5=1
P 0.74593002 2.02206998 12 P 0 8 0;3=3,5=1
P 1.0146 0.54196998 11 P 0 8 0;3=11,5=1
P 1.0546 0.54196998 11 P 0 8 0;3=11,5=1
P 1.0946 0.54196998 11 P 0 8 0;3=11,5=1
P 1.1346 0.54196998 11 P 0 8 0;3=11,5=1
P 1.1746 0.54196998 11 P 0 8 0;3=11,5=1
P 1.00413002 4.33598002 11 P 0 8 0;3=11,5=1
P 0.96413002 4.33598002 11 P 0 8 0;3=11,5=1
P 0.92413002 4.33598002 11 P 0 8 0;3=11,5=1
P 0.88413002 4.33598002 11 P 0 8 0;3=11,5=1
P 0.84413002 4.33598002 11 P 0 8 0;3=11,5=1
P 1.025 4.2 12 P 0 8 0;3=3,5=1
P 0.94 4.2 12 P 0 8 0;3=3,5=1
P 0.858 2.87451998 15 P 0 8 0;3=5,5=1
L 0.858 2.831 0.858 2.87451998 10 P 0 
P 0.988 2.724 12 P 0 8 0;3=3,5=1
P 0.987 2.683 15 P 0 8 0;1,3=1,5=1
P 0.856 2.637 11 P 0 8 0;3=11,5=1
P 0.93031998 2.46476998 12 P 0 8 0;3=3,5=1
P 0.872 2.583 12 P 0 8 0;3=3,5=1
P 0.868 2.3 11 P 0 8 0;3=11,5=1
P 1.401 3.956 12 P 0 8 0;3=3,5=1
L 1.401 3.956 1.411 3.946 9 P 0 
L 1.411 3.946 1.435 3.946 9 P 0 
P 1.435 3.946 36 P 0 8 0;0,3=0,5=0
P 1.40123002 3.91603996 12 P 0 8 0;3=3,5=1
P 1.48 3.7 12 P 0 8 0;3=3,5=1
P 1.38163002 0.21716998 11 P 0 8 0;3=11,5=1
P 1.42163002 0.21716998 11 P 0 8 0;3=11,5=1
P 1.46163002 0.21716998 11 P 0 8 0;3=11,5=1
P 1.50163002 0.21716998 11 P 0 8 0;3=11,5=1
P 1.54163002 0.21716998 11 P 0 8 0;3=11,5=1
P 1.36413002 4.33598002 11 P 0 8 0;3=11,5=1
P 1.32413002 4.33598002 11 P 0 8 0;3=11,5=1
P 1.28413002 4.33598002 11 P 0 8 0;3=11,5=1
P 1.24413002 4.33598002 11 P 0 8 0;3=11,5=1
P 1.20413002 4.33598002 11 P 0 8 0;3=11,5=1
P 1.515 3.7 12 P 0 8 0;3=3,5=1
P 1.385 0.75 11 P 0 8 0;3=11,5=1
P 1.44 0.625 11 P 0 8 0;3=11,5=1
P 1.5184 0.79935 11 P 0 8 0;3=11,5=1
P 1.2146 0.54196998 11 P 0 8 0;3=11,5=1
P 1.2546 0.54196998 11 P 0 8 0;3=11,5=1
P 1.2945 0.53916998 11 P 0 8 0;3=11,5=1
P 1.3292 0.51926004 11 P 0 8 0;3=11,5=1
P 1.34976998 0.48496004 11 P 0 8 0;3=11,5=1
P 1.35298996 0.44508996 11 P 0 8 0;3=11,5=1
P 1.35298996 0.40508996 11 P 0 8 0;3=11,5=1
P 1.35298996 0.36508996 11 P 0 8 0;3=11,5=1
P 1.35298996 0.32508996 11 P 0 8 0;3=11,5=1
P 1.35298996 0.28508996 11 P 0 8 0;3=11,5=1
P 1.35298996 0.24508996 11 P 0 8 0;3=11,5=1
P 1.16413002 4.33598002 11 P 0 8 0;3=11,5=1
P 1.12413002 4.33598002 11 P 0 8 0;3=11,5=1
P 1.08413002 4.33598002 11 P 0 8 0;3=11,5=1
P 1.04413002 4.33598002 11 P 0 8 0;3=11,5=1
P 1.96413002 4.33598002 11 P 0 8 0;3=11,5=1
P 1.92413002 4.33598002 11 P 0 8 0;3=11,5=1
P 1.915 4.13 12 P 0 8 0;3=3,5=1
L 1.873 4.13 1.915 4.13 10 P 0 
P 1.873 4.13 39 P 0 8 0;0,3=12,5=0
P 1.88413002 4.33598002 11 P 0 8 0;3=11,5=1
P 1.84413002 4.33598002 11 P 0 8 0;3=11,5=1
P 1.80413002 4.33598002 11 P 0 8 0;3=11,5=1
P 1.76413002 4.33598002 11 P 0 8 0;3=11,5=1
P 1.746 4.061 12 P 0 8 0;3=3,5=1
P 1.746 4.106 15 P 0 8 0;1,3=1,5=1
P 1.751 3.871 12 P 0 8 0;3=3,5=1
P 1.746 4.016 12 P 0 8 0;3=3,5=1
P 1.751 3.826 15 P 0 8 0;1,3=1,5=1
P 1.786 3.746 12 P 0 8 0;3=3,5=1
P 1.786 3.786 12 P 0 8 0;3=3,5=1
P 2.0966 3.315 11 P 0 8 0;3=11,5=1
P 1.72413002 4.33598002 11 P 0 8 0;3=11,5=1
P 1.68413002 4.33598002 11 P 0 8 0;3=11,5=1
P 1.64413002 4.33598002 11 P 0 8 0;3=11,5=1
P 1.60413002 4.33598002 11 P 0 8 0;3=11,5=1
P 1.56413002 4.33598002 11 P 0 8 0;3=11,5=1
P 1.671 4.056 11 P 0 8 0;3=11,5=1
P 1.5086 0.674 15 P 0 8 0;1,3=1,5=1
P 1.59111998 0.45653996 11 P 0 8 0;3=11,5=1
P 1.60736004 0.49308996 11 P 0 8 0;3=11,5=1
P 1.58795 0.29666998 11 P 0 8 0;3=11,5=1
P 1.58795 0.33666998 11 P 0 8 0;3=11,5=1
P 1.58795 0.37666998 11 P 0 8 0;3=11,5=1
P 1.58795 0.41666998 11 P 0 8 0;3=11,5=1
P 1.58163002 0.21716998 11 P 0 8 0;3=11,5=1
P 1.58795 0.25666998 11 P 0 8 0;3=11,5=1
P 1.52413002 4.33598002 11 P 0 8 0;3=11,5=1
P 1.48413002 4.33598002 11 P 0 8 0;3=11,5=1
P 1.44413002 4.33598002 11 P 0 8 0;3=11,5=1
P 1.40413002 4.33598002 11 P 0 8 0;3=11,5=1
P 2.56413002 4.33598002 11 P 0 8 0;3=11,5=1
P 2.52413002 4.33598002 11 P 0 8 0;3=11,5=1
P 2.48413002 4.33598002 11 P 0 8 0;3=11,5=1
P 2.44413002 4.33598002 11 P 0 8 0;3=11,5=1
P 2.40413002 4.33598002 11 P 0 8 0;3=11,5=1
P 2.36413002 4.33598002 11 P 0 8 0;3=11,5=1
P 2.32413002 4.33598002 11 P 0 8 0;3=11,5=1
P 2.28413002 4.33598002 11 P 0 8 0;3=11,5=1
P 2.295 4.15 12 P 0 8 0;3=3,5=1
P 2.285 3.825 15 P 0 8 0;1,3=1,5=1
P 2.24413002 4.33598002 11 P 0 8 0;3=11,5=1
P 2.20413002 4.33598002 11 P 0 8 0;3=11,5=1
P 2.16413002 4.33598002 11 P 0 8 0;3=11,5=1
P 2.12413002 4.33598002 11 P 0 8 0;3=11,5=1
P 2.176 4.151 12 P 0 8 0;3=3,5=1
P 2.256 4.151 12 P 0 8 0;3=3,5=1
P 2.215 4.15 12 P 0 8 0;3=3,5=1
P 2.18 3.811 12 P 0 8 0;3=3,5=1
P 2.218 2.895 11 P 0 8 0;3=11,5=1
P 2.173 2.895 11 P 0 8 0;3=11,5=1
P 2.083 2.895 11 P 0 8 0;3=11,5=1
L 2.173 2.931 2.128 2.931 10 P 0 
P 2.128 2.931 32 P 0 8 0;0,3=0,5=0
L 2.128 2.931 2.083 2.931 10 P 0 
P 2.083 2.931 32 P 0 8 0;0,3=0,5=0
P 2.173 2.931 32 P 0 8 0;0,3=0,5=0
P 2.08413002 4.33598002 11 P 0 8 0;3=11,5=1
P 2.04413002 4.33598002 11 P 0 8 0;3=11,5=1
P 2.00413002 4.33598002 11 P 0 8 0;3=11,5=1
S P 0
OB 6.51838996063 0.65353996063 I
OC 6.51838996063 0.65353996063 6.40038996063 0.65353996063 Y
OE
OB 6.47538996063 0.65353996063 H
OC 6.47538996063 0.65353996063 6.40038996063 0.65353996063 N
OE
SE
S P 0
OB 0.413280019685 3.73031003937 I
OC 0.413280019685 3.73031003937 0.295280019685 3.73031003937 Y
OE
OB 0.370280019685 3.73031003937 H
OC 0.370280019685 3.73031003937 0.295280019685 3.73031003937 N
OE
SE
P 0.22703996 3.79855 13 P 0 8 0;3=32,5=0
P 0.19878002 3.73031004 13 P 0 8 0;3=32,5=0
P 0.22703996 3.66206998 13 P 0 8 0;3=32,5=0
P 0.29528002 3.63381004 13 P 0 8 0;3=32,5=0
P 0.36351998 3.66206998 13 P 0 8 0;3=32,5=0
P 0.39178002 3.73031004 13 P 0 8 0;3=32,5=0
P 0.36351998 3.79855 13 P 0 8 0;3=32,5=0
P 0.29528002 3.82681004 13 P 0 8 0;3=32,5=0
P 6.19961004 2.21273996 11 P 0 8 0;3=11,5=1
P 6.19961004 2.30873996 11 P 0 8 0;3=11,5=1
P 4.3445 1.16598996 11 P 0 8 0;3=11,5=1
P 4.4405 1.16598996 11 P 0 8 0;3=11,5=1
P 3.45301004 1.96298996 11 P 0 8 0;3=11,5=1
P 3.65101004 1.94758996 11 P 0 8 0;3=11,5=1
L 4.275 0.961 4.275 1 10 P 0 
L 4.275 1 4.278 1.003 10 P 0 
P 4.44 2.63 12 P 0 8 0;3=3,5=1
P 4.395 2.665 12 P 0 8 0;3=3,5=1
P 4.566 2.845 36 P 0 8 0;0,3=0,5=0
L 4.566 2.845 4.6 2.845 10 P 0 
P 4.566 2.895 36 P 0 8 0;0,3=0,5=0
L 4.566 2.895 4.6 2.895 10 P 0 
P 4.6 2.895 12 P 0 8 0;3=3,5=1
P 4.6 2.845 12 P 0 8 0;3=3,5=1
P 5.753 1.99 39 P 0 8 0;0,3=12,5=0
L 5.753 1.99 5.753 2.022 10 P 0 
L 5.753 2.022 5.732 2.043 10 P 0 
L 3.26 3.74 3.243 3.757 10 P 0 
L 3.243 3.757 3.185 3.757 10 P 0 
P 3.185 3.757 43 P 0 8 0;0,3=12,5=0
P 3.42 3.76 12 P 0 8 0;3=3,5=1
P 3.385 3.76 12 P 0 8 0;3=3,5=1
P 3.315 3.76 12 P 0 8 0;3=3,5=1
P 3.26 3.74 12 P 0 8 0;3=3,5=1
S P 0
OB 6.52238996063 2.79276003937 I
OC 6.52238996063 2.7663 6.530516535433 2.779530019685 N
OS 6.52238996063 2.5043
OS 6.520869980315 2.503930019685
OC 6.508619980315 2.498669980315 6.530515846457 2.464571456693 N
OC 6.50246003937 2.502030019685 6.506459251969 2.50203523622 Y
OS 6.50246003937 2.589580019685
OC 6.50246003937 2.630419980315 6.487996751969 2.61 N
OS 6.50246003937 2.826780019685
OC 6.550419980315 2.892969980315 6.572118208661 2.82677746063 Y
OS 6.550419980315 3.925180019685
OS 6.57035 3.925180019685
OS 6.57035 2.876469980315
OC 6.52238996063 2.826780019685 6.572115452756 2.826775885827 N
OS 6.52238996063 2.79276003937
OE
SE
S P 0
OB 6.550419980315 2.3 I
OS 6.550419980315 2.348180019685
OC 6.50246003937 2.414369980315 6.572114665354 2.414369980315 Y
OS 6.50246003937 2.42711003937
OC 6.508619980315 2.430469980315 6.506459251969 2.427104724409 Y
OC 6.520869980315 2.42521003937 6.530515551181 2.464568503937 N
OS 6.52238996063 2.42483996063
OS 6.52238996063 2.414369980315
OC 6.57035 2.364680019685 6.572111220472 2.41437007874 N
OS 6.57035 2.3
OS 6.550419980315 2.3
OE
SE
S P 0
OB 6.550419980315 1.915 I
OS 6.57035 1.915
OS 6.57035 0.919430019685
OC 6.5655 0.915519980315 6.56635019685 0.919428346457 Y
OC 6.56038996063 0.916069980315 6.56038996063 0.892056692913 N
OS 6.560369980315 0.916069980315
OC 6.555269980315 0.915519980315 6.560380807087 0.892049015748 N
OC 6.550419980315 0.919419980315 6.554418996063 0.91942746063 Y
OS 6.550419980315 1.915
OE
SE
S P 0
OB 6.18926003937 0.55193996063 I
OC 6.19116003937 0.549330019685 6.189254232283 0.549939173228 Y
OS 6.19116003937 0.5332
OS 6.189980019685 0.532019980315
OS 3.164369980315 0.532019980315
OS 3.16286003937 0.533530019685
OS 3.16286003937 0.5503
OS 3.1645 0.55193996063
OS 6.18926003937 0.55193996063
OE
SE
S P 0
OB 0.50888996063 4.326 I
OC 0.50698996063 4.32861003937 0.508895767717 4.328000787402 Y
OC 0.50815 4.335969980315 0.48413011811 4.335984448819 N
OS 0.50815 4.335980019685
OC 0.50813996063 4.336580019685 0.484131692913 4.335878248031 N
OS 0.50813996063 4.34548996063
OS 0.50858996063 4.34593996063
OS 6.181769980315 4.34593996063
OS 6.181769980315 4.326
OS 0.50888996063 4.326
OE
SE
S P 0
OB 6.205 0.54133996063 I
OS 6.20551003937 0.54133996063
OS 6.20551003937 0.901569980315
OS 6.570169980315 0.901569980315
OS 6.570169980315 0.54005
OS 6.562419980315 0.5323
OS 6.205 0.5323
OS 6.205 0.54133996063
OE
SE
S P 0
OB 6.20551003937 3.9252 I
OS 6.20551003937 4.33661003937
OS 6.20551003937 4.344919980315
OS 6.564030019685 4.344919980315
OS 6.5698 4.33915
OS 6.5698 3.9252
OS 6.20551003937 3.9252
OE
SE
P 6.56038996 1.81205 11 P 0 8 0;3=11,5=1
P 6.56038996 1.77205 11 P 0 8 0;3=11,5=1
P 6.56038996 1.73205 11 P 0 8 0;3=11,5=1
P 6.56038996 1.69205 11 P 0 8 0;3=11,5=1
P 6.56038996 1.65205 11 P 0 8 0;3=11,5=1
P 6.56038996 1.61205 11 P 0 8 0;3=11,5=1
P 6.56038996 1.57205 11 P 0 8 0;3=11,5=1
P 6.56038996 1.53205 11 P 0 8 0;3=11,5=1
P 6.56038996 1.49205 11 P 0 8 0;3=11,5=1
P 6.56038996 1.45205 11 P 0 8 0;3=11,5=1
P 6.56038996 1.05205 11 P 0 8 0;3=11,5=1
P 6.56038996 1.01205 11 P 0 8 0;3=11,5=1
P 6.56038996 0.97205 11 P 0 8 0;3=11,5=1
P 6.56038996 0.93205 11 P 0 8 0;3=11,5=1
P 6.56038996 0.89205 11 P 0 8 0;3=11,5=1
P 6.56038996 0.85205 11 P 0 8 0;3=11,5=1
P 6.56038996 0.81205 11 P 0 8 0;3=11,5=1
P 6.56038996 0.77205 11 P 0 8 0;3=11,5=1
P 6.56038996 0.73205 11 P 0 8 0;3=11,5=1
P 6.56038996 0.69205 11 P 0 8 0;3=11,5=1
P 6.56038996 0.65205 11 P 0 8 0;3=11,5=1
P 6.56038996 0.61205 11 P 0 8 0;3=11,5=1
P 6.56038996 0.57205 11 P 0 8 0;3=11,5=1
P 6.53401998 0.54196998 11 P 0 8 0;3=11,5=1
P 6.49401998 0.54196998 11 P 0 8 0;3=11,5=1
P 6.29401998 0.54196998 11 P 0 8 0;3=11,5=1
P 6.25401998 0.54196998 11 P 0 8 0;3=11,5=1
P 6.21401998 0.54196998 11 P 0 8 0;3=11,5=1
P 6.17401998 0.54196998 11 P 0 8 0;3=11,5=1
P 6.13401998 0.54196998 11 P 0 8 0;3=11,5=1
P 6.09401998 0.54196998 11 P 0 8 0;3=11,5=1
P 6.05401998 0.54196998 11 P 0 8 0;3=11,5=1
P 6.01401998 0.54196998 11 P 0 8 0;3=11,5=1
P 5.97401998 0.54196998 11 P 0 8 0;3=11,5=1
P 5.93401998 0.54196998 11 P 0 8 0;3=11,5=1
P 5.89401998 0.54196998 11 P 0 8 0;3=11,5=1
P 5.85401998 0.54196998 11 P 0 8 0;3=11,5=1
P 5.81401998 0.54196998 11 P 0 8 0;3=11,5=1
P 5.77401998 0.54196998 11 P 0 8 0;3=11,5=1
P 5.73401998 0.54196998 11 P 0 8 0;3=11,5=1
P 5.69401998 0.54196998 11 P 0 8 0;3=11,5=1
P 5.65401998 0.54196998 11 P 0 8 0;3=11,5=1
P 5.61401998 0.54196998 11 P 0 8 0;3=11,5=1
P 5.57401998 0.54196998 11 P 0 8 0;3=11,5=1
P 5.53401998 0.54196998 11 P 0 8 0;3=11,5=1
P 5.49401998 0.54196998 11 P 0 8 0;3=11,5=1
P 5.45401998 0.54196998 11 P 0 8 0;3=11,5=1
P 5.41401998 0.54196998 11 P 0 8 0;3=11,5=1
P 5.37401998 0.54196998 11 P 0 8 0;3=11,5=1
P 5.33401998 0.54196998 11 P 0 8 0;3=11,5=1
P 5.29401998 0.54196998 11 P 0 8 0;3=11,5=1
P 5.25401998 0.54196998 11 P 0 8 0;3=11,5=1
P 5.21401998 0.54196998 11 P 0 8 0;3=11,5=1
P 5.17401998 0.54196998 11 P 0 8 0;3=11,5=1
P 5.13401998 0.54196998 11 P 0 8 0;3=11,5=1
P 5.09401998 0.54196998 11 P 0 8 0;3=11,5=1
P 5.05401998 0.54196998 11 P 0 8 0;3=11,5=1
P 5.01401998 0.54196998 11 P 0 8 0;3=11,5=1
P 4.97401998 0.54196998 11 P 0 8 0;3=11,5=1
P 4.93401998 0.54196998 11 P 0 8 0;3=11,5=1
P 4.89401998 0.54196998 11 P 0 8 0;3=11,5=1
P 4.85401998 0.54196998 11 P 0 8 0;3=11,5=1
P 4.81401998 0.54196998 11 P 0 8 0;3=11,5=1
P 4.77401998 0.54196998 11 P 0 8 0;3=11,5=1
P 4.73401998 0.54196998 11 P 0 8 0;3=11,5=1
P 4.69401998 0.54196998 11 P 0 8 0;3=11,5=1
P 4.65401998 0.54196998 11 P 0 8 0;3=11,5=1
P 4.61401998 0.54196998 11 P 0 8 0;3=11,5=1
P 4.57401998 0.54196998 11 P 0 8 0;3=11,5=1
P 4.53401998 0.54196998 11 P 0 8 0;3=11,5=1
P 4.49401998 0.54196998 11 P 0 8 0;3=11,5=1
P 4.45401998 0.54196998 11 P 0 8 0;3=11,5=1
P 4.41401998 0.54196998 11 P 0 8 0;3=11,5=1
P 4.37401998 0.54196998 11 P 0 8 0;3=11,5=1
P 4.33401998 0.54196998 11 P 0 8 0;3=11,5=1
P 4.29401998 0.54196998 11 P 0 8 0;3=11,5=1
P 4.25401998 0.54196998 11 P 0 8 0;3=11,5=1
P 4.21401998 0.54196998 11 P 0 8 0;3=11,5=1
P 4.17401998 0.54196998 11 P 0 8 0;3=11,5=1
P 2.80413002 4.33598002 11 P 0 8 0;3=11,5=1
P 2.84413002 4.33598002 11 P 0 8 0;3=11,5=1
P 2.88413002 4.33598002 11 P 0 8 0;3=11,5=1
P 2.92413002 4.33598002 11 P 0 8 0;3=11,5=1
P 2.96413002 4.33598002 11 P 0 8 0;3=11,5=1
P 3.00413002 4.33598002 11 P 0 8 0;3=11,5=1
P 3.04413002 4.33598002 11 P 0 8 0;3=11,5=1
P 3.08413002 4.33598002 11 P 0 8 0;3=11,5=1
P 3.12413002 4.33598002 11 P 0 8 0;3=11,5=1
P 3.16413002 4.33598002 11 P 0 8 0;3=11,5=1
P 3.20413002 4.33598002 11 P 0 8 0;3=11,5=1
P 3.24413002 4.33598002 11 P 0 8 0;3=11,5=1
P 3.28413002 4.33598002 11 P 0 8 0;3=11,5=1
P 3.32413002 4.33598002 11 P 0 8 0;3=11,5=1
P 3.36413002 4.33598002 11 P 0 8 0;3=11,5=1
P 3.40413002 4.33598002 11 P 0 8 0;3=11,5=1
P 3.44413002 4.33598002 11 P 0 8 0;3=11,5=1
P 3.48413002 4.33598002 11 P 0 8 0;3=11,5=1
P 3.52413002 4.33598002 11 P 0 8 0;3=11,5=1
P 3.56413002 4.33598002 11 P 0 8 0;3=11,5=1
P 3.60413002 4.33598002 11 P 0 8 0;3=11,5=1
P 3.64413002 4.33598002 11 P 0 8 0;3=11,5=1
P 3.68413002 4.33598002 11 P 0 8 0;3=11,5=1
P 3.72413002 4.33598002 11 P 0 8 0;3=11,5=1
P 3.76413002 4.33598002 11 P 0 8 0;3=11,5=1
P 3.80413002 4.33598002 11 P 0 8 0;3=11,5=1
P 3.84413002 4.33598002 11 P 0 8 0;3=11,5=1
P 3.88413002 4.33598002 11 P 0 8 0;3=11,5=1
P 3.92413002 4.33598002 11 P 0 8 0;3=11,5=1
P 3.96413002 4.33598002 11 P 0 8 0;3=11,5=1
P 4.00413002 4.33598002 11 P 0 8 0;3=11,5=1
P 4.04413002 4.33598002 11 P 0 8 0;3=11,5=1
P 4.08413002 4.33598002 11 P 0 8 0;3=11,5=1
P 4.12413002 4.33598002 11 P 0 8 0;3=11,5=1
P 4.16413002 4.33598002 11 P 0 8 0;3=11,5=1
P 4.20413002 4.33598002 11 P 0 8 0;3=11,5=1
P 4.24413002 4.33598002 11 P 0 8 0;3=11,5=1
P 4.28413002 4.33598002 11 P 0 8 0;3=11,5=1
P 4.32413002 4.33598002 11 P 0 8 0;3=11,5=1
P 4.36413002 4.33598002 11 P 0 8 0;3=11,5=1
P 4.40413002 4.33598002 11 P 0 8 0;3=11,5=1
P 4.44413002 4.33598002 11 P 0 8 0;3=11,5=1
P 4.48413002 4.33598002 11 P 0 8 0;3=11,5=1
P 4.52413002 4.33598002 11 P 0 8 0;3=11,5=1
P 4.56413002 4.33598002 11 P 0 8 0;3=11,5=1
P 4.60413002 4.33598002 11 P 0 8 0;3=11,5=1
P 4.64413002 4.33598002 11 P 0 8 0;3=11,5=1
P 4.68413002 4.33598002 11 P 0 8 0;3=11,5=1
P 4.72413002 4.33598002 11 P 0 8 0;3=11,5=1
P 4.76413002 4.33598002 11 P 0 8 0;3=11,5=1
P 4.80413002 4.33598002 11 P 0 8 0;3=11,5=1
P 4.84413002 4.33598002 11 P 0 8 0;3=11,5=1
P 4.88413002 4.33598002 11 P 0 8 0;3=11,5=1
P 4.92413002 4.33598002 11 P 0 8 0;3=11,5=1
P 4.96413002 4.33598002 11 P 0 8 0;3=11,5=1
P 5.00413002 4.33598002 11 P 0 8 0;3=11,5=1
P 5.04413002 4.33598002 11 P 0 8 0;3=11,5=1
P 5.08413002 4.33598002 11 P 0 8 0;3=11,5=1
P 5.12413002 4.33598002 11 P 0 8 0;3=11,5=1
P 5.16413002 4.33598002 11 P 0 8 0;3=11,5=1
P 5.20413002 4.33598002 11 P 0 8 0;3=11,5=1
P 5.24413002 4.33598002 11 P 0 8 0;3=11,5=1
P 5.28413002 4.33598002 11 P 0 8 0;3=11,5=1
P 5.32413002 4.33598002 11 P 0 8 0;3=11,5=1
P 5.36413002 4.33598002 11 P 0 8 0;3=11,5=1
P 5.40413002 4.33598002 11 P 0 8 0;3=11,5=1
P 5.44413002 4.33598002 11 P 0 8 0;3=11,5=1
P 5.48413002 4.33598002 11 P 0 8 0;3=11,5=1
P 5.52413002 4.33598002 11 P 0 8 0;3=11,5=1
P 5.56413002 4.33598002 11 P 0 8 0;3=11,5=1
P 5.60413002 4.33598002 11 P 0 8 0;3=11,5=1
P 5.64413002 4.33598002 11 P 0 8 0;3=11,5=1
P 5.68413002 4.33598002 11 P 0 8 0;3=11,5=1
P 5.72413002 4.33598002 11 P 0 8 0;3=11,5=1
P 5.76413002 4.33598002 11 P 0 8 0;3=11,5=1
P 5.80413002 4.33598002 11 P 0 8 0;3=11,5=1
P 5.84413002 4.33598002 11 P 0 8 0;3=11,5=1
P 5.88413002 4.33598002 11 P 0 8 0;3=11,5=1
P 5.92413002 4.33598002 11 P 0 8 0;3=11,5=1
P 5.96413002 4.33598002 11 P 0 8 0;3=11,5=1
P 6.00413002 4.33598002 11 P 0 8 0;3=11,5=1
P 6.04413002 4.33598002 11 P 0 8 0;3=11,5=1
P 6.08413002 4.33598002 11 P 0 8 0;3=11,5=1
P 6.12413002 4.33598002 11 P 0 8 0;3=11,5=1
P 6.16413002 4.33598002 11 P 0 8 0;3=11,5=1
P 6.20413002 4.33598002 11 P 0 8 0;3=11,5=1
P 6.24413002 4.33598002 11 P 0 8 0;3=11,5=1
P 6.28413002 4.33598002 11 P 0 8 0;3=11,5=1
P 6.32413002 4.33598002 11 P 0 8 0;3=11,5=1
P 6.36413002 4.33598002 11 P 0 8 0;3=11,5=1
P 6.40413002 4.33598002 11 P 0 8 0;3=11,5=1
P 6.44413002 4.33598002 11 P 0 8 0;3=11,5=1
P 6.48413002 4.33598002 11 P 0 8 0;3=11,5=1
P 6.52413002 4.33598002 11 P 0 8 0;3=11,5=1
P 6.56038996 4.31908996 11 P 0 8 0;3=11,5=1
P 6.56038996 4.27908996 11 P 0 8 0;3=11,5=1
P 6.56038996 4.23908996 11 P 0 8 0;3=11,5=1
P 6.56038996 4.19908996 11 P 0 8 0;3=11,5=1
P 6.56038996 4.15908996 11 P 0 8 0;3=11,5=1
P 6.56038996 4.11908996 11 P 0 8 0;3=11,5=1
P 6.56038996 4.07908996 11 P 0 8 0;3=11,5=1
P 6.56038996 4.03908996 11 P 0 8 0;3=11,5=1
P 6.56038996 3.99908996 11 P 0 8 0;3=11,5=1
P 6.56038996 3.95908996 11 P 0 8 0;3=11,5=1
P 6.56038996 3.91908996 11 P 0 8 0;3=11,5=1
P 6.56038996 3.87908996 11 P 0 8 0;3=11,5=1
P 6.56038996 3.83908996 11 P 0 8 0;3=11,5=1
P 6.56038996 3.79908996 11 P 0 8 0;3=11,5=1
P 6.56038996 3.75908996 11 P 0 8 0;3=11,5=1
P 6.56038996 3.71908996 11 P 0 8 0;3=11,5=1
P 6.56038996 3.67908996 11 P 0 8 0;3=11,5=1
P 6.56038996 3.63908996 11 P 0 8 0;3=11,5=1
P 6.56038996 3.59908996 11 P 0 8 0;3=11,5=1
P 6.56038996 3.55908996 11 P 0 8 0;3=11,5=1
P 6.56038996 3.51908996 11 P 0 8 0;3=11,5=1
P 6.56038996 3.47908996 11 P 0 8 0;3=11,5=1
P 6.56038996 3.43908996 11 P 0 8 0;3=11,5=1
P 6.56038996 3.39908996 11 P 0 8 0;3=11,5=1
P 6.56038996 3.35908996 11 P 0 8 0;3=11,5=1
P 6.56038996 3.31908996 11 P 0 8 0;3=11,5=1
P 6.56038996 3.27908996 11 P 0 8 0;3=11,5=1
P 6.56038996 3.23908996 11 P 0 8 0;3=11,5=1
P 6.56038996 3.19908996 11 P 0 8 0;3=11,5=1
P 6.56038996 3.15908996 11 P 0 8 0;3=11,5=1
P 6.56038996 3.11908996 11 P 0 8 0;3=11,5=1
P 6.56038996 2.35585 11 P 0 8 0;3=11,5=1
P 5.772 0.658 32 P 0 8 0;0,3=0,5=0
L 5.772 0.658 5.805 0.658 10 P 0 
P 5.119 2.762 12 P 0 8 0;3=3,5=1
P 5.63341004 0.62101998 12 P 0 8 0;3=3,5=1
P 5.59941004 0.6212 12 P 0 8 0;3=3,5=1
P 2.419 2.388 12 P 0 8 0;3=3,5=1
L 2.419 2.355 2.419 2.388 10 P 0 
P 2.419 2.355 36 P 0 8 0;0,3=0,5=0
L 2.805 2.243 2.79 2.258 10 P 0 
L 2.79 2.258 2.79 2.296 10 P 0 
P 2.79 2.206 32 P 0 8 0;0,3=0,5=0
L 2.79 2.206 2.79 2.2101 10 P 0 
L 2.79 2.2101 2.7701 2.23 10 P 0 
L 2.7701 2.23 2.7526 2.23 10 P 0 
P 2.79 2.296 32 P 0 8 0;0,3=0,5=0
P 2.805 2.243 12 P 0 8 0;3=3,5=1
P 2.7526 2.23 12 P 0 8 0;3=3,5=1
P 4.55511004 1.755 36 P 0 8 0;0,3=0,5=0
P 4.52153996 1.84343996 14 P 0 8 0;0,3=19,5=0
P 4.278 1.003 12 P 0 8 0;3=3,5=1
P 4.32 0.961 32 P 0 8 0;0,3=0,5=0
L 4.32 0.961 4.275 0.961 10 P 0 
P 4.275 0.961 32 P 0 8 0;0,3=0,5=0
P 3.041 2.05 36 P 0 8 0;0,3=0,5=0
P 3.041 2.005 36 P 0 8 0;0,3=0,5=0
P 3.08966998 2.04 12 P 0 8 0;3=3,5=1
P 3.068 1.945 39 P 0 8 0;0,3=12,5=0
L 2.41441004 2.193 2.41441004 2.15 8 P 0 
P 2.41441004 2.15 12 P 0 8 0;3=3,5=1
P 2.41441004 2.193 29 P 0 8 0;0,3=22,5=0
L 3.305 2.915 3.305 2.875 10 P 0 
L 3.305 2.875 3.289 2.859 10 P 0 
L 3.289 2.859 3.245 2.859 10 P 0 
P 2.69 2.15 12 P 0 8 0;3=3,5=1
P 5.83 1.92 12 P 0 8 0;3=3,5=1
P 5.805 1.945 12 P 0 8 0;3=3,5=1
P 5.035 3.854 32 P 0 8 0;0,3=0,5=0
P 5.085 3.854 32 P 0 8 0;0,3=0,5=0
P 5.045 3.76 12 P 0 8 0;3=3,5=1
P 5.05 3.795 12 P 0 8 0;3=3,5=1
P 4.54 3.97 12 P 0 8 0;3=3,5=1
P 4.54 3.935 12 P 0 8 0;3=3,5=1
P 4.614 3.94 36 P 0 8 0;0,3=0,5=0
P 4.614 3.895 36 P 0 8 0;0,3=0,5=0
P 4.62 2.461 32 P 0 8 0;0,3=0,5=0
P 4.62 2.5 12 P 0 8 0;3=3,5=1
P 3.305 2.915 12 P 0 8 0;3=3,5=1
P 3.145 2.765 12 P 0 8 0;3=3,5=1
P 6.105 2.27 12 P 0 8 0;3=3,5=1
P 6.141 2.241 12 P 0 8 0;3=3,5=1
P 2.54 2.174 32 P 0 8 0;0,3=0,5=0
L 2.54 2.174 2.54 2.135 10 P 0 
P 2.54 2.135 12 P 0 8 0;3=3,5=1
P 2.59 2.264 32 P 0 8 0;0,3=0,5=0
L 2.59 2.264 2.59 2.23 10 P 0 
P 2.59 2.23 12 P 0 8 0;3=3,5=1
P 5.825 0.796 32 P 0 8 0;0,3=0,5=0
L 5.825 0.796 5.859 0.796 10 P 0 
P 5.859 0.796 12 P 0 8 0;3=3,5=1
P 5.80643002 0.609 12 P 0 8 0;3=3,5=1
P 5.805 0.658 12 P 0 8 0;3=3,5=1
L 5.404 0.69 5.37 0.69 10 P 0 
P 5.404 0.69 36 P 0 8 0;0,3=0,5=0
P 5.37 0.69 12 P 0 8 0;3=3,5=1
P 5.43956998 0.60543002 12 P 0 8 0;3=3,5=1
P 6.335 1.96873996 12 P 0 8 0;3=3,5=1
L 5.557 0.747 5.557 0.797 10 P 0 
P 5.59 0.888 12 P 0 8 0;3=3,5=1
L 4.933 1.215 4.933 1.263 10 P 0 
P 4.933 1.263 39 P 0 8 0;0,3=12,5=0
P 4.933 1.215 12 P 0 8 0;3=3,5=1
P 4.894 1.263 12 P 0 8 0;3=3,5=1
L 4.76666004 1.38866998 4.79866998 1.38866998 10 P 0 
P 4.79866998 1.38866998 12 P 0 8 0;3=3,5=1
P 5.0395 1.43 12 P 0 8 0;3=3,5=1
L 4.44 2.461 4.485 2.461 10 P 0 
P 4.485 2.461 32 P 0 8 0;0,3=0,5=0
P 4.44 2.5 12 P 0 8 0;3=3,5=1
P 4.965 1.925 12 P 0 8 0;3=3,5=1
P 4.96 2.055 12 P 0 8 0;3=3,5=1
P 5.346 1.52 12 P 0 8 0;3=3,5=1
P 5.346 1.483 12 P 0 8 0;3=3,5=1
P 4.926 1.675 36 P 0 8 0;0,3=0,5=0
L 4.926 1.675 4.96 1.675 10 P 0 
P 4.96 1.675 12 P 0 8 0;3=3,5=1
L 3.99 2.25 3.99 2.3175 10 P 0 
L 3.99 2.3175 3.9825 2.325 10 P 0 
L 3.99 2.21406998 4.02306998 2.21406998 10 P 0 
L 4.02306998 2.21406998 4.024 2.215 10 P 0 
P 4.024 2.215 36 P 0 8 0;0,3=0,5=0
P 3.99 2.25 12 P 0 8 0;3=3,5=1
P 3.9825 2.325 42 P 0 8 0;0,3=21,5=0
P 3.99 2.21406998 12 P 0 8 0;3=3,5=1
P 3.7206 2.13 12 P 0 8 0;3=3,5=1
P 3.6956 2.13 12 P 0 8 0;3=3,5=1
P 3.678 2.23 39 P 0 8 0;0,3=12,5=0
P 4.78 1.98 12 P 0 8 0;3=3,5=1
L 4.75776998 2.00091004 4.75908996 2.00091004 10 P 0 
L 4.75908996 2.00091004 4.78 1.98 10 P 0 
P 4.75776998 2.00091004 14 P 0 8 0;0,3=19,5=0
P 5.557 0.747 32 P 0 8 0;0,3=0,5=0
P 5.6065 0.7045 12 P 0 8 0;3=31,5=1
P 5.602 0.815 12 P 0 8 0;3=3,5=1
P 5.59 0.85 12 P 0 8 0;3=3,5=1
P 5.625 0.746 12 P 0 8 0;3=3,5=1
P 4.22 0.775 12 P 0 8 0;3=3,5=1
P 4.345 0.77 12 P 0 8 0;3=3,5=1
P 4.4843 0.8954 12 P 0 8 0;3=3,5=1
P 4.442 1.005 12 P 0 8 0;3=3,5=1
P 4.31 1.165 12 P 0 8 0;3=3,5=1
P 4.414 0.781 15 P 0 8 0;1,3=1,5=1
P 4.335 1.005 12 P 0 8 0;3=3,5=1
P 4.23 1.005 12 P 0 8 0;3=3,5=1
P 3.12 2.955 12 P 0 8 0;3=3,5=1
P 2.995 2.955 12 P 0 8 0;3=3,5=1
P 2.92 2.9472 12 P 0 8 0;3=3,5=1
P 2.88 2.93 12 P 0 8 0;3=3,5=1
P 2.96 2.913 43 P 0 8 0;0,3=12,5=0
P 3.035 2.913 43 P 0 8 0;0,3=12,5=0
P 3.11 2.913 43 P 0 8 0;0,3=12,5=0
P 2.855 2.886 32 P 0 8 0;0,3=0,5=0
P 2.9 2.886 32 P 0 8 0;0,3=0,5=0
P 3.01 3.12 12 P 0 8 0;3=3,5=1
P 3.662 2.952 43 P 0 8 0;0,3=12,5=0
P 5.121 2.447 12 P 0 8 0;3=3,5=1
P 5.121 2.407 12 P 0 8 0;3=3,5=1
P 5.298 2.23 12 P 0 8 0;3=3,5=1
P 5.332 2.2 15 P 0 8 0;1,3=1,5=1
P 5.369 2.015 12 P 0 8 0;3=3,5=1
P 5.435 2.05 12 P 0 8 0;3=3,5=1
P 5.409 2.015 12 P 0 8 0;3=3,5=1
P 5.071 2.407 12 P 0 8 0;3=3,5=1
P 4.815 1.82016004 12 P 0 8 0;3=3,5=1
P 4.78 1.82111004 32 P 0 8 0;0,3=0,5=0
P 4.44 2.26 12 P 0 8 0;3=3,5=1
P 4.40343002 2.19776998 14 P 0 8 0;0,3=19,5=0
L 4.40343002 2.19776998 4.42566004 2.22 10 P 0 
L 4.42566004 2.22 4.45485 2.22 10 P 0 
P 4.45485 2.22 36 P 0 8 0;0,3=0,5=0
P 3.67 2.41243002 12 P 0 8 0;3=3,5=1
P 3.67 2.32 15 P 0 8 0;1,3=1,5=1
P 3.54975 2.479 12 P 0 8 0;3=3,5=1
P 3.605 2.43 12 P 0 8 0;3=3,5=1
P 3.55 2.425 12 P 0 8 0;3=3,5=1
P 3.415 2.335 12 P 0 8 0;3=3,5=1
P 3.505 2.295 12 P 0 8 0;3=3,5=1
P 3.40953002 2.37 12 P 0 8 0;3=3,5=1
P 3.116 2.524 12 P 0 8 0;3=3,5=1
P 3.12 2.344 12 P 0 8 0;3=3,5=1
P 3.12 2.17 15 P 0 8 0;1,3=1,5=1
P 3.512 1.966 12 P 0 8 0;3=3,5=1
L 4.26563996 2.17806998 4.24596998 2.1584 10 P 0 
L 4.24596998 2.1584 4.24595 2.1584 10 P 0 
P 4.24595 2.1584 14 P 0 8 0;0,3=19,5=0
L 4.6987 1.78436998 4.68753996 1.79553996 10 P 0 
L 4.68753996 1.79553996 4.67903002 1.80403996 10 P 0 
L 4.67903002 1.80403996 4.67903002 1.80406004 10 P 0 
P 4.67903002 1.80406004 14 P 0 8 0;0,3=19,5=0
P 4.67901998 2.1584 14 P 0 8 0;0,3=19,5=0
P 3.8916 2.15838996 14 P 0 8 0;0,3=19,5=0
P 3.93098002 2.07963996 14 P 0 8 0;0,3=19,5=0
P 3.97035 1.92216998 14 P 0 8 0;0,3=19,5=0
L 3.97035 1.92216998 3.95066998 1.94185 10 P 0 
P 4.20658002 1.48908996 14 P 0 8 0;0,3=19,5=0
P 4.20658002 1.44973002 14 P 0 8 0;0,3=19,5=0
L 4.20658002 1.44973002 4.22626998 1.46941998 10 P 0 
P 4.12783002 1.4891 14 P 0 8 0;0,3=19,5=0
P 4.24596004 1.56783996 14 P 0 8 0;0,3=19,5=0
P 4.16721004 1.56783002 14 P 0 8 0;0,3=19,5=0
P 4.309 1.48468996 14 P 0 8 0;0,3=19,5=0
P 4.12783002 1.52846998 14 P 0 8 0;0,3=19,5=0
P 4.16721998 2.04028002 14 P 0 8 0;0,3=19,5=0
P 4.31006004 1.93718002 14 P 0 8 0;0,3=19,5=0
P 4.3 2.029 32 P 0 8 0;0,3=0,5=0
P 4.16721004 2.00091998 14 P 0 8 0;0,3=19,5=0
P 4.0491 1.96155 14 P 0 8 0;0,3=19,5=0
P 4.08846004 1.96153996 14 P 0 8 0;0,3=19,5=0
P 4.20658002 1.88281004 14 P 0 8 0;0,3=19,5=0
P 4.199 1.75 36 P 0 8 0;0,3=0,5=0
L 4.34436998 1.70563996 4.323 1.72701004 10 P 0 
L 4.323 1.72701004 4.323 1.741 10 P 0 
P 4.306 1.795 32 P 0 8 0;0,3=0,5=0
L 4.306 1.795 4.306 1.758 10 P 0 
L 4.306 1.758 4.323 1.741 10 P 0 
P 4.323 1.741 36 P 0 8 0;0,3=0,5=0
P 4.098 1.75 36 P 0 8 0;0,3=0,5=0
P 4.20656998 1.80406004 14 P 0 8 0;0,3=19,5=0
P 4.20656998 1.68595 14 P 0 8 0;0,3=19,5=0
P 4.16721004 1.68596004 14 P 0 8 0;0,3=19,5=0
L 4.16721004 1.68596004 4.1869 1.66626998 10 P 0 
P 4.20658002 1.6072 14 P 0 8 0;0,3=19,5=0
P 4.305 1.591 32 P 0 8 0;0,3=0,5=0
P 4.305 1.649 32 P 0 8 0;0,3=0,5=0
P 4.24595 1.64658996 14 P 0 8 0;0,3=19,5=0
P 4.52153996 1.64656998 14 P 0 8 0;0,3=19,5=0
P 4.60026998 1.68595 14 P 0 8 0;0,3=19,5=0
L 4.60026998 1.68595 4.58058996 1.66626998 10 P 0 
P 4.63963996 1.56783996 14 P 0 8 0;0,3=19,5=0
P 4.60028002 1.56785 14 P 0 8 0;0,3=19,5=0
L 4.60028002 1.56785 4.61996004 1.58753002 10 P 0 
P 4.48218002 1.64658002 14 P 0 8 0;0,3=19,5=0
L 4.50185 1.70563996 4.48218002 1.68596998 10 P 0 
L 4.48218002 1.68596998 4.48218002 1.68595 10 P 0 
P 4.48218002 1.68595 14 P 0 8 0;0,3=19,5=0
P 4.46511004 1.755 36 P 0 8 0;0,3=0,5=0
P 4.63965 1.88281004 14 P 0 8 0;0,3=19,5=0
P 4.4428 1.60721998 14 P 0 8 0;0,3=19,5=0
P 4.40343002 1.64656998 14 P 0 8 0;0,3=19,5=0
P 4.36406004 1.64658996 14 P 0 8 0;0,3=19,5=0
P 4.48216998 1.56783002 14 P 0 8 0;0,3=19,5=0
P 4.52153996 1.41035 14 P 0 8 0;0,3=19,5=0
P 4.5609 1.41035 14 P 0 8 0;0,3=19,5=0
P 4.40343002 1.56783002 14 P 0 8 0;0,3=19,5=0
P 4.40343002 1.37098996 14 P 0 8 0;0,3=19,5=0
P 4.4428 1.41035 14 P 0 8 0;0,3=19,5=0
P 4.36406004 1.52846004 14 P 0 8 0;0,3=19,5=0
P 4.36406004 1.48911004 14 P 0 8 0;0,3=19,5=0
L 4.36406004 1.48911004 4.38373996 1.50878996 10 P 0 
P 4.40341998 1.92216998 14 P 0 8 0;0,3=19,5=0
L 4.40341998 1.92216998 4.38373996 1.94185 10 P 0 
P 4.48216004 2.07965 14 P 0 8 0;0,3=19,5=0
L 4.48216004 2.07965 4.46248002 2.09933002 10 P 0 
P 4.395 3.37891998 11 P 0 8 0;3=11,5=1
P 4.44 4.165 11 P 0 8 0;3=11,5=1
S P 0
OB 3.326 3.965 I
OS 3.337069980315 3.965
OS 3.364 3.965
OS 3.366 3.963
OS 3.366 3.921
OS 3.366 3.917
OS 3.354 3.905
OS 3.243 3.905
OS 3.243 3.96
OS 3.248 3.965
OS 3.326 3.965
OE
SE
P 3.3635 3.947 45 P 0 8 0;0,3=23,5=0
P 2.86151004 3.295 11 P 0 8 0;3=11,5=1
P 3.21898996 3.43 12 P 0 8 0;3=3,5=1
L 3.21898996 3.43 3.256 3.43 9 P 0 
P 3.256 3.43 36 P 0 8 0;0,3=0,5=0
P 4.134 2.936 39 P 0 8 0;0,3=12,5=0
P 4.134 2.855 39 P 0 8 0;0,3=12,5=0
P 3.548 2.898 11 P 0 8 0;3=11,5=1
P 3.621 2.91 12 P 0 8 0;3=3,5=1
P 3.658 2.861 12 P 0 8 0;3=3,5=1
P 3.658 2.911 12 P 0 8 0;3=3,5=1
P 3.623 2.861 12 P 0 8 0;3=3,5=1
P 3.615 2.961 12 P 0 8 0;3=3,5=1
P 3.253 3.917 12 P 0 8 0;3=3,5=1
P 3.253 3.962 12 P 0 8 0;3=3,5=1
P 3.248 4.107 12 P 0 8 0;3=3,5=1
P 3.213 4.167 12 P 0 8 0;3=3,5=1
P 3.248 4.152 12 P 0 8 0;3=3,5=1
P 3.213 4.236 15 P 0 8 0;1,3=1,5=1
P 3.253 3.872 12 P 0 8 0;3=3,5=1
P 4.465 2.895 11 P 0 8 0;3=11,5=1
P 4.093 2.863 12 P 0 8 0;3=3,5=1
P 4.091 2.813 12 P 0 8 0;3=3,5=1
P 4.092 2.917 12 P 0 8 0;3=3,5=1
P 3.78 2.735 12 P 0 8 0;3=3,5=1
P 3.435 2.589 12 P 0 8 0;3=3,5=1
P 3.5485 2.761 11 P 0 8 0;3=11,5=1
P 3.285 2.589 15 P 0 8 0;1,3=1,5=1
P 4.775 2.59 12 P 0 8 0;3=3,5=1
P 4.71 2.592 15 P 0 8 0;1,3=1,5=1
P 4.918 2.777 12 P 0 8 0;3=3,5=1
P 4.925 2.722 12 P 0 8 0;3=3,5=1
L 4.961 2.728 4.931 2.728 9 P 0 
L 4.931 2.728 4.925 2.722 9 P 0 
P 4.961 2.728 32 P 0 8 0;0,3=0,5=0
P 3.106 3.305 11 P 0 8 0;3=11,5=1
L 3.068 3.305 3.106 3.305 10 P 0 
P 3.068 3.305 36 P 0 8 0;0,3=0,5=0
P 3.222 3.25 11 P 0 8 0;3=11,5=1
P 3.975 3.129 12 P 0 8 0;3=3,5=1
P 3.998 2.784 12 P 0 8 0;3=3,5=1
P 3.83 2.932 12 P 0 8 0;3=3,5=1
P 3.78 2.932 12 P 0 8 0;3=3,5=1
P 3.703 2.911 12 P 0 8 0;3=3,5=1
P 3.748 2.911 12 P 0 8 0;3=3,5=1
P 3.933 3.125 12 P 0 8 0;3=3,5=1
L 3.933 3.092 3.933 3.125 9 P 0 
P 3.933 3.092 36 P 0 8 0;0,3=0,5=0
P 3.6 4.024 12 P 0 8 0;3=3,5=1
L 3.6 4.024 3.592 4.032 9 P 0 
L 3.592 4.032 3.564 4.032 9 P 0 
P 3.564 4.032 36 P 0 8 0;0,3=0,5=0
P 3.631 4.228 12 P 0 8 0;3=3,5=1
P 3.60311004 4.0988 12 P 0 8 0;3=3,5=1
P 3.631 4.183 12 P 0 8 0;3=3,5=1
P 3.38 3.15 12 P 0 8 0;3=3,5=1
P 4.43 3.965 11 P 0 8 0;3=11,5=1
L 4.396 3.965 4.43 3.965 10 P 0 
P 4.396 3.965 36 P 0 8 0;0,3=0,5=0
P 4.43 4.015 11 P 0 8 0;3=11,5=1
P 4.714 3.633 12 P 0 8 0;3=3,5=1
P 4.71 3.47 12 P 0 8 0;3=3,5=1
P 4.94093996 4.12008002 24 P 0 8 0;3=34,5=0
P 4.94093996 3.09646004 24 P 0 8 0;3=34,5=0
P 3.8865 2.9265 12 P 0 8 0;3=31,5=1
P 2.55906004 4.12008002 24 P 0 8 0;3=34,5=0
P 2.55906004 3.09646004 24 P 0 8 0;3=34,5=0
P 5.815 2.67 12 P 0 8 0;3=3,5=1
L 5.815 2.67 5.775 2.67 10 P 0 
L 5.775 2.67 5.7425 2.6375 10 P 0 
P 5.7425 2.6375 41 P 0 8 0;0,3=35,5=0
P 5.517 2.563 12 P 0 8 0;3=3,5=1
P 5.49 2.675 12 P 0 8 0;3=3,5=1
P 5.3035 2.5748 12 P 0 8 0;3=3,5=1
P 5.278 2.611 32 P 0 8 0;0,3=0,5=0
P 5.122 2.587 12 P 0 8 0;3=3,5=1
P 5.123 2.544 12 P 0 8 0;3=3,5=1
P 5.121 2.495 12 P 0 8 0;3=3,5=1
P 5.121 2.625 12 P 0 8 0;3=3,5=1
P 5.41346004 3.03506998 12 P 0 8 0;3=3,5=1
P 5.814 2.9225 12 P 0 8 0;3=3,5=1
L 5.7375 2.9225 5.814 2.9225 10 P 0 
P 5.7375 2.9225 41 P 0 8 0;0,3=35,5=0
P 5.25176004 4.11925 12 P 0 8 0;3=3,5=1
P 5.88778996 3.34448996 21 P 0 8 0;3=27,5=0
P 5.88778996 3.50983996 21 P 0 8 0;3=27,5=0
P 5.88778996 3.67518996 21 P 0 8 0;3=27,5=0
S P 0
OB 0.413280019685 0.36811003937 I
OC 0.413280019685 0.36811003937 0.295280019685 0.36811003937 Y
OE
OB 0.370280019685 0.36811003937 H
OC 0.370280019685 0.36811003937 0.295280019685 0.36811003937 N
OE
SE
P 5.64 2.1655 33 P 0 8 0;0,3=23,5=0
S P 0
OB 5.622 2.128 I
OS 5.622 2.139069980315
OS 5.622 2.166
OS 5.624 2.168
OS 5.666 2.168
OS 5.677 2.168
OS 5.679 2.166
OS 5.679 2.127
OS 5.672 2.12
OS 5.626 2.12
OS 5.622 2.124
OS 5.622 2.128
OE
SE
P 5.08 2.454 39 P 0 8 0;0,3=12,5=0
P 5.538 2.402 12 P 0 8 0;3=3,5=1
L 5.538 2.402 5.555 2.385 8 P 0 
L 5.555 2.385 5.555 2.378 8 P 0 
L 5.555 2.378 5.555 2.366 9 P 0 
P 5.555 2.366 32 P 0 8 0;0,3=0,5=0
P 5.666 2.129 11 P 0 8 0;3=11,5=1
P 5.647 2.044 12 P 0 8 0;3=3,5=1
P 5.687 2.043 12 P 0 8 0;3=3,5=1
P 5.732 2.043 12 P 0 8 0;3=3,5=1
P 5.865 2.3 12 P 0 8 0;3=3,5=1
P 6.36 2.16141998 12 P 0 8 0;3=3,5=1
S P 0
OB 6.51838996063 4.17835 I
OC 6.51838996063 4.17835 6.40038996063 4.17835 Y
OE
OB 6.47538996063 4.17835 H
OC 6.47538996063 4.17835 6.40038996063 4.17835 N
OE
SE
P 6.51581998 2.24803996 27 P 0 8 0;3=36,5=0
P 6.51581998 1.97243996 27 P 0 8 0;3=37,5=0
P 6.40951998 2.20866998 17 P 0 8 0;3=38,5=0
P 6.40951998 2.01181004 17 P 0 8 0;3=38,5=0
P 0.06038996 1.38346004 19 P 0 8 0;3=39,5=0
P 0.26038996 1.38346004 19 P 0 8 0;3=39,5=0
P 0.06038996 1.18346004 19 P 0 8 0;3=39,5=0
P 0.26038996 1.18346004 19 P 0 8 0;3=39,5=0
P 0.06038996 0.8126 19 P 0 8 0;3=39,5=0
P 0.26038996 0.8126 19 P 0 8 0;3=39,5=0
P 0.06038996 0.6126 19 P 0 8 0;3=39,5=0
P 0.26038996 0.6126 19 P 0 8 0;3=39,5=0
P 0.06038996 2.5252 19 P 0 8 0;3=39,5=0
P 0.26038996 2.5252 19 P 0 8 0;3=39,5=0
P 0.06038996 2.3252 19 P 0 8 0;3=39,5=0
P 0.26038996 2.3252 19 P 0 8 0;3=39,5=0
P 0.06038996 1.95433002 19 P 0 8 0;3=39,5=0
P 0.26038996 1.95433002 19 P 0 8 0;3=39,5=0
P 0.06038996 1.75433002 19 P 0 8 0;3=39,5=0
P 0.26038996 1.75433002 19 P 0 8 0;3=39,5=0
P 1.26066998 1.84043002 20 P 0 8 0;3=29,5=0
L 5.4525 2.6795 5.4855 2.6795 10 P 0 
L 5.4855 2.6795 5.49 2.675 10 P 0 
P 5.4525 2.6795 32 P 0 8 0;0,3=0,5=0
P 3.256 3.295 36 P 0 8 0;0,3=0,5=0
L 3.256 3.295 3.256 3.25 10 P 0 
L 3.256 3.25 3.222 3.25 10 P 0 
P 3.256 3.25 36 P 0 8 0;0,3=0,5=0
P 4.63966004 1.96153996 14 P 0 8 0;0,3=19,5=0
L 4.63966004 1.96153996 4.63966004 1.92216998 8 P 0 
P 4.63966004 1.92216998 14 P 0 8 0;0,3=19,5=0
P 3.93098002 2.00091004 14 P 0 8 0;0,3=19,5=0
L 3.93098002 2.00091004 3.9219 2.00998996 10 P 0 
L 3.9219 2.00998996 3.9219 2.03121004 10 P 0 
L 3.9219 2.03121004 3.93096998 2.04028002 10 P 0 
P 3.93096998 2.04028002 14 P 0 8 0;0,3=19,5=0
P 4.44 2.461 32 P 0 8 0;0,3=0,5=0
P 4.76666004 1.38866998 14 P 0 8 0;0,3=19,5=0
L 2.69 2.1935 2.69 2.15 10 P 0 
P 2.69 2.1935 31 P 0 8 0;0,3=20,5=0
P 3.245 2.859 32 P 0 8 0;0,3=0,5=0
P 6.421 1.08 36 P 0 8 0;0,3=0,5=0
L 6.421 1.08 6.421 1.02 10 P 0 
P 6.421 0.965 36 P 0 8 0;0,3=0,5=0
L 6.421 0.965 6.421 1.02 10 P 0 
P 6.421 1.02 36 P 0 8 0;0,3=0,5=0
P 0.889 0.71 36 P 0 8 0;0,3=0,5=0
L 0.889 0.71 0.889 0.67 10 P 0 
P 1.038 0.718 36 P 0 8 0;0,3=0,5=0
L 1.7485 3.388 1.667 3.388 10 P 0 
P 1.7485 3.388 47 P 0 8 0;0,3=9,5=0
P 5.96901998 1.90865 32 P 0 8 0;0,3=0,5=0
L 5.96901998 1.90865 5.97703002 1.90063996 10 P 0 
L 5.97703002 1.90063996 5.97703002 1.87 10 P 0 
P 5.762 3.907 36 P 0 8 0;0,3=0,5=0
L 5.762 3.907 5.762 3.857 10 P 0 
P 5.762 3.857 36 P 0 8 0;0,3=0,5=0
P 5.91901998 2.003 15 P 0 8 0;1,3=10,5=1
P 6.06901998 2.004 15 P 0 8 0;1,3=10,5=1
P 3.49 0.825 15 P 0 8 0;1,3=10,5=1
P 2.65966998 0.93443002 20 P 0 8 0;3=29,5=0
L 6.036 2.79 6.095 2.731 3 P 0 
L 6.095 2.731 6.095 2.545 3 P 0 
L 5.33 0.995 5.2573 0.9223 3 P 0 
L 5.2573 0.9223 5.12283002 0.9223 3 P 0 
L 5.12283002 0.9223 5.11553002 0.915 3 P 0 
L 5.11553002 0.915 5.115 0.915 3 P 0 
L 5.115 0.915 4.85 0.65 3 P 0 
L 4.85 0.65 3.75 0.65 3 P 0 
L 3.75 0.65 3.55 0.85 3 P 0 
L 3.55 0.85 3.515 0.85 3 P 0 
L 3.515 0.85 3.49 0.825 3 P 0 
P 6.036 2.79 36 P 0 8 0;0,3=0,5=0
P 6.095 2.545 15 P 0 8 0;1,3=1,5=1
P 5.07 1.885 12 P 0 8 0;3=3,5=1
P 5.33 0.995 11 P 0 8 0;3=11,5=1
P 3.54 0.825 12 P 0 8 0;3=3,5=1
L 5.33 0.95 5.285 0.905 3 P 0 
L 5.285 0.905 5.13 0.905 3 P 0 
L 5.13 0.905 4.855 0.63 3 P 0 
L 4.855 0.63 3.735 0.63 3 P 0 
L 3.735 0.63 3.54 0.825 3 P 0 
L 5.07 1.925 4.97 2.025 3 P 0 
L 4.97 2.025 4.926 2.025 3 P 0 
L 6.04 2.545 6.04 2.55 3 P 0 
L 6.04 2.55 6.036 2.554 3 P 0 
L 6.036 2.554 6.036 2.615 3 P 0 
P 6.04 2.545 15 P 0 8 0;1,3=1,5=1
P 6.036 2.615 36 P 0 8 0;0,3=0,5=0
P 5.07 1.925 12 P 0 8 0;3=3,5=1
P 4.926 2.025 36 P 0 8 0;0,3=0,5=0
P 5.33 0.95 11 P 0 8 0;3=11,5=1
P 2.53966998 0.93443002 20 P 0 8 0;3=29,5=0
L 2.7965 1.945 2.80881998 1.95731998 1 P 0 
A 2.80881998 1.95731998 2.812 1.965 2.80113602 1.965 1 P 0 N
L 2.812 1.965 2.812 1.97538002 1 P 0 
A 2.812 1.97538002 2.81086004 1.97813996 2.80808898 1.97537992 1 P 0 N
L 2.81086004 1.97813996 2.802 1.987 1 P 0 
P 2.7965 1.945 36 P 0 8 0;0,3=0,5=0
P 2.802 1.987 11 P 0 8 0;3=11,5=1
L 2.8385 1.945 2.82788996 1.95561004 1 P 0 
A 2.82788996 1.95561004 2.824 1.965 2.83727815 1.9649999 1 P 0 Y
L 2.824 1.965 2.824 1.97538002 1 P 0 
A 2.824 1.97538002 2.82513996 1.97813996 2.82791102 1.97537992 1 P 0 Y
L 2.82513996 1.97813996 2.834 1.987 1 P 0 
P 2.8385 1.945 36 P 0 8 0;0,3=0,5=0
P 2.834 1.987 11 P 0 8 0;3=11,5=1
L 2.845 1.875 2.83613996 1.86613996 1 P 0 
A 2.83613996 1.86613996 2.83338002 1.865 2.83337992 1.86891102 1 P 0 Y
L 2.83338002 1.865 2.815 1.865 1 P 0 
A 2.815 1.865 2.80646004 1.86853996 2.8149999 1.87707106 1 P 0 Y
L 2.80646004 1.86853996 2.795 1.88 1 P 0 
P 2.795 1.88 32 P 0 8 0;0,3=0,5=0
P 2.845 1.875 11 P 0 8 0;3=11,5=1
L 2.845 1.843 2.83613996 1.85186004 1 P 0 
A 2.83613996 1.85186004 2.83338002 1.853 2.83337992 1.84908898 1 P 0 N
L 2.83338002 1.853 2.815 1.853 1 P 0 
A 2.815 1.853 2.80646004 1.84946004 2.8149999 1.84092894 1 P 0 N
L 2.80646004 1.84946004 2.795 1.838 1 P 0 
P 2.795 1.838 32 P 0 8 0;0,3=0,5=0
P 2.845 1.843 11 P 0 8 0;3=11,5=1
P 2.77866998 0.93443002 20 P 0 8 0;3=29,5=0
P 4.97 1.54 15 P 0 8 0;1,3=4,5=0
L 4.926 1.855 4.9806 1.855 3 P 0 
P 4.926 1.855 36 P 0 8 0;0,3=0,5=0
P 4.9806 1.855 15 P 0 8 0;1,3=1,5=1
P 1.26066998 1.04043002 20 P 0 8 0;3=29,5=0
P 0.724 2.646 15 P 0 8 0;1,3=1,5=1
P 0.758 2.743 15 P 0 8 0;1,3=5,5=1
P 3.235 2.63 15 P 0 8 0;3=4,5=0
P 3.275 2.32 15 P 0 8 0;1,3=5,5=1
P 3.24 2.275 15 P 0 8 0;1,3=1,5=1
P 3.305 2.65 15 P 0 8 0;1,3=4,5=0
P 3.375 2.65 15 P 0 8 0;3=4,5=0
P 3.326 2.466 15 P 0 8 0;1,3=5,5=1
L 3.326 2.466 3.326 2.482 3 P 0 
L 3.326 2.482 3.335 2.491 3 P 0 
L 3.335 2.491 3.335 2.511 3 P 0 
P 3.335 2.511 32 P 0 8 0;0,3=0,5=0
P 2.1481 0.7881 15 P 0 8 0;1,3=10,5=1
L 5.08 1.105 5.08525 1.11025 3 P 0 
L 5.08525 1.11025 5.09188996 1.11025 3 P 0 
L 5.09188996 1.11025 5.11275 1.08938996 3 P 0 
L 5.11275 1.08938996 5.11938996 1.08938996 3 P 0 
L 5.11938996 1.08938996 5.13021998 1.10021998 3 P 0 
L 5.13021998 1.10021998 5.13021998 1.10686004 3 P 0 
L 5.13021998 1.10686004 5.10936004 1.12771998 3 P 0 
L 5.10936004 1.12771998 5.10936004 1.13436004 3 P 0 
L 5.10936004 1.13436004 5.12018996 1.14518996 3 P 0 
L 5.12018996 1.14518996 5.12683002 1.14518996 3 P 0 
L 5.12683002 1.14518996 5.14768996 1.12433002 3 P 0 
L 5.14768996 1.12433002 5.15433002 1.12433002 3 P 0 
L 5.15433002 1.12433002 5.16516004 1.13516004 3 P 0 
L 5.16516004 1.13516004 5.16516004 1.1418 3 P 0 
L 5.16516004 1.1418 5.1443 1.16266004 3 P 0 
L 5.1443 1.16266004 5.1443 1.1693 3 P 0 
L 5.1443 1.1693 5.1555 1.1805 3 P 0 
L 5.1555 1.1805 5.1555 1.22388002 3 P 0 
L 5.1555 1.22388002 5.1602 1.22858002 3 P 0 
L 5.1602 1.22858002 5.2073 1.22858002 3 P 0 
L 5.2073 1.22858002 5.212 1.23328002 3 P 0 
L 5.212 1.23328002 5.212 1.24858002 3 P 0 
L 5.212 1.24858002 5.2073 1.25328002 3 P 0 
L 5.2073 1.25328002 5.1602 1.25328002 3 P 0 
L 5.1602 1.25328002 5.1555 1.25798002 3 P 0 
L 5.1555 1.25798002 5.1555 1.27328002 3 P 0 
L 5.1555 1.27328002 5.1602 1.27798002 3 P 0 
L 5.1602 1.27798002 5.2073 1.27798002 3 P 0 
L 5.2073 1.27798002 5.212 1.28268002 3 P 0 
L 5.212 1.28268002 5.212 1.29798002 3 P 0 
L 5.212 1.29798002 5.2073 1.30268002 3 P 0 
L 5.2073 1.30268002 5.1602 1.30268002 3 P 0 
L 5.1602 1.30268002 5.1555 1.30738002 3 P 0 
L 5.1555 1.30738002 5.1555 1.32268002 3 P 0 
L 5.1555 1.32268002 5.1602 1.32738002 3 P 0 
L 5.1602 1.32738002 5.2073 1.32738002 3 P 0 
L 5.2073 1.32738002 5.212 1.33208002 3 P 0 
L 5.212 1.33208002 5.212 1.34738002 3 P 0 
L 5.212 1.34738002 5.2073 1.35208002 3 P 0 
L 5.2073 1.35208002 5.1602 1.35208002 3 P 0 
L 5.1602 1.35208002 5.1555 1.35678002 3 P 0 
L 5.1555 1.35678002 5.1555 1.36821004 3 P 0 
L 5.1555 1.36821004 5.21028996 1.423 3 P 0 
L 5.21028996 1.423 5.21028996 2.32146004 3 P 0 
L 5.21028996 2.32146004 5.26353996 2.37471004 3 P 0 
L 5.26353996 2.37471004 5.31023996 2.37471004 3 P 0 
L 5.31023996 2.37471004 5.3991 2.46356998 3 P 0 
L 5.3991 2.46356998 5.3991 2.62538002 3 P 0 
L 5.3991 2.62538002 5.35 2.67448002 3 P 0 
L 5.35 2.67448002 5.35 2.825 3 P 0 
L 5.35 2.825 5.395 2.87 3 P 0 
L 5.395 2.87 5.454 2.87 3 P 0 
P 5.08 1.105 12 P 0 8 0;3=3,5=1
P 5.454 2.87 36 P 0 8 0;0,3=0,5=0
L 2.08295 0.525 2.08295 0.56855 3 P 0 
L 2.08295 0.56855 2.1006 0.5862 3 P 0 
L 2.1006 0.5862 2.1006 0.6756 3 P 0 
L 2.1006 0.6756 2.1481 0.7231 3 P 0 
L 2.1481 0.7231 2.1481 0.7881 3 P 0 
P 2.08295 0.525 15 P 0 8 0;1,3=14,5=1
L 2.07283002 0.13781004 2.07283002 0.24216998 3 P 0 
L 2.07283002 0.24216998 2.045 0.27 3 P 0 
L 2.045 0.27 2.045 0.42181998 3 P 0 
L 2.045 0.42181998 2.08295 0.45976998 3 P 0 
L 2.08295 0.45976998 2.08295 0.525 3 P 0 
P 2.07283002 0.13781004 35 P 0 8 0;0,3=30,5=0
L 5.225 1.145 5.23 1.15 3 P 0 
L 5.23 1.15 5.23 2.3167 3 P 0 
L 5.23 2.3167 5.27071004 2.35741004 3 P 0 
L 5.27071004 2.35741004 5.31741004 2.35741004 3 P 0 
L 5.31741004 2.35741004 5.4164 2.4564 3 P 0 
L 5.4164 2.4564 5.4164 2.63255 3 P 0 
L 5.4164 2.63255 5.415 2.63395 3 P 0 
L 5.415 2.63395 5.415 2.63446998 3 P 0 
L 5.415 2.63446998 5.3673 2.68216998 3 P 0 
L 5.3673 2.68216998 5.3673 2.8157 3 P 0 
L 5.3673 2.8157 5.3916 2.84 3 P 0 
L 5.3916 2.84 5.5385 2.84 3 P 0 
L 5.5385 2.84 5.546 2.8325 3 P 0 
L 5.546 2.8325 5.546 2.815 3 P 0 
P 5.225 1.145 12 P 0 8 0;3=3,5=1
P 5.546 2.815 36 P 0 8 0;0,3=0,5=0
P 5.132 0.66 12 P 0 8 0;3=3,5=1
P 2.0816 0.7399 12 P 0 8 0;3=3,5=1
P 2.03346004 0.13781004 35 P 0 8 0;0,3=30,5=0
L 2.0137 0.43 2.0137 0.3337 3 P 0 
L 2.0137 0.3337 1.995 0.315 3 P 0 
L 1.995 0.315 1.995 0.26846004 3 P 0 
L 1.995 0.26846004 2.03346004 0.23 3 P 0 
L 2.03346004 0.23 2.03346004 0.13781004 3 P 0 
P 2.0137 0.43 15 P 0 8 0;1,3=14,5=1
L 2.0816 0.7399 2.0816 0.6592 3 P 0 
L 2.0816 0.6592 2.0506 0.6282 3 P 0 
L 2.0506 0.6282 2.0506 0.4669 3 P 0 
L 2.0506 0.4669 2.0137 0.43 3 P 0 
L 2.03 0.75 1.99468996 0.71468996 3 P 0 
L 1.99468996 0.71468996 1.99468996 0.50968996 3 P 0 
L 1.99468996 0.50968996 1.98 0.495 3 P 0 
P 1.98 0.495 15 P 0 8 0;1,3=14,5=1
L 1.98 0.495 1.96 0.475 3 P 0 
L 1.96 0.475 1.96 0.35048002 3 P 0 
L 1.96 0.35048002 1.97201998 0.33846004 3 P 0 
L 1.97201998 0.33846004 1.97201998 0.26206998 3 P 0 
L 1.97201998 0.26206998 1.99408996 0.24 3 P 0 
L 1.99408996 0.24 1.99408996 0.13781004 3 P 0 
P 1.99408996 0.13781004 35 P 0 8 0;0,3=30,5=0
P 2.03 0.75 15 P 0 8 0;1,3=10,5=1
L 5.546 3.065 5.546 3.0969 3 P 0 
L 5.546 3.0969 5.5296 3.1133 3 P 0 
L 5.5296 3.1133 5.4093 3.1133 3 P 0 
L 5.4093 3.1133 5.338 3.042 3 P 0 
L 5.338 3.042 5.338 2.838 3 P 0 
L 5.338 2.838 5.3 2.8 3 P 0 
L 5.3 2.8 5.3 2.69501004 3 P 0 
L 5.3 2.69501004 5.3818 2.61321004 3 P 0 
L 5.3818 2.61321004 5.3818 2.47073996 3 P 0 
L 5.3818 2.47073996 5.30306998 2.39201004 3 P 0 
L 5.30306998 2.39201004 5.25636998 2.39201004 3 P 0 
L 5.25636998 2.39201004 5.19298996 2.32863002 3 P 0 
L 5.19298996 2.32863002 5.19298996 1.433 3 P 0 
L 5.19298996 1.433 5.1335 1.37351004 3 P 0 
L 5.1335 1.37351004 5.1335 1.2085 3 P 0 
L 5.1335 1.2085 5.08 1.155 3 P 0 
P 5.08 1.155 12 P 0 8 0;3=3,5=1
P 5.546 3.065 36 P 0 8 0;0,3=0,5=0
L 5.546 2.595 5.546 2.5543 3 P 0 
L 5.546 2.5543 5.3267 2.335 3 P 0 
L 5.3267 2.335 5.28 2.335 3 P 0 
L 5.28 2.335 5.25 2.305 3 P 0 
L 5.25 2.305 5.25 1.115 3 P 0 
L 5.25 1.115 5.19 1.055 3 P 0 
L 5.19 1.055 5.08 1.055 3 P 0 
P 5.08 1.055 12 P 0 8 0;3=3,5=1
P 5.546 2.595 36 P 0 8 0;0,3=0,5=0
P 2.0788 0.7874 15 P 0 8 0;1,3=10,5=1
L 2.0788 0.7874 2.0024 0.7874 3 P 0 
L 2.0024 0.7874 1.99731998 0.78231998 3 P 0 
L 1.99731998 0.78231998 1.99731998 0.75161004 3 P 0 
L 1.99731998 0.75161004 1.94468996 0.69898002 3 P 0 
L 1.94468996 0.69898002 1.94468996 0.5862 3 P 0 
L 1.94468996 0.5862 1.91765 0.55916004 3 P 0 
L 1.91765 0.55916004 1.91765 0.46421004 3 P 0 
L 1.91765 0.46421004 1.924 0.45786004 3 P 0 
P 1.924 0.45786004 15 P 0 8 0;1,3=14,5=1
L 1.924 0.45786004 1.9427 0.43916004 3 P 0 
L 1.9427 0.43916004 1.9427 0.3433 3 P 0 
L 1.9427 0.3433 1.95471998 0.33128002 3 P 0 
L 1.95471998 0.33128002 1.95471998 0.13781004 3 P 0 
P 1.95471998 0.13781004 35 P 0 8 0;0,3=30,5=0
L 2.29581998 0.48918002 2.24663996 0.44 3 P 0 
L 2.24663996 0.44 2.23 0.44 3 P 0 
L 2.23 0.44 2.19093996 0.40093996 3 P 0 
L 2.19093996 0.40093996 2.19093996 0.13781004 3 P 0 
P 2.19093996 0.13781004 35 P 0 8 0;0,3=30,5=0
P 2.29581998 0.48918002 15 P 0 8 0;1,3=4,5=0
P 2.633 0.522 11 P 0 8 0;3=11,5=1
P 3.455 0.87 12 P 0 8 0;3=3,5=1
L 4.82 0.835 4.82 0.78 3 P 0 
L 4.82 0.78 4.77803002 0.73803002 3 P 0 
L 4.77803002 0.73803002 4.77803002 0.73138996 3 P 0 
L 4.77803002 0.73138996 4.78458996 0.72483002 3 P 0 
L 4.78458996 0.72483002 4.78458996 0.71818996 3 P 0 
L 4.78458996 0.71818996 4.77376004 0.70736004 3 P 0 
L 4.77376004 0.70736004 4.76711998 0.70736004 3 P 0 
L 4.76711998 0.70736004 4.76056004 0.71391998 3 P 0 
L 4.76056004 0.71391998 4.75391998 0.71391998 3 P 0 
L 4.75391998 0.71391998 4.74308996 0.70308996 3 P 0 
L 4.74308996 0.70308996 4.74308996 0.69645 3 P 0 
L 4.74308996 0.69645 4.7477 0.69183996 3 P 0 
L 4.7477 0.69183996 4.7477 0.6852 3 P 0 
L 4.7477 0.6852 4.73686998 0.67436998 3 P 0 
L 4.73686998 0.67436998 4.73023002 0.67436998 3 P 0 
L 4.73023002 0.67436998 4.72561998 0.67898002 3 P 0 
L 4.72561998 0.67898002 4.71898002 0.67898002 3 P 0 
L 4.71898002 0.67898002 4.71 0.67 3 P 0 
L 4.71 0.67 3.765 0.67 3 P 0 
L 3.765 0.67 3.55 0.885 3 P 0 
L 3.55 0.885 3.47 0.885 3 P 0 
L 3.47 0.885 3.455 0.87 3 P 0 
L 0.8825 1.7725 0.85265 1.80235 3 P 0 
L 0.85265 1.80235 0.82573996 1.80235 3 P 0 
L 0.82573996 1.80235 0.6923 1.66891004 3 P 0 
L 0.6923 1.66891004 0.6923 1.65083002 3 P 0 
L 0.6923 1.65083002 0.676 1.63453002 3 P 0 
L 0.676 1.63453002 0.676 1.599 3 P 0 
P 0.9225 0.9775 12 P 0 8 0;3=3,5=1
P 4.82 0.835 15 P 0 8 0;1,3=1,5=1
P 0.676 1.599 36 P 0 8 0;0,3=0,5=0
P 0.8825 1.7725 12 P 0 8 0;3=3,5=1
P 3.405 0.87 12 P 0 8 0;3=3,5=1
L 4.78 0.78 4.69 0.69 3 P 0 
L 4.69 0.69 3.76998996 0.69 3 P 0 
L 3.76998996 0.69 3.54998996 0.91 3 P 0 
L 3.54998996 0.91 3.445 0.91 3 P 0 
L 3.445 0.91 3.405 0.87 3 P 0 
L 0.91 1.815 0.895 1.83 3 P 0 
L 0.895 1.83 0.82 1.83 3 P 0 
L 0.82 1.83 0.675 1.685 3 P 0 
L 0.675 1.685 0.675 1.658 3 P 0 
L 0.675 1.658 0.64 1.623 3 P 0 
L 0.64 1.623 0.64 1.579 3 P 0 
L 0.64 1.579 0.675 1.544 3 P 0 
P 0.965 0.98 12 P 0 8 0;3=3,5=1
P 0.91 1.815 15 P 0 8 0;1,3=1,5=1
P 0.675 1.544 36 P 0 8 0;0,3=0,5=0
P 4.78 0.78 12 P 0 8 0;3=3,5=1
P 4.4428 1.84343002 14 P 0 8 0;0,3=19,5=0
L 4.4428 1.84343002 4.44278996 1.84343002 5 P 0 
L 4.44278996 1.84343002 4.42311004 1.86311004 5 P 0 
P 4.42311004 1.86311004 11 P 0 8 0;3=25,5=1
P 3.575 1.88648996 36 P 0 8 0;0,3=0,5=0
P 3.65101004 1.88358996 11 P 0 8 0;3=13,5=1
L 3.65101004 1.88358996 3.64826998 1.88633002 5 P 0 
A 3.64826998 1.88633002 3.634 1.89223996 3.634 1.87205719 5 P 0 N
A 3.634 1.89223996 3.61981998 1.89561004 3.6340001 1.92375768 5 P 0 Y
A 3.61981998 1.89561004 3.61673002 1.89761004 3.62757352 1.91097618 5 P 0 Y
A 3.61673002 1.89761004 3.60586004 1.90148996 3.60584596 1.88428406 5 P 0 N
L 3.60586004 1.90148996 3.60523002 1.90148996 5 P 0 
A 3.60523002 1.90148996 3.60171998 1.9016 3.60509636 1.95326358 5 P 0 Y
A 3.60171998 1.9016 3.57973996 1.89121998 3.60520719 1.86575394 5 P 0 N
L 3.57973996 1.89121998 3.575 1.88648996 5 P 0 
P 4.48216998 1.84343002 14 P 0 8 0;0,3=19,5=0
L 4.48216998 1.84343002 4.48216004 1.84343002 5 P 0 
L 4.48216004 1.84343002 4.46248002 1.86311004 5 P 0 
P 4.46248002 1.86311004 11 P 0 8 0;3=25,5=1
P 3.575 1.93148996 36 P 0 8 0;0,3=0,5=0
P 3.65101004 1.91558996 11 P 0 8 0;3=13,5=1
L 3.65101004 1.91558996 3.64826998 1.91285 5 P 0 
A 3.64826998 1.91285 3.62426998 1.91071998 3.63499715 1.92612598 5 P 0 Y
A 3.62426998 1.91071998 3.60586998 1.91648996 3.60587421 1.88428071 5 P 0 N
L 3.60586998 1.91648996 3.60523002 1.91648996 5 P 0 
A 3.60523002 1.91648996 3.57923002 1.92726004 3.60523002 1.95325846 5 P 0 Y
L 3.57923002 1.92726004 3.575 1.93148996 5 P 0 
L 2.98283996 1.75183996 3.00816004 1.75183996 3 P 0 
L 3.00816004 1.75183996 3.065 1.695 3 P 0 
P 3.065 1.695 15 P 0 8 0;1,3=4,5=0
P 2.98283996 1.75183996 12 P 0 8 0;3=3,5=1
P 2.225 3.245 12 P 0 8 0;3=3,5=1
L 0.66 3.056 0.646 3.07 3 P 0 
L 0.646 3.07 0.62 3.07 3 P 0 
P 4.595 2.62 12 P 0 8 0;3=3,5=1
P 4.025 3.08 12 P 0 8 0;3=3,5=1
L 0.66 3.056 0.749 3.056 3 P 0 
L 0.749 3.056 0.77 3.035 3 P 0 
L 0.77 3.035 0.815 3.035 3 P 0 
L 0.815 3.035 0.85 3.07 3 P 0 
L 0.85 3.07 0.915 3.07 3 P 0 
L 0.915 3.07 1.015 2.97 3 P 0 
L 1.015 2.97 1.355 2.97 3 P 0 
L 1.355 2.97 1.41 2.915 3 P 0 
L 1.41 2.915 1.64 2.915 3 P 0 
L 1.64 2.915 1.6904 2.8646 3 P 0 
L 1.6904 2.8646 1.8996 2.8646 3 P 0 
L 1.8996 2.8646 1.97 2.935 3 P 0 
L 1.97 2.935 1.97 3.11356998 3 P 0 
L 1.97 3.11356998 2.04143002 3.185 3 P 0 
L 2.04143002 3.185 2.1953 3.185 3 P 0 
L 2.1953 3.185 2.225 3.2147 3 P 0 
L 2.225 3.2147 2.225 3.245 3 P 0 
P 0.62 3.07 12 P 0 8 0;3=3,5=1
P 0.66 3.056 32 P 0 8 0;0,3=0,5=0
P 5.865 1.125 15 P 0 8 0;1,3=1,5=1
L 2.265 3.34 2.255 3.33 3 P 0 
L 2.255 3.33 2.255 3.215 3 P 0 
L 2.255 3.215 2.204 3.164 3 P 0 
L 2.204 3.164 2.05 3.164 3 P 0 
L 2.05 3.164 1.995 3.109 3 P 0 
L 1.995 3.109 1.995 2.92 3 P 0 
L 1.995 2.92 1.9223 2.8473 3 P 0 
L 1.9223 2.8473 1.6727 2.8473 3 P 0 
L 1.6727 2.8473 1.6258 2.8942 3 P 0 
L 1.6258 2.8942 1.4058 2.8942 3 P 0 
L 1.4058 2.8942 1.3473 2.9527 3 P 0 
L 1.3473 2.9527 0.9273 2.9527 3 P 0 
L 0.9273 2.9527 0.89 2.99 3 P 0 
L 0.89 2.99 0.845 2.99 3 P 0 
L 0.845 2.99 0.795 2.94 3 P 0 
L 0.795 2.94 0.71 2.94 3 P 0 
L 0.71 2.94 0.699 2.951 3 P 0 
L 0.699 2.951 0.699 2.965 3 P 0 
L 0.699 2.965 0.6475 2.965 3 P 0 
L 0.6475 2.965 0.645 2.9675 3 P 0 
P 5.865 1.07 15 P 0 8 0;1,3=1,5=1
L 0.645 2.9675 0.6286 2.9675 3 P 0 
L 0.6286 2.9675 0.5933 3.0028 3 P 0 
L 0.5933 3.0028 0.5505 3.0028 3 P 0 
P 2.265 3.34 12 P 0 8 0;3=3,5=1
P 4.57 2.585 12 P 0 8 0;3=3,5=1
P 4.02 3.03 12 P 0 8 0;3=3,5=1
P 0.645 2.9675 12 P 0 8 0;3=3,5=1
P 0.5505 3.0028 46 P 0 8 0;0,3=18,5=0
P 5.48828996 4.16328996 15 P 0 8 0;1,3=1,5=1
P 3.99005 1.90248002 11 P 0 8 0;3=2,5=1
P 5.55315 4.175 15 P 0 8 0;1,3=1,5=1
P 3.99005 1.86311004 11 P 0 8 0;3=2,5=1
P 5.67126004 4.175 15 P 0 8 0;1,3=1,5=1
P 3.95066998 1.82373996 11 P 0 8 0;3=2,5=1
P 5.78936998 4.175 15 P 0 8 0;1,3=1,5=1
P 3.9113 1.82373996 11 P 0 8 0;3=2,5=1
P 4.205 2.295 15 P 0 8 0;1,3=4,5=0
P 4.65933002 1.6269 15 P 0 8 0;3=4,5=0
P 4.254 2.296 15 P 0 8 0;1,3=4,5=0
P 4.23 2.354 15 P 0 8 0;1,3=4,5=0
P 4.915 1.485 15 P 0 8 0;1,3=4,5=0
P 4.65933002 1.54816004 11 P 0 8 0;3=2,5=1
P 3.94 2.235 15 P 0 8 0;1,3=4,5=0
P 4.85 1.54 15 P 0 8 0;1,3=4,5=0
P 4.149 2.298 15 P 0 8 0;1,3=4,5=0
P 4.161 2.354 15 P 0 8 0;1,3=4,5=0
P 3.75 2.1 15 P 0 8 0;1,3=4,5=0
P 4.975 1.485 15 P 0 8 0;1,3=4,5=0
P 4.58058996 1.58753002 11 P 0 8 0;3=2,5=1
P 3.8 2.1 15 P 0 8 0;1,3=4,5=0
P 4.73806998 1.54816004 15 P 0 8 0;1,3=4,5=0
P 3.9 2.325 15 P 0 8 0;1,3=4,5=0
P 4.73806998 1.50878996 15 P 0 8 0;3=4,5=0
P 3.83 2.325 15 P 0 8 0;1,3=4,5=0
L 0.846 2.489 0.87835 2.52135 3 P 0 
L 0.87835 2.52135 0.90941004 2.52135 3 P 0 
L 0.90941004 2.52135 0.97076004 2.46 3 P 0 
L 0.97076004 2.46 1.79946998 2.46 3 P 0 
L 1.79946998 2.46 2.06721998 2.72775 3 P 0 
L 2.06721998 2.72775 2.27456998 2.72775 3 P 0 
L 2.27456998 2.72775 2.3738 2.82698002 3 P 0 
L 2.3738 2.82698002 2.3738 3.2245 3 P 0 
L 2.3738 3.2245 2.427 3.2777 3 P 0 
L 2.427 3.2777 2.63283002 3.2777 3 P 0 
L 2.63283002 3.2777 2.88553002 3.025 3 P 0 
L 2.88553002 3.025 3.025 3.025 3 P 0 
L 3.025 3.025 3.1 3.1 3 P 0 
L 3.1 3.1 3.18526004 3.1 3 P 0 
L 3.18526004 3.1 3.18996004 3.0953 3 P 0 
L 3.18996004 3.0953 3.18996004 3.0747 3 P 0 
L 3.18996004 3.0747 3.19466004 3.07 3 P 0 
L 3.19466004 3.07 3.20996004 3.07 3 P 0 
L 3.20996004 3.07 3.21466004 3.0747 3 P 0 
L 3.21466004 3.0747 3.21466004 3.0953 3 P 0 
L 3.21466004 3.0953 3.21936004 3.1 3 P 0 
L 3.21936004 3.1 3.245 3.1 3 P 0 
L 3.245 3.1 3.28 3.065 3 P 0 
P 0.846 2.489 15 P 0 8 0;1,3=5,5=1
L 0.846 2.489 0.85 2.485 3 P 0 
L 0.85 2.485 0.85 2.444 3 P 0 
P 0.805 2.444 32 P 0 8 0;0,3=0,5=0
L 0.805 2.444 0.85 2.444 3 P 0 
P 3.28 3.065 12 P 0 8 0;3=3,5=1
P 0.85 2.444 32 P 0 8 0;0,3=0,5=0
L 3.325 3.065 3.27 3.12 3 P 0 
L 3.27 3.12 3.085 3.12 3 P 0 
L 3.085 3.12 3.01 3.045 3 P 0 
L 3.01 3.045 2.89 3.045 3 P 0 
L 2.89 3.045 2.64 3.295 3 P 0 
L 2.64 3.295 2.41983002 3.295 3 P 0 
L 2.41983002 3.295 2.3565 3.23166998 3 P 0 
L 2.3565 3.23166998 2.3565 2.83415 3 P 0 
L 2.3565 2.83415 2.2674 2.74505 3 P 0 
L 2.2674 2.74505 2.06005 2.74505 3 P 0 
L 2.06005 2.74505 1.795 2.48 3 P 0 
L 1.795 2.48 0.97523002 2.48 3 P 0 
L 0.97523002 2.48 0.91658002 2.53865 3 P 0 
L 0.91658002 2.53865 0.84565 2.53865 3 P 0 
L 0.84565 2.53865 0.796 2.489 3 P 0 
P 0.796 2.489 15 P 0 8 0;1,3=5,5=1
L 0.796 2.489 0.768 2.489 3 P 0 
L 0.768 2.489 0.76 2.481 3 P 0 
L 0.76 2.481 0.76 2.444 3 P 0 
P 3.325 3.065 12 P 0 8 0;3=3,5=1
P 0.76 2.444 32 P 0 8 0;0,3=0,5=0
L 0.76 2.444 0.715 2.444 3 P 0 
P 0.715 2.444 32 P 0 8 0;0,3=0,5=0
L 4.985 3.546 5.03 3.546 3 P 0 
P 4.985 3.546 32 P 0 8 0;0,3=0,5=0
P 5.03 3.546 15 P 0 8 0;1,3=5,5=1
P 4.935 3.546 32 P 0 8 0;0,3=0,5=0
L 4.935 3.546 4.935 3.59 3 P 0 
P 4.935 3.59 15 P 0 8 0;1,3=5,5=1
L 4.736 3.551 4.674 3.551 3 P 0 
L 4.674 3.551 4.67 3.555 3 P 0 
P 4.67 3.555 15 P 0 8 0;1,3=4,5=0
P 4.736 3.551 36 P 0 8 0;0,3=0,5=0
L 4.885 3.546 4.885 3.59 3 P 0 
P 4.885 3.546 32 P 0 8 0;0,3=0,5=0
P 4.885 3.59 15 P 0 8 0;1,3=10,5=1
P 4.70461998 3.69461998 15 P 0 8 0;1,3=5,5=1
L 5.395 2.92 5.3975 2.9225 3 P 0 
L 5.3975 2.9225 5.452 2.9225 3 P 0 
P 4.50185 1.82373996 11 P 0 8 0;3=2,5=1
P 5.395 2.92 15 P 0 8 0;1,3=1,5=1
L 5.496 2.87 5.496 2.886 3 P 0 
L 5.496 2.886 5.502 2.892 3 P 0 
L 5.502 2.892 5.502 2.9225 3 P 0 
P 5.496 2.87 36 P 0 8 0;0,3=0,5=0
P 5.502 2.9225 36 P 0 8 0;0,3=0,5=0
P 5.452 2.9225 32 P 0 8 0;0,3=0,5=0
L 5.502 2.9225 5.452 2.9225 3 P 0 
P 5.504 2.815 36 P 0 8 0;0,3=0,5=0
L 5.504 2.815 5.504 2.77 3 P 0 
L 5.504 2.77 5.47763996 2.77 3 P 0 
L 5.47763996 2.77 5.47663996 2.771 3 P 0 
L 5.47663996 2.771 5.452 2.771 3 P 0 
L 5.015 1.925 5.015 1.84 3 P 0 
L 5.015 1.84 4.99765 1.82265 3 P 0 
L 4.99765 1.82265 4.93865 1.82265 3 P 0 
L 4.93865 1.82265 4.926 1.81 3 P 0 
P 4.926 1.81 36 P 0 8 0;0,3=0,5=0
P 5.015 1.925 12 P 0 8 0;3=3,5=1
P 5.452 2.771 32 P 0 8 0;0,3=0,5=0
P 5.504 2.77 36 P 0 8 0;0,3=0,5=0
P 5.39976998 2.75123996 15 P 0 8 0;1,3=10,5=1
L 5.452 2.771 5.41953002 2.771 3 P 0 
L 5.41953002 2.771 5.39976998 2.75123996 3 P 0 
P 5.504 3.065 36 P 0 8 0;0,3=0,5=0
L 5.504 3.065 5.504 3.02 3 P 0 
L 5.504 3.02 5.47763996 3.02 3 P 0 
L 5.47763996 3.02 5.47663996 3.019 3 P 0 
L 5.47663996 3.019 5.452 3.019 3 P 0 
P 4.46248002 1.82373996 11 P 0 8 0;3=2,5=1
L 5.375 2.96606998 5.37606998 2.96606998 3 P 0 
L 5.37606998 2.96606998 5.429 3.019 3 P 0 
L 5.429 3.019 5.452 3.019 3 P 0 
P 5.504 3.02 36 P 0 8 0;0,3=0,5=0
P 5.452 3.019 32 P 0 8 0;0,3=0,5=0
P 5.375 2.96606998 15 P 0 8 0;1,3=10,5=1
L 5.504 2.64 5.455 2.64 3 P 0 
L 5.455 2.64 5.4525 2.6375 3 P 0 
L 5.504 2.64 5.504 2.595 3 P 0 
P 5.504 2.595 36 P 0 8 0;0,3=0,5=0
P 4.58058996 1.78436998 11 P 0 8 0;3=2,5=1
P 5.4525 2.6375 32 P 0 8 0;0,3=0,5=0
L 5.4525 2.6375 5.4525 2.563 3 P 0 
P 5.504 2.64 36 P 0 8 0;0,3=0,5=0
P 5.4525 2.563 15 P 0 8 0;1,3=10,5=1
P 3.545 0.6092 12 P 0 8 0;3=3,5=1
P 1.395 0.625 15 P 0 8 0;1,3=10,5=1
P 5.085 0.645 12 P 0 8 0;3=3,5=1
P 3.495 0.61 12 P 0 8 0;3=3,5=1
P 5.04 0.645 12 P 0 8 0;3=3,5=1
P 1.485 0.625 15 P 0 8 0;1,3=10,5=1
P 2.34841998 0.13781004 35 P 0 8 0;0,3=30,5=0
L 2.34841998 0.13781004 2.34841998 0.23605 1 P 0 
A 2.34841998 0.23605 2.35413996 0.24985 2.36792687 0.23605 1 P 0 Y
L 2.35413996 0.24985 2.35638996 0.2521 1 P 0 
A 2.35638996 0.2521 2.36211004 0.2659 2.34260315 0.2659 1 P 0 N
L 2.36211004 0.2659 2.36211004 0.55681004 1 P 0 
A 2.36211004 0.55681004 2.35638996 0.57061004 2.34260315 0.55680994 1 P 0 N
L 2.35638996 0.57061004 2.3431 0.5839 1 P 0 
P 2.3431 0.5839 32 P 0 8 0;0,3=0,5=0
P 2.38778996 0.13781004 35 P 0 8 0;0,3=30,5=0
L 2.38778996 0.13781004 2.38778996 0.23621998 1 P 0 
A 2.38778996 0.23621998 2.38206998 0.25001998 2.36828317 0.23621998 1 P 0 N
L 2.38206998 0.25001998 2.37983002 0.25226004 1 P 0 
A 2.37983002 0.25226004 2.37411004 0.26606004 2.39361683 0.26605994 1 P 0 Y
L 2.37411004 0.26606004 2.37411004 0.55691998 1 P 0 
A 2.37411004 0.55691998 2.37983002 0.57071998 2.39361683 0.55691998 1 P 0 Y
L 2.37983002 0.57071998 2.39311004 0.584 1 P 0 
P 2.39311004 0.584 32 P 0 8 0;0,3=0,5=0
P 2.97303002 0.584 32 P 0 8 0;0,3=0,5=0
A 2.97303002 0.584 2.99053002 0.54175 2.93077992 0.54175069 5 P 0 Y
L 2.99053002 0.54175 2.99053002 0.53931998 5 P 0 
A 2.99053002 0.53931998 2.99961004 0.51738996 3.02153868 0.53931417 5 P 0 N
L 2.99961004 0.51738996 3.007 0.51 5 P 0 
A 3.007 0.51 3.013 0.49551004 2.99251043 0.49551289 5 P 0 Y
L 3.013 0.49551004 3.013 0.32856998 5 P 0 
A 3.013 0.32856998 3.00638996 0.31261004 2.99043022 0.3285687 5 P 0 Y
L 3.00638996 0.31261004 3.00288996 0.30911004 5 P 0 
A 3.00288996 0.30911004 2.99051998 0.27921998 3.03277116 0.27923898 5 P 0 N
L 2.99051998 0.27921998 2.99051998 0.25021004 5 P 0 
A 2.99051998 0.25021004 2.98886004 0.2442 2.9787813 0.25021791 5 P 0 Y
A 2.98886004 0.2442 2.98708002 0.24191004 2.97877283 0.25020404 5 P 0 Y
L 2.98708002 0.24191004 2.98158002 0.23641004 5 P 0 
A 2.98158002 0.23641004 2.97833996 0.22858996 2.9893999 0.22858878 5 P 0 N
L 2.97833996 0.22858996 2.97833996 0.13781004 5 P 0 
P 2.97833996 0.13781004 35 P 0 8 0;0,3=30,5=0
P 3.02303002 0.584 32 P 0 8 0;0,3=0,5=0
A 3.02303002 0.584 3.00553002 0.54175 3.06528012 0.54175069 5 P 0 N
L 3.00553002 0.54175 3.00553002 0.53931998 5 P 0 
A 3.00553002 0.53931998 3.01021998 0.528 3.02153622 0.53931988 5 P 0 N
L 3.01021998 0.528 3.01761004 0.52061004 5 P 0 
A 3.01761004 0.52061004 3.028 0.4955 2.99250886 0.49551909 5 P 0 Y
L 3.028 0.4955 3.028 0.32858002 5 P 0 
A 3.028 0.32858002 3.017 0.302 2.99042864 0.3285625 5 P 0 Y
L 3.017 0.302 3.0135 0.2985 5 P 0 
A 3.0135 0.2985 3.00551998 0.27923002 3.03276959 0.27923278 5 P 0 N
L 3.00551998 0.27923002 3.00551998 0.24946998 5 P 0 
A 3.00551998 0.24946998 3.00685 0.24448996 3.01546201 0.24945758 5 P 0 N
A 3.00685 0.24448996 3.00843002 0.24243996 3.01544823 0.24948307 5 P 0 N
L 3.00843002 0.24243996 3.01393002 0.23693996 5 P 0 
A 3.01393002 0.23693996 3.01771004 0.22781004 3.0047997 0.2278123 5 P 0 Y
L 3.01771004 0.22781004 3.01771004 0.13781004 5 P 0 
P 3.01771004 0.13781004 35 P 0 8 0;0,3=30,5=0
P 2.80055 0.584 32 P 0 8 0;0,3=0,5=0
A 2.80055 0.584 2.81805 0.54175 2.7582999 0.54175069 5 P 0 Y
L 2.81805 0.54175 2.81805 0.48455 5 P 0 
A 2.81805 0.48455 2.82638996 0.46438996 2.84654124 0.4845313 5 P 0 N
L 2.82638996 0.46438996 2.82686004 0.46391998 5 P 0 
A 2.82686004 0.46391998 2.83303996 0.449 2.81194006 0.4490001 5 P 0 Y
L 2.83303996 0.449 2.83303996 0.24988002 5 P 0 
A 2.83303996 0.24988002 2.83136998 0.24406998 2.82210955 0.24987667 5 P 0 Y
A 2.83136998 0.24406998 2.82983996 0.24215 2.82211083 0.24987884 5 P 0 Y
L 2.82983996 0.24215 2.82383996 0.23615 5 P 0 
A 2.82383996 0.23615 2.82086004 0.22896004 2.83102972 0.22895758 5 P 0 N
L 2.82086004 0.22896004 2.82086004 0.13781004 5 P 0 
P 2.82086004 0.13781004 35 P 0 8 0;0,3=30,5=0
P 2.85055 0.584 32 P 0 8 0;0,3=0,5=0
A 2.85055 0.584 2.83305 0.54175 2.8928001 0.54175069 5 P 0 N
L 2.83305 0.54175 2.83305 0.48453996 5 P 0 
A 2.83305 0.48453996 2.837 0.475 2.84653967 0.4845376 5 P 0 N
L 2.837 0.475 2.83746998 0.47453002 5 P 0 
A 2.83746998 0.47453002 2.84803996 0.44898996 2.81193839 0.4490062 5 P 0 Y
L 2.84803996 0.44898996 2.84803996 0.2498 5 P 0 
A 2.84803996 0.2498 2.84978996 0.24391004 2.85879222 0.24978967 5 P 0 N
A 2.84978996 0.24391004 2.85118996 0.2422 2.85876644 0.24983091 5 P 0 N
L 2.85118996 0.2422 2.85618996 0.2372 5 P 0 
A 2.85618996 0.2372 2.86023002 0.22745 2.84644026 0.22744803 5 P 0 Y
L 2.86023002 0.22745 2.86023002 0.13781004 5 P 0 
P 2.86023002 0.13781004 35 P 0 8 0;0,3=30,5=0
P 2.65806998 0.584 32 P 0 8 0;0,3=0,5=0
A 2.65806998 0.584 2.67556998 0.54175 2.61581988 0.54175069 5 P 0 Y
L 2.67556998 0.54175 2.67556998 0.25023996 5 P 0 
A 2.67556998 0.25023996 2.67378002 0.244 2.66376181 0.25025039 5 P 0 Y
A 2.67378002 0.244 2.67211004 0.24188996 2.66374695 0.2502247 5 P 0 Y
L 2.67211004 0.24188996 2.66661004 0.23638996 5 P 0 
A 2.66661004 0.23638996 2.66338002 0.22858996 2.67441014 0.22859104 5 P 0 N
L 2.66338002 0.22858996 2.66338002 0.13781004 5 P 0 
P 2.66338002 0.13781004 35 P 0 8 0;0,3=30,5=0
P 2.70806998 0.584 32 P 0 8 0;0,3=0,5=0
L 2.70806998 0.584 2.70616004 0.58208996 5 P 0 
A 2.70616004 0.58208996 2.69056998 0.54445 2.7438003 0.54445118 5 P 0 N
L 2.69056998 0.54445 2.69056998 0.25156004 5 P 0 
A 2.69056998 0.25156004 2.6926 0.24401004 2.70556427 0.2515437 5 P 0 N
A 2.6926 0.24401004 2.69496004 0.24096004 2.70554026 0.25158484 5 P 0 N
L 2.69496004 0.24096004 2.69796004 0.23796004 5 P 0 
A 2.69796004 0.23796004 2.70275 0.2264 2.6864003 0.22639774 5 P 0 Y
L 2.70275 0.2264 2.70275 0.13781004 5 P 0 
P 2.70275 0.13781004 35 P 0 8 0;0,3=30,5=0
P 2.46121998 0.584 32 P 0 8 0;0,3=0,5=0
A 2.46121998 0.584 2.47871998 0.54175 2.41896988 0.54175069 5 P 0 Y
L 2.47871998 0.54175 2.47871998 0.50146004 5 P 0 
L 2.47871998 0.50146004 2.47871004 0.50145 5 P 0 
L 2.47871004 0.50145 2.47871004 0.25176004 5 P 0 
A 2.47871004 0.25176004 2.47418002 0.24081998 2.46323976 0.25175797 5 P 0 Y
L 2.47418002 0.24081998 2.47018002 0.23681998 5 P 0 
A 2.47018002 0.23681998 2.46653002 0.22801004 2.47898986 0.22800886 5 P 0 N
L 2.46653002 0.22801004 2.46653002 0.13781004 5 P 0 
P 2.46653002 0.13781004 35 P 0 8 0;0,3=30,5=0
P 2.51121998 0.584 32 P 0 8 0;0,3=0,5=0
A 2.51121998 0.584 2.49371998 0.54175 2.55347008 0.54175069 5 P 0 N
L 2.49371998 0.54175 2.49371998 0.50146004 5 P 0 
L 2.49371998 0.50146004 2.49371004 0.50146998 5 P 0 
L 2.49371004 0.50146998 2.49371004 0.25216998 5 P 0 
A 2.49371004 0.25216998 2.49853002 0.24053002 2.51017028 0.25216801 5 P 0 N
L 2.49853002 0.24053002 2.50153002 0.23753002 5 P 0 
L 2.50153002 0.23753002 2.50153996 0.23751004 5 P 0 
A 2.50153996 0.23751004 2.5059 0.227 2.49103327 0.22699193 5 P 0 Y
L 2.5059 0.227 2.5059 0.13781004 5 P 0 
P 2.5059 0.13781004 35 P 0 8 0;0,3=30,5=0
A 2.95835 0.385 2.93783002 0.3765 2.93782953 0.40551998 5 P 0 Y
L 2.93783002 0.3765 2.917 0.3765 5 P 0 
A 2.917 0.3765 2.897 0.3965 2.917 0.3965 5 P 0 Y
L 2.897 0.3965 2.897 0.41895 5 P 0 
A 2.897 0.41895 2.9015 0.42345 2.9015 0.41895 5 P 0 Y
A 2.9015 0.42345 2.906 0.42795 2.9015 0.42795 5 P 0 N
L 2.906 0.42795 2.906 0.44175 5 P 0 
A 2.906 0.44175 2.9015 0.44625 2.9015 0.44175 5 P 0 N
A 2.9015 0.44625 2.897 0.45075 2.9015 0.45075 5 P 0 Y
L 2.897 0.45075 2.897 0.72068996 5 P 0 
A 2.897 0.72068996 2.905 0.74 2.92431033 0.7206876 5 P 0 Y
A 2.905 0.74 2.914 0.76175 2.88325846 0.76173356 5 P 0 N
L 2.914 0.76175 2.914 0.806 5 P 0 
A 2.914 0.806 2.93011004 0.84488996 2.9690003 0.80599803 5 P 0 Y
L 2.93011004 0.84488996 3.06926998 0.98405 5 P 0 
A 3.06926998 0.98405 3.097 1.05098996 3.00232835 1.05099429 5 P 0 N
L 3.097 1.05098996 3.097 1.21885 5 P 0 
A 3.097 1.21885 3.12311004 1.28188996 3.18614951 1.21885295 5 P 0 Y
L 3.12311004 1.28188996 3.39461004 1.55338996 5 P 0 
A 3.39461004 1.55338996 3.4323 1.569 3.43229744 1.51570039 5 P 0 Y
L 3.4323 1.569 3.79001004 1.569 5 P 0 
A 3.79001004 1.569 3.8156 1.5796 3.79000463 1.60520187 5 P 0 N
L 3.8156 1.5796 3.83271998 1.59671998 5 P 0 
A 3.83271998 1.59671998 3.84001998 1.59975 3.84003445 1.5894063 5 P 0 Y
L 3.84001998 1.59975 3.84816004 1.59975 5 P 0 
L 3.84816004 1.59975 3.84906004 1.59975 0 P 0 
L 3.84906004 1.59975 3.85301004 1.6037 0 P 0 
L 3.85301004 1.6037 3.959 1.6037 0 P 0 
A 3.959 1.6037 3.97391004 1.61861004 3.959 1.61861004 0 P 0 N
L 3.97391004 1.61861004 3.97391004 1.61918996 0 P 0 
A 3.97391004 1.61918996 3.98161998 1.6269 3.98161998 1.61918996 0 P 0 Y
L 3.98161998 1.6269 3.99005 1.6269 0 P 0 
P 3.99005 1.6269 11 P 0 8 0;3=25,5=1
P 2.95835 0.385 11 P 0 8 0;3=13,5=1
A 2.95835 0.353 2.93783002 0.3615 2.93782953 0.33248002 5 P 0 N
L 2.93783002 0.3615 2.917 0.3615 5 P 0 
A 2.917 0.3615 2.882 0.3965 2.917 0.3965 5 P 0 Y
L 2.882 0.3965 2.882 0.7207 5 P 0 
A 2.882 0.7207 2.89438996 0.75061004 2.92431201 0.7206938 5 P 0 Y
A 2.89438996 0.75061004 2.899 0.76173996 2.88326004 0.76173976 5 P 0 N
L 2.899 0.76173996 2.899 0.80601004 5 P 0 
A 2.899 0.80601004 2.9195 0.8555 2.96900187 0.80600423 5 P 0 Y
L 2.9195 0.8555 3.05866004 0.99466004 5 P 0 
A 3.05866004 0.99466004 3.082 1.051 3.00232992 1.05100039 5 P 0 N
L 3.082 1.051 3.082 1.21883996 5 P 0 
A 3.082 1.21883996 3.1125 1.2925 3.18615108 1.21885915 5 P 0 Y
L 3.1125 1.2925 3.384 1.564 5 P 0 
A 3.384 1.564 3.43231004 1.584 3.43229124 1.51569882 5 P 0 Y
L 3.43231004 1.584 3.79 1.584 5 P 0 
A 3.79 1.584 3.80498996 1.59021004 3.78999843 1.6052002 5 P 0 N
L 3.80498996 1.59021004 3.82211004 1.60733002 5 P 0 
A 3.82211004 1.60733002 3.84003002 1.61475 3.84002835 1.58940463 5 P 0 Y
L 3.84003002 1.61475 3.84816004 1.61475 5 P 0 
L 3.84816004 1.61475 3.84906004 1.61475 0 P 0 
L 3.84906004 1.61475 3.85301004 1.6108 0 P 0 
L 3.85301004 1.6108 3.959 1.6108 0 P 0 
A 3.959 1.6108 3.96681004 1.61861004 3.959 1.61861004 0 P 0 N
L 3.96681004 1.61861004 3.96681004 1.61941004 0 P 0 
A 3.96681004 1.61941004 3.95931998 1.6269 3.95931998 1.61941004 0 P 0 N
L 3.95931998 1.6269 3.95066998 1.6269 0 P 0 
P 3.95066998 1.6269 11 P 0 8 0;3=25,5=1
P 2.95835 0.353 11 P 0 8 0;3=13,5=1
A 2.80086998 0.385 2.78305 0.37761998 2.78305167 0.40282018 5 P 0 Y
L 2.78305 0.37761998 2.778 0.37761998 5 P 0 
A 2.778 0.37761998 2.766 0.38961998 2.778 0.38961998 5 P 0 Y
L 2.766 0.38961998 2.766 0.43646998 5 P 0 
A 2.766 0.43646998 2.76935 0.43981998 2.76935 0.43646998 5 P 0 Y
A 2.76935 0.43981998 2.7727 0.44316998 2.76935 0.44316998 5 P 0 N
L 2.7727 0.44316998 2.7727 0.45926998 5 P 0 
A 2.7727 0.45926998 2.76935 0.46261998 2.76935 0.45926998 5 P 0 N
A 2.76935 0.46261998 2.766 0.46596998 2.76935 0.46596998 5 P 0 Y
L 2.766 0.46596998 2.766 0.66678002 5 P 0 
A 2.766 0.66678002 2.76915 0.66993002 2.76915 0.66678002 5 P 0 Y
A 2.76915 0.66993002 2.7723 0.67308002 2.76915 0.67308002 5 P 0 N
L 2.7723 0.67308002 2.7723 0.68958002 5 P 0 
A 2.7723 0.68958002 2.76915 0.69273002 2.76915 0.68958002 5 P 0 N
A 2.76915 0.69273002 2.766 0.69588002 2.76915 0.69588002 5 P 0 Y
L 2.766 0.69588002 2.766 0.769 5 P 0 
A 2.766 0.769 2.793 0.796 2.793 0.769 5 P 0 Y
L 2.793 0.796 2.80301004 0.796 5 P 0 
A 2.80301004 0.796 2.82896998 0.80675 2.80300512 0.83273179 5 P 0 N
L 2.82896998 0.80675 2.98768996 0.96546998 5 P 0 
A 2.98768996 0.96546998 3.014 1.02901004 2.92415846 1.0289936 5 P 0 N
L 3.014 1.02901004 3.014 1.251 5 P 0 
A 3.014 1.251 3.03521004 1.30221998 3.08643258 1.25100738 5 P 0 Y
L 3.03521004 1.30221998 3.329 1.596 5 P 0 
A 3.329 1.596 3.3628 1.61 3.36279931 1.5622001 5 P 0 Y
L 3.3628 1.61 3.75901998 1.61 5 P 0 
A 3.75901998 1.61 3.78618002 1.62126004 3.75901417 1.6483999 5 P 0 N
L 3.78618002 1.62126004 3.79673002 1.63181004 5 P 0 
A 3.79673002 1.63181004 3.81395 1.63895 3.81395571 1.61460069 5 P 0 Y
L 3.81395 1.63895 3.8372 1.63895 5 P 0 
L 3.8372 1.63895 3.8381 1.63895 0 P 0 
L 3.8381 1.63895 3.84205 1.6429 0 P 0 
L 3.84205 1.6429 3.88081004 1.6429 0 P 0 
A 3.88081004 1.6429 3.89053002 1.64691004 3.88082618 1.65664587 0 P 0 N
L 3.89053002 1.64691004 3.89116998 1.64755 0 P 0 
A 3.89116998 1.64755 3.89516998 1.65726004 3.8814253 1.65724311 0 P 0 N
L 3.89516998 1.65726004 3.89516998 1.65926998 0 P 0 
A 3.89516998 1.65926998 3.90216998 1.66626998 3.90216998 1.65926998 0 P 0 Y
L 3.90216998 1.66626998 3.9113 1.66626998 0 P 0 
P 3.9113 1.66626998 11 P 0 8 0;3=25,5=1
P 2.80086998 0.385 11 P 0 8 0;3=13,5=1
L 2.80086998 0.353 2.79708996 0.35678996 5 P 0 
A 2.79708996 0.35678996 2.783 0.36261998 2.78300748 0.34269685 5 P 0 N
L 2.783 0.36261998 2.778 0.36261998 5 P 0 
A 2.778 0.36261998 2.751 0.38961998 2.778 0.38961998 5 P 0 Y
L 2.751 0.38961998 2.751 0.769 5 P 0 
A 2.751 0.769 2.793 0.811 2.793 0.769 5 P 0 Y
L 2.793 0.811 2.803 0.811 5 P 0 
A 2.803 0.811 2.81836004 0.81736004 2.80299902 0.83273012 5 P 0 N
L 2.81836004 0.81736004 2.97708002 0.97608002 5 P 0 
A 2.97708002 0.97608002 2.999 1.029 2.92416004 1.0289997 5 P 0 N
L 2.999 1.029 2.999 1.25098996 5 P 0 
A 2.999 1.25098996 3.0246 1.31283996 3.08643858 1.25102165 5 P 0 Y
L 3.0246 1.31283996 3.03088002 1.31911004 5 P 0 
L 3.03088002 1.31911004 3.03088996 1.31911004 5 P 0 
L 3.03088996 1.31911004 3.31838996 1.60661004 5 P 0 
A 3.31838996 1.60661004 3.36281004 1.625 3.36279311 1.56219852 5 P 0 Y
L 3.36281004 1.625 3.75901004 1.625 5 P 0 
A 3.75901004 1.625 3.77556004 1.63186998 3.759 1.6483939 5 P 0 N
L 3.77556004 1.63186998 3.78611998 1.64241998 5 P 0 
A 3.78611998 1.64241998 3.81393996 1.65395 3.81394961 1.61459911 5 P 0 Y
L 3.81393996 1.65395 3.8372 1.65395 5 P 0 
L 3.8372 1.65395 3.8381 1.65395 0 P 0 
L 3.8381 1.65395 3.84205 1.65 0 P 0 
L 3.84205 1.65 3.88081004 1.65 0 P 0 
A 3.88081004 1.65 3.8855 1.65193996 3.88081004 1.65663907 0 P 0 N
L 3.8855 1.65193996 3.88613002 1.65256998 0 P 0 
A 3.88613002 1.65256998 3.88806998 1.65726004 3.88143091 1.65725984 0 P 0 N
L 3.88806998 1.65726004 3.88806998 1.66266998 0 P 0 
A 3.88806998 1.66266998 3.88446998 1.66626998 3.88446998 1.66266998 0 P 0 N
L 3.88446998 1.66626998 3.87193002 1.66626998 0 P 0 
P 3.87193002 1.66626998 11 P 0 8 0;3=25,5=1
P 2.80086998 0.353 11 P 0 8 0;3=13,5=1
A 2.64338996 0.385 2.62286998 0.3765 2.62286949 0.40551998 5 P 0 Y
L 2.62286998 0.3765 2.611 0.3765 5 P 0 
A 2.611 0.3765 2.594 0.3935 2.611 0.3935 5 P 0 Y
L 2.594 0.3935 2.594 0.4612 5 P 0 
A 2.594 0.4612 2.58 0.495 2.54618839 0.46119577 5 P 0 N
L 2.58 0.495 2.568 0.507 5 P 0 
A 2.568 0.507 2.561 0.5239 2.5849 0.52389961 5 P 0 Y
L 2.561 0.5239 2.561 0.58578996 5 P 0 
A 2.561 0.58578996 2.5656 0.59038996 2.5656 0.58578996 5 P 0 Y
A 2.5656 0.59038996 2.5702 0.59498996 2.5656 0.59498996 5 P 0 N
L 2.5702 0.59498996 2.5702 0.60858996 5 P 0 
A 2.5702 0.60858996 2.5656 0.61318996 2.5656 0.60858996 5 P 0 N
A 2.5656 0.61318996 2.561 0.61778996 2.5656 0.61778996 5 P 0 Y
L 2.561 0.61778996 2.561 0.6963 5 P 0 
A 2.561 0.6963 2.582 0.747 2.6326998 0.69630089 5 P 0 Y
L 2.582 0.747 2.659 0.824 5 P 0 
A 2.659 0.824 2.7097 0.845 2.70969902 0.7733002 5 P 0 Y
L 2.7097 0.845 2.78501004 0.845 5 P 0 
A 2.78501004 0.845 2.82291998 0.8607 2.78500492 0.89863179 5 P 0 N
L 2.82291998 0.8607 2.93811004 0.97588996 5 P 0 
A 2.93811004 0.97588996 2.957 1.02151998 2.89248878 1.02150128 5 P 0 N
L 2.957 1.02151998 2.957 1.274 5 P 0 
A 2.957 1.274 2.97255 1.31155 3.01010984 1.27400118 5 P 0 Y
L 2.97255 1.31155 3.3015 1.6405 5 P 0 
L 3.3015 1.6405 3.3024 1.64138996 5 P 0 
A 3.3024 1.64138996 3.328 1.652 3.32800758 1.61579262 5 P 0 Y
L 3.328 1.652 3.72246998 1.652 5 P 0 
A 3.72246998 1.652 3.7575 1.6665 3.7224875 1.70152136 5 P 0 N
L 3.7575 1.6665 3.75901004 1.66801004 5 P 0 
A 3.75901004 1.66801004 3.78251004 1.67775 3.78252333 1.64449823 5 P 0 Y
L 3.78251004 1.67775 3.84383996 1.67775 5 P 0 
L 3.84383996 1.67775 3.84473996 1.67775 0 P 0 
L 3.84473996 1.67775 3.84868996 1.6817 0 P 0 
L 3.84868996 1.6817 3.95866998 1.6817 0 P 0 
A 3.95866998 1.6817 3.97391004 1.69693996 3.95866998 1.69693996 0 P 0 N
L 3.97391004 1.69693996 3.97391004 1.69793002 0 P 0 
A 3.97391004 1.69793002 3.98161998 1.70563996 3.98161998 1.69793002 0 P 0 Y
L 3.98161998 1.70563996 3.99005 1.70563996 0 P 0 
P 3.99005 1.70563996 11 P 0 8 0;3=25,5=1
P 2.64338996 0.385 11 P 0 8 0;3=13,5=1
A 2.64338996 0.353 2.62286998 0.3615 2.62286949 0.33248002 5 P 0 N
L 2.62286998 0.3615 2.611 0.3615 5 P 0 
A 2.611 0.3615 2.579 0.3935 2.611 0.3935 5 P 0 Y
L 2.579 0.3935 2.579 0.46118996 5 P 0 
A 2.579 0.46118996 2.56938996 0.48438996 2.54618996 0.46118947 5 P 0 N
L 2.56938996 0.48438996 2.55738996 0.49638996 5 P 0 
A 2.55738996 0.49638996 2.546 0.5239 2.58490167 0.5238935 5 P 0 Y
L 2.546 0.5239 2.546 0.69628996 5 P 0 
A 2.546 0.69628996 2.57138996 0.75761004 2.63270148 0.69630709 5 P 0 Y
L 2.57138996 0.75761004 2.64838996 0.83461004 5 P 0 
A 2.64838996 0.83461004 2.70971004 0.86 2.70969282 0.77329852 5 P 0 Y
L 2.70971004 0.86 2.785 0.86 5 P 0 
A 2.785 0.86 2.81231004 0.87131004 2.78499882 0.89863022 5 P 0 N
L 2.81231004 0.87131004 2.9275 0.9865 5 P 0 
A 2.9275 0.9865 2.942 1.02151004 2.89249035 1.02150748 5 P 0 N
L 2.942 1.02151004 2.942 1.27398996 5 P 0 
A 2.942 1.27398996 2.96193996 1.32216004 3.01011142 1.27400738 5 P 0 Y
L 2.96193996 1.32216004 3.29088996 1.65111004 5 P 0 
L 3.29088996 1.65111004 3.29181998 1.65203002 5 P 0 
A 3.29181998 1.65203002 3.32798996 1.667 3.32800138 1.61579094 5 P 0 Y
L 3.32798996 1.667 3.72248002 1.667 5 P 0 
A 3.72248002 1.667 3.74688996 1.67711004 3.7224813 1.70151978 5 P 0 N
L 3.74688996 1.67711004 3.7484 1.67861998 5 P 0 
A 3.7484 1.67861998 3.78251998 1.69275 3.78251713 1.64449665 5 P 0 Y
L 3.78251998 1.69275 3.84383996 1.69275 5 P 0 
L 3.84383996 1.69275 3.84473996 1.69275 0 P 0 
L 3.84473996 1.69275 3.84868996 1.6888 0 P 0 
L 3.84868996 1.6888 3.95866998 1.6888 0 P 0 
A 3.95866998 1.6888 3.96681004 1.69693996 3.95866998 1.69693996 0 P 0 N
L 3.96681004 1.69693996 3.96681004 1.69793002 0 P 0 
A 3.96681004 1.69793002 3.9591 1.70563996 3.9591 1.69793002 0 P 0 N
L 3.9591 1.70563996 3.95066998 1.70563996 0 P 0 
P 3.95066998 1.70563996 11 P 0 8 0;3=25,5=1
P 2.64338996 0.353 11 P 0 8 0;3=13,5=1
L 2.95835 0.481 2.95505 0.4777 5 P 0 
A 2.95505 0.4777 2.9437 0.473 2.9436999 0.48905453 5 P 0 Y
A 2.9437 0.473 2.938 0.4787 2.9437 0.4787 5 P 0 Y
L 2.938 0.4787 2.938 0.707 5 P 0 
A 2.938 0.707 2.93943002 0.71473996 2.95973012 0.7069872 5 P 0 Y
A 2.93943002 0.71473996 2.94253002 0.71953002 2.95217224 0.70989163 5 P 0 Y
L 2.94253002 0.71953002 2.94898002 0.72598002 5 P 0 
A 2.94898002 0.72598002 2.961 0.75501004 2.91997677 0.75499232 5 P 0 N
L 2.961 0.75501004 2.961 0.79 5 P 0 
A 2.961 0.79 2.97726004 0.82926004 3.01653022 0.78999862 5 P 0 Y
L 2.97726004 0.82926004 2.98956998 0.84156998 5 P 0 
A 2.98956998 0.84156998 2.99365 0.84156998 2.99160994 0.83951998 5 P 0 Y
L 2.99365 0.84156998 2.99366998 0.84155 5 P 0 
A 2.99366998 0.84155 2.99775 0.84155 2.99570994 0.8436 5 P 0 N
L 2.99775 0.84155 3.0098 0.8536 5 P 0 
A 3.0098 0.8536 3.0098 0.85768002 3.00775 0.85563996 5 P 0 N
L 3.0098 0.85768002 3.00978002 0.8577 5 P 0 
A 3.00978002 0.8577 3.00978002 0.86178002 3.01183002 0.85973996 5 P 0 Y
L 3.00978002 0.86178002 3.133 0.985 5 P 0 
A 3.133 0.985 3.161 1.05261998 3.06538848 1.05260354 5 P 0 N
L 3.161 1.05261998 3.161 1.21308002 5 P 0 
A 3.161 1.21308002 3.1765 1.2505 3.21392008 1.21307972 5 P 0 Y
L 3.1765 1.2505 3.40415 1.47815 5 P 0 
A 3.40415 1.47815 3.44 1.493 3.44000059 1.4422999 5 P 0 Y
L 3.44 1.493 3.75191004 1.493 5 P 0 
A 3.75191004 1.493 3.80598002 1.5154 3.75190994 1.56945817 5 P 0 N
L 3.80598002 1.5154 3.8403 1.54971998 5 P 0 
L 3.8403 1.54971998 3.84093002 1.55035 0 P 0 
L 3.84093002 1.55035 3.84093002 1.55443996 0 P 0 
A 3.84093002 1.55443996 3.84198002 1.55698002 3.84452717 1.55443996 0 P 0 Y
L 3.84198002 1.55698002 3.84458996 1.55958996 0 P 0 
A 3.84458996 1.55958996 3.857 1.56473002 3.857 1.54717864 0 P 0 Y
L 3.857 1.56473002 3.88066004 1.56473002 0 P 0 
A 3.88066004 1.56473002 3.89516998 1.57923996 3.88066004 1.57923996 0 P 0 N
L 3.89516998 1.57923996 3.89516998 1.57981998 0 P 0 
A 3.89516998 1.57981998 3.90288002 1.58753002 3.90288002 1.57981998 0 P 0 Y
L 3.90288002 1.58753002 3.9113 1.58753002 0 P 0 
P 3.9113 1.58753002 11 P 0 8 0;3=25,5=1
P 2.95835 0.481 11 P 0 8 0;3=13,5=1
P 2.95835 0.449 11 P 0 8 0;3=13,5=1
L 2.95835 0.449 2.95333996 0.454 5 P 0 
A 2.95333996 0.454 2.9437 0.458 2.94369144 0.44436348 5 P 0 N
A 2.9437 0.458 2.923 0.4787 2.9437 0.4787 5 P 0 Y
L 2.923 0.4787 2.923 0.70701004 5 P 0 
A 2.923 0.70701004 2.92541004 0.72008002 2.959731 0.70699419 5 P 0 Y
A 2.92541004 0.72008002 2.93191998 0.73013996 2.95217411 0.70989685 5 P 0 Y
L 2.93191998 0.73013996 2.93836998 0.73658996 5 P 0 
A 2.93836998 0.73658996 2.946 0.755 2.91997835 0.75499843 5 P 0 N
L 2.946 0.755 2.946 0.79001004 5 P 0 
A 2.946 0.79001004 2.96665 0.83986998 3.01653179 0.79000472 5 P 0 Y
L 2.96665 0.83986998 3.12238996 0.99561004 5 P 0 
A 3.12238996 0.99561004 3.146 1.05261004 3.06539006 1.05260974 5 P 0 N
L 3.146 1.05261004 3.146 1.21308996 5 P 0 
A 3.146 1.21308996 3.16588996 1.26111004 3.21392165 1.21308593 5 P 0 Y
L 3.16588996 1.26111004 3.39353996 1.48876004 5 P 0 
A 3.39353996 1.48876004 3.43998996 1.508 3.43999439 1.44229833 5 P 0 Y
L 3.43998996 1.508 3.75191004 1.508 5 P 0 
A 3.75191004 1.508 3.79536998 1.52601004 3.75190413 1.56945571 5 P 0 N
L 3.79536998 1.52601004 3.82968996 1.56033002 5 P 0 
L 3.82968996 1.56033002 3.83031998 1.56096004 0 P 0 
L 3.83031998 1.56096004 3.83441004 1.56096004 0 P 0 
A 3.83441004 1.56096004 3.83695 1.56201004 3.83440994 1.56455719 0 P 0 N
L 3.83695 1.56201004 3.83956004 1.56461998 0 P 0 
A 3.83956004 1.56461998 3.857 1.57183002 3.85698376 1.54717195 0 P 0 Y
L 3.857 1.57183002 3.88066004 1.57183002 0 P 0 
A 3.88066004 1.57183002 3.88806998 1.57923996 3.88066004 1.57923996 0 P 0 N
L 3.88806998 1.57923996 3.88806998 1.58003996 0 P 0 
A 3.88806998 1.58003996 3.88058002 1.58753002 3.88058002 1.58003996 0 P 0 N
L 3.88058002 1.58753002 3.87193002 1.58753002 0 P 0 
P 3.87193002 1.58753002 11 P 0 8 0;3=25,5=1
P 3.125 0.875 11 P 0 8 0;3=13,5=1
A 3.125 0.875 3.11651004 0.85451998 3.09603346 0.87500827 5 P 0 Y
L 3.11651004 0.85451998 3.115 0.853 5 P 0 
L 3.115 0.853 3.0065 0.7445 5 P 0 
A 3.0065 0.7445 2.99053002 0.70591998 3.04507126 0.70593829 5 P 0 N
L 2.99053002 0.70591998 2.99053002 0.66825 5 P 0 
A 2.99053002 0.66825 2.97303002 0.626 2.93077992 0.66824921 5 P 0 Y
P 2.97303002 0.626 32 P 0 8 0;0,3=0,5=0
P 3.99005 1.54816004 11 P 0 8 0;3=25,5=1
P 3.14763002 0.85236998 11 P 0 8 0;3=13,5=1
A 3.14763002 0.85236998 3.12706998 0.84386004 3.14762234 0.82329685 5 P 0 N
L 3.12706998 0.84386004 3.12661004 0.84338996 5 P 0 
L 3.12661004 0.84338996 3.01711004 0.73388996 5 P 0 
A 3.01711004 0.73388996 3.00553002 0.70593002 3.04506969 0.70593199 5 P 0 N
L 3.00553002 0.70593002 3.00553002 0.66825 5 P 0 
A 3.00553002 0.66825 3.02303002 0.626 3.06528012 0.66824921 5 P 0 N
P 3.02303002 0.626 32 P 0 8 0;0,3=0,5=0
P 3.95066998 1.54816004 11 P 0 8 0;3=25,5=1
P 2.81855 0.763 11 P 0 8 0;3=13,5=1
A 2.80055 0.626 2.81805 0.66825 2.7582999 0.66824921 5 P 0 N
L 2.81805 0.66825 2.81805 0.70393002 5 P 0 
A 2.81805 0.70393002 2.8245 0.7195 2.84008189 0.70392402 5 P 0 Y
A 2.8245 0.7195 2.82705 0.72566004 2.81834035 0.72565758 5 P 0 N
L 2.82705 0.72566004 2.82705 0.74248002 5 P 0 
A 2.82705 0.74248002 2.81855 0.763 2.79803002 0.74247953 5 P 0 N
P 2.80055 0.626 32 P 0 8 0;0,3=0,5=0
P 3.9113 1.50878996 11 P 0 8 0;3=25,5=1
P 2.85055 0.763 11 P 0 8 0;3=13,5=1
A 2.85055 0.626 2.83305 0.66825 2.8928001 0.66824921 5 P 0 Y
L 2.83305 0.66825 2.83305 0.70391998 5 P 0 
A 2.83305 0.70391998 2.83511004 0.70888996 2.84008032 0.70391782 5 P 0 Y
A 2.83511004 0.70888996 2.84205 0.72566998 2.81833878 0.72565138 5 P 0 N
L 2.84205 0.72566998 2.84205 0.74248002 5 P 0 
A 2.84205 0.74248002 2.85055 0.763 2.87106998 0.74247953 5 P 0 Y
P 2.85055 0.626 32 P 0 8 0;0,3=0,5=0
P 3.87193002 1.50878996 11 P 0 8 0;3=25,5=1
P 2.66706998 0.763 11 P 0 8 0;3=13,5=1
A 2.65806998 0.626 2.67556998 0.66825 2.61581988 0.66824921 5 P 0 N
L 2.67556998 0.66825 2.67556998 0.74248002 5 P 0 
A 2.67556998 0.74248002 2.66706998 0.763 2.6465501 0.74247953 5 P 0 N
P 2.65806998 0.626 32 P 0 8 0;0,3=0,5=0
P 3.99005 1.46941998 11 P 0 8 0;3=25,5=1
P 2.69906998 0.763 11 P 0 8 0;3=13,5=1
A 2.70806998 0.626 2.69056998 0.66825 2.75032008 0.66824921 5 P 0 Y
L 2.69056998 0.66825 2.69056998 0.74248002 5 P 0 
A 2.69056998 0.74248002 2.69906998 0.763 2.71958996 0.74247953 5 P 0 Y
P 2.70806998 0.626 32 P 0 8 0;0,3=0,5=0
P 3.95066998 1.46941998 11 P 0 8 0;3=25,5=1
P 2.47021998 0.763 11 P 0 8 0;3=13,5=1
A 2.47021998 0.763 2.47871998 0.74248002 2.4497001 0.74247953 5 P 0 Y
L 2.47871998 0.74248002 2.47871998 0.6587 5 P 0 
A 2.47871998 0.6587 2.46796998 0.63275 2.44202067 0.65870128 5 P 0 Y
L 2.46796998 0.63275 2.46121998 0.626 5 P 0 
P 2.46121998 0.626 32 P 0 8 0;0,3=0,5=0
P 3.9113 1.43005 11 P 0 8 0;3=25,5=1
P 2.50221998 0.763 11 P 0 8 0;3=13,5=1
A 2.51121998 0.626 2.49371998 0.66825 2.55347008 0.66824921 5 P 0 Y
L 2.49371998 0.66825 2.49371998 0.74248002 5 P 0 
A 2.49371998 0.74248002 2.50221998 0.763 2.52273996 0.74247953 5 P 0 Y
P 2.51121998 0.626 32 P 0 8 0;0,3=0,5=0
P 3.87193002 1.43005 11 P 0 8 0;3=25,5=1
P 1.889 0.5496 12 P 0 8 0;3=3,5=1
P 2.435 0.4865 15 P 0 8 0;1,3=5,5=1
L 1.8646 0.6022 1.8843 0.6022 3 P 0 
L 1.8843 0.6022 1.889 0.5975 3 P 0 
L 1.889 0.5975 1.889 0.5496 3 P 0 
P 1.8646 0.6022 32 P 0 8 0;0,3=0,5=0
L 1.8646 0.6022 1.8646 0.49156004 3 P 0 
L 1.8646 0.49156004 1.79723996 0.4242 3 P 0 
L 1.79723996 0.4242 1.79723996 0.15731004 3 P 0 
P 1.79723996 0.15731004 34 P 0 8 0;0,3=40,5=0
L 3.461 2.255 3.45935 2.25665 3 P 0 
L 3.45935 2.25665 3.45935 2.2803 3 P 0 
L 3.45935 2.2803 3.45465 2.285 3 P 0 
L 3.45465 2.285 3.40498996 2.285 3 P 0 
L 3.40498996 2.285 3.365 2.32498996 3 P 0 
L 3.365 2.32498996 3.365 2.40761998 3 P 0 
L 3.365 2.40761998 3.38738002 2.43 3 P 0 
L 3.38738002 2.43 3.44466998 2.43 3 P 0 
L 3.44466998 2.43 3.47975 2.46508002 3 P 0 
L 3.47975 2.46508002 3.47975 2.47171998 3 P 0 
L 3.47975 2.47171998 3.42906004 2.52241004 3 P 0 
L 3.42906004 2.52241004 3.42906004 2.52905 3 P 0 
L 3.42906004 2.52905 3.43988996 2.53988002 3 P 0 
L 3.43988996 2.53988002 3.44653002 2.53988002 3 P 0 
L 3.44653002 2.53988002 3.49721998 2.48918996 3 P 0 
L 3.49721998 2.48918996 3.50386004 2.48918996 3 P 0 
L 3.50386004 2.48918996 3.51468996 2.50001998 3 P 0 
L 3.51468996 2.50001998 3.51468996 2.50666004 3 P 0 
L 3.51468996 2.50666004 3.464 2.55735 3 P 0 
L 3.464 2.55735 3.464 2.56398996 3 P 0 
L 3.464 2.56398996 3.47483002 2.57481998 3 P 0 
L 3.47483002 2.57481998 3.48146998 2.57481998 3 P 0 
L 3.48146998 2.57481998 3.53216004 2.52413002 3 P 0 
L 3.53216004 2.52413002 3.5388 2.52413002 3 P 0 
L 3.5388 2.52413002 3.54963002 2.53496004 3 P 0 
L 3.54963002 2.53496004 3.54963002 2.5416 3 P 0 
L 3.54963002 2.5416 3.52893996 2.56228996 3 P 0 
L 3.52893996 2.56228996 3.52893996 2.56893002 3 P 0 
L 3.52893996 2.56893002 3.53976998 2.57976004 3 P 0 
L 3.53976998 2.57976004 3.54641004 2.57976004 3 P 0 
L 3.54641004 2.57976004 3.5671 2.55906998 3 P 0 
L 3.5671 2.55906998 3.57373996 2.55906998 3 P 0 
L 3.57373996 2.55906998 3.6177 2.60303002 3 P 0 
L 3.6177 2.60303002 3.6177 2.65621998 3 P 0 
L 3.6177 2.65621998 3.61035 2.66356998 3 P 0 
L 3.61035 2.66356998 3.61035 2.73508002 3 P 0 
L 3.61035 2.73508002 3.52665 2.81878002 3 P 0 
L 3.52665 2.81878002 3.52665 2.93165 3 P 0 
L 3.52665 2.93165 3.535 2.94 3 P 0 
L 3.535 2.94 3.535 2.998 3 P 0 
L 3.535 2.998 3.56 3.023 3 P 0 
P 3.56 3.023 15 P 0 8 0;1,3=1,5=1
P 3.461 2.255 36 P 0 8 0;0,3=0,5=0
L 3.461 2.255 3.461 2.21 3 P 0 
P 3.461 2.21 36 P 0 8 0;0,3=0,5=0
L 3.329 2.21 3.329 2.18476004 3 P 0 
L 3.329 2.18476004 3.29315 2.14891004 3 P 0 
L 3.29315 2.14891004 3.29315 2.12208996 3 P 0 
L 3.29315 2.12208996 3.31208996 2.10315 3 P 0 
L 3.31208996 2.10315 3.33891004 2.10315 3 P 0 
L 3.33891004 2.10315 3.35441004 2.08765 3 P 0 
L 3.35441004 2.08765 3.45341004 2.08765 3 P 0 
L 3.45341004 2.08765 3.49165 2.12588996 3 P 0 
L 3.49165 2.12588996 3.49165 2.27336004 3 P 0 
L 3.49165 2.27336004 3.46001004 2.305 3 P 0 
L 3.46001004 2.305 3.41 2.305 3 P 0 
L 3.41 2.305 3.385 2.33 3 P 0 
L 3.385 2.33 3.385 2.38 3 P 0 
L 3.385 2.38 3.415 2.41 3 P 0 
L 3.415 2.41 3.44913996 2.41 3 P 0 
L 3.44913996 2.41 3.635 2.59586004 3 P 0 
L 3.635 2.59586004 3.635 2.66338996 3 P 0 
L 3.635 2.66338996 3.62765 2.67073996 3 P 0 
L 3.62765 2.67073996 3.62765 2.74225 3 P 0 
L 3.62765 2.74225 3.57 2.7999 3 P 0 
L 3.57 2.7999 3.57 2.955 3 P 0 
P 3.57 2.955 15 P 0 8 0;1,3=1,5=1
P 3.329 2.21 36 P 0 8 0;0,3=0,5=0
L 3.329 2.21 3.329 2.255 3 P 0 
P 3.329 2.255 36 P 0 8 0;0,3=0,5=0
L 4.975 2.14 5.0223 2.0927 3 P 0 
L 5.0223 2.0927 5.0223 2.05663996 3 P 0 
L 5.0223 2.05663996 5.1346 1.94433996 3 P 0 
L 5.1346 1.94433996 5.1346 1.77013002 3 P 0 
L 5.1346 1.77013002 5.115 1.75053002 3 P 0 
L 5.115 1.75053002 5.115 1.75 3 P 0 
L 5.115 1.75 5.1023 1.7373 3 P 0 
L 5.1023 1.7373 5.1023 1.22001004 3 P 0 
L 5.1023 1.22001004 5.03005 1.14776004 3 P 0 
L 5.03005 1.14776004 5.03005 0.99493996 3 P 0 
P 4.975 2.14 12 P 0 8 0;3=3,5=1
P 5.03005 0.99493996 15 P 0 8 0;1,3=1,5=1
P 3.09645 0.13781004 35 P 0 8 0;0,3=30,5=0
P 2.58463996 0.13781004 35 P 0 8 0;0,3=30,5=0
P 5.638 3.907 15 P 0 8 0;1,3=1,5=1
P 1.8317 0.5639 15 P 0 8 0;1,3=10,5=1
P 5.372 3.963 15 P 0 8 0;1,3=14,5=1
L 3.83799911 -1.28733278 3.8420001 -1.28333356 6 P 0 ;2,4=41,6=0.000000
L 3.8420001 -1.28333356 3.84499951 -1.27666831 6 P 0 ;2,4=41,6=0.000000
L 3.84499951 -1.27666831 3.84700089 -1.26733209 6 P 0 ;2,4=41,6=0.000000
L 3.84700089 -1.26733209 3.84499951 -1.25933386 6 P 0 ;2,4=41,6=0.000000
L 3.84499951 -1.25933386 3.84100039 -1.25400167 6 P 0 ;2,4=41,6=0.000000
L 3.84100039 -1.25400167 3.834 -1.25 6 P 0 ;2,4=41,6=0.000000
L 3.834 -1.25 3.8070003 -1.25 6 P 0 ;2,4=41,6=0.000000
L 3.8070003 -1.25 3.8070003 -1.33 6 P 0 ;2,4=41,6=0.000000
L 3.8070003 -1.33 3.84000059 -1.33 6 P 0 ;2,4=41,6=0.000000
L 3.84000059 -1.33 3.84700089 -1.32466782 6 P 0 ;2,4=41,6=0.000000
L 3.84700089 -1.32466782 3.851 -1.31666713 6 P 0 ;2,4=41,6=0.000000
L 3.851 -1.31666713 3.85299961 -1.30733337 6 P 0 ;2,4=41,6=0.000000
L 3.85299961 -1.30733337 3.851 -1.29800197 6 P 0 ;2,4=41,6=0.000000
L 3.851 -1.29800197 3.84499951 -1.29000128 6 P 0 ;2,4=41,6=0.000000
L 3.84499951 -1.29000128 3.83799911 -1.28733278 6 P 0 ;2,4=41,6=0.000000
L 3.83799911 -1.28733278 3.8070003 -1.28733278 6 P 0 ;2,4=41,6=0.000000
L 3.90999902 -1.33 3.90199892 -1.32866703 6 P 0 ;2,4=41,6=0.000000
L 3.90199892 -1.32866703 3.89500039 -1.32333484 6 P 0 ;2,4=41,6=0.000000
L 3.89500039 -1.32333484 3.8889999 -1.31533406 6 P 0 ;2,4=41,6=0.000000
L 3.8889999 -1.31533406 3.88499892 -1.3060003 6 P 0 ;2,4=41,6=0.000000
L 3.88499892 -1.3060003 3.88299931 -1.29533346 6 P 0 ;2,4=41,6=0.000000
L 3.88299931 -1.29533346 3.88299931 -1.28466663 6 P 0 ;2,4=41,6=0.000000
L 3.88299931 -1.28466663 3.88499892 -1.2739998 6 P 0 ;2,4=41,6=0.000000
L 3.88499892 -1.2739998 3.8889999 -1.26466604 6 P 0 ;2,4=41,6=0.000000
L 3.8889999 -1.26466604 3.89500039 -1.25666772 6 P 0 ;2,4=41,6=0.000000
L 3.89500039 -1.25666772 3.90199892 -1.25133307 6 P 0 ;2,4=41,6=0.000000
L 3.90199892 -1.25133307 3.90999902 -1.25 6 P 0 ;2,4=41,6=0.000000
L 3.90999902 -1.25 3.91799911 -1.25133307 6 P 0 ;2,4=41,6=0.000000
L 3.91799911 -1.25133307 3.92499951 -1.25666772 6 P 0 ;2,4=41,6=0.000000
L 3.92499951 -1.25666772 3.931 -1.26466604 6 P 0 ;2,4=41,6=0.000000
L 3.931 -1.26466604 3.93500098 -1.2739998 6 P 0 ;2,4=41,6=0.000000
L 3.93500098 -1.2739998 3.93700059 -1.28466663 6 P 0 ;2,4=41,6=0.000000
L 3.93700059 -1.28466663 3.93700059 -1.29533346 6 P 0 ;2,4=41,6=0.000000
L 3.93700059 -1.29533346 3.93500098 -1.3060003 6 P 0 ;2,4=41,6=0.000000
L 3.93500098 -1.3060003 3.931 -1.31533406 6 P 0 ;2,4=41,6=0.000000
L 3.931 -1.31533406 3.92499951 -1.32333484 6 P 0 ;2,4=41,6=0.000000
L 3.92499951 -1.32333484 3.91799911 -1.32866703 6 P 0 ;2,4=41,6=0.000000
L 3.91799911 -1.32866703 3.90999902 -1.33 6 P 0 ;2,4=41,6=0.000000
L 3.98999902 -1.25 3.98999902 -1.33 6 P 0 ;2,4=41,6=0.000000
L 3.9670003 -1.25 4.01299961 -1.25 6 P 0 ;2,4=41,6=0.000000
L 4.06999902 -1.25 4.06999902 -1.33 6 P 0 ;2,4=41,6=0.000000
L 4.0470003 -1.25 4.09299961 -1.25 6 P 0 ;2,4=41,6=0.000000
L 4.14999902 -1.33 4.14199892 -1.32866703 6 P 0 ;2,4=41,6=0.000000
L 4.14199892 -1.32866703 4.13500039 -1.32333484 6 P 0 ;2,4=41,6=0.000000
L 4.13500039 -1.32333484 4.1289999 -1.31533406 6 P 0 ;2,4=41,6=0.000000
L 4.1289999 -1.31533406 4.12499892 -1.3060003 6 P 0 ;2,4=41,6=0.000000
L 4.12499892 -1.3060003 4.12299931 -1.29533346 6 P 0 ;2,4=41,6=0.000000
L 4.12299931 -1.29533346 4.12299931 -1.28466663 6 P 0 ;2,4=41,6=0.000000
L 4.12299931 -1.28466663 4.12499892 -1.2739998 6 P 0 ;2,4=41,6=0.000000
L 4.12499892 -1.2739998 4.1289999 -1.26466604 6 P 0 ;2,4=41,6=0.000000
L 4.1289999 -1.26466604 4.13500039 -1.25666772 6 P 0 ;2,4=41,6=0.000000
L 4.13500039 -1.25666772 4.14199892 -1.25133307 6 P 0 ;2,4=41,6=0.000000
L 4.14199892 -1.25133307 4.14999902 -1.25 6 P 0 ;2,4=41,6=0.000000
L 4.14999902 -1.25 4.15799911 -1.25133307 6 P 0 ;2,4=41,6=0.000000
L 4.15799911 -1.25133307 4.16499951 -1.25666772 6 P 0 ;2,4=41,6=0.000000
L 4.16499951 -1.25666772 4.171 -1.26466604 6 P 0 ;2,4=41,6=0.000000
L 4.171 -1.26466604 4.17500098 -1.2739998 6 P 0 ;2,4=41,6=0.000000
L 4.17500098 -1.2739998 4.17700059 -1.28466663 6 P 0 ;2,4=41,6=0.000000
L 4.17700059 -1.28466663 4.17700059 -1.29533346 6 P 0 ;2,4=41,6=0.000000
L 4.17700059 -1.29533346 4.17500098 -1.3060003 6 P 0 ;2,4=41,6=0.000000
L 4.17500098 -1.3060003 4.171 -1.31533406 6 P 0 ;2,4=41,6=0.000000
L 4.171 -1.31533406 4.16499951 -1.32333484 6 P 0 ;2,4=41,6=0.000000
L 4.16499951 -1.32333484 4.15799911 -1.32866703 6 P 0 ;2,4=41,6=0.000000
L 4.15799911 -1.32866703 4.14999902 -1.33 6 P 0 ;2,4=41,6=0.000000
L 4.20399911 -1.33 4.20399911 -1.25 6 P 0 ;2,4=41,6=0.000000
L 4.20399911 -1.25 4.22999902 -1.31666713 6 P 0 ;2,4=41,6=0.000000
L 4.22999902 -1.31666713 4.25600079 -1.25 6 P 0 ;2,4=41,6=0.000000
L 4.25600079 -1.25 4.25600079 -1.33 6 P 0 ;2,4=41,6=0.000000
P 1.105 4.145 16 P 0 8 0;0,3=42,5=0
P 5.78 1.165 16 P 0 8 0;0,3=42,5=0
P 0.95 0.845 16 P 0 8 0;0,3=42,5=0
P 2.68566998 1.12143002 19 P 0 8 0;3=43,5=0
P 2.68566998 2.55943002 19 P 0 8 0;3=43,5=0
P 1.46066998 2.68043002 19 P 0 8 0;3=43,5=0
P 1.43566998 1.06043002 19 P 0 8 0;3=43,5=0
P 6.40038996 0.65353996 23 P 0 8 0;3=44,5=0
P 0.29528002 3.73031004 23 P 0 8 0;3=44,5=0
P 0.29528002 0.36811004 23 P 0 8 0;3=44,5=0
P 6.40038996 4.17835 23 P 0 8 0;3=44,5=0
P 6.34055 3.34448996 22 P 0 8 0;3=45,5=0
P 6.34055 3.67518996 22 P 0 8 0;3=45,5=0
L 3.16 -0.655 3.16 -1.58 8 P 0 ;2
L 1.36 -0.655 1.36 -1.58 8 P 0 ;2
L 1.36 -1.58 5.06 -1.58 8 P 0 ;2
L 5.06 -1.58 5.06 -0.655 8 P 0 ;2
L 5.06 -0.655 1.36 -0.655 8 P 0 ;2
A 1.559 -1.33655 1.559 -1.33655 1.55268002 -1.33655 6 P 0 N;2
A 1.54775 -1.205 1.54775 -1.205 1.53883002 -1.205 6 P 0 N;2
A 1.54763996 -0.99775 1.54763996 -0.99775 1.53871998 -0.99775 6 P 0 N;2
A 1.54063996 -1.10118002 1.54063996 -1.10118002 1.52603996 -1.10118002 6 P 0 N;2
A 1.49695 -1.10118002 1.49695 -1.10118002 1.48656998 -1.10118002 6 P 0 N;2
A 1.45963996 -1.10118002 1.45963996 -1.10118002 1.4533 -1.10118002 6 P 0 N;2
A 1.52135 -0.98681004 1.52135 -0.98681004 1.51503002 -0.98681004 6 P 0 N;2
A 1.79433002 -1.43586998 1.79433002 -1.43586998 1.78798996 -1.43586998 6 P 0 N;2
A 1.79841004 -1.40261004 1.79841004 -1.40261004 1.78798996 -1.40261004 6 P 0 N;2
A 1.80255 -1.36311004 1.80255 -1.36311004 1.78798996 -1.36311004 6 P 0 N;2
A 1.80668996 -1.31528002 1.80668996 -1.31528002 1.78798996 -1.31528002 6 P 0 N;2
A 1.68013002 -1.37456004 1.68013002 -1.37456004 1.67378996 -1.37456004 6 P 0 N;2
A 1.69321998 -1.35033002 1.69321998 -1.35033002 1.6843 -1.35033002 6 P 0 N;2
A 1.7108 -1.31738996 1.7108 -1.31738996 1.69798002 -1.31738996 6 P 0 N;2
A 1.89666998 -1.31511004 1.89666998 -1.31511004 1.88383996 -1.31511004 6 P 0 N;2
A 1.88198996 -1.16876004 1.88198996 -1.16876004 1.85558996 -1.16876004 6 P 0 N;2
A 1.87928002 -1.27801998 1.87928002 -1.27801998 1.86343996 -1.27801998 6 P 0 N;2
A 1.86176998 -1.23075 1.86176998 -1.23075 1.84206004 -1.23075 6 P 0 N;2
A 1.80978996 -1.25916998 1.80978996 -1.25916998 1.78798996 -1.25916998 6 P 0 N;2
A 1.74681004 -1.16876004 1.74681004 -1.16876004 1.72041004 -1.16876004 6 P 0 N;2
A 1.67813002 -1.15513002 1.67813002 -1.15513002 1.65841998 -1.15513002 6 P 0 N;2
A 1.73018002 -1.27816004 1.73018002 -1.27816004 1.71433996 -1.27816004 6 P 0 N;2
A 1.75373002 -1.23081004 1.75373002 -1.23081004 1.73405 -1.23081004 6 P 0 N;2
A 1.65531004 -1.25255 1.65531004 -1.25255 1.63661998 -1.25255 6 P 0 N;2
A 1.69808996 -1.21291998 1.69808996 -1.21291998 1.67628996 -1.21291998 6 P 0 N;2
A 1.81438996 -1.1968 1.81438996 -1.1968 1.78798996 -1.1968 6 P 0 N;2
A 1.6269 -1.1749 1.6269 -1.1749 1.61106004 -1.1749 6 P 0 N;2
A 1.58461004 -1.19126004 1.58461004 -1.19126004 1.57178002 -1.19126004 6 P 0 N;2
A 1.5853 -1.31428002 1.5853 -1.31428002 1.57488996 -1.31428002 6 P 0 N;2
A 1.61735 -1.28638996 1.61735 -1.28638996 1.60276998 -1.28638996 6 P 0 N;2
A 1.88198996 -1.03361004 1.88198996 -1.03361004 1.85558996 -1.03361004 6 P 0 N;2
A 1.71881004 -1.10118002 1.71881004 -1.10118002 1.69238996 -1.10118002 6 P 0 N;2
A 1.65183002 -1.10118002 1.65183002 -1.10118002 1.63003002 -1.10118002 6 P 0 N;2
A 1.67801998 -1.04738996 1.67801998 -1.04738996 1.65831004 -1.04738996 6 P 0 N;2
A 1.74681004 -1.03361004 1.74681004 -1.03361004 1.72041004 -1.03361004 6 P 0 N;2
A 1.69811998 -0.98951004 1.69811998 -0.98951004 1.67631998 -0.98951004 6 P 0 N;2
A 1.81438996 -1.00556004 1.81438996 -1.00556004 1.78798996 -1.00556004 6 P 0 N;2
A 1.59258002 -1.10118002 1.59258002 -1.10118002 1.5739 -1.10118002 6 P 0 N;2
A 1.58451004 -1.01148996 1.58451004 -1.01148996 1.57168002 -1.01148996 6 P 0 N;2
A 1.62681004 -1.02773996 1.62681004 -1.02773996 1.61096998 -1.02773996 6 P 0 N;2
A 1.92148002 -1.21285 1.92148002 -1.21285 1.89968002 -1.21285 6 P 0 N;2
A 1.92148002 -0.98951004 1.92148002 -0.98951004 1.89968002 -0.98951004 6 P 0 N;2
A 1.80978996 -0.9432 1.80978996 -0.9432 1.78798996 -0.9432 6 P 0 N;2
A 1.80668996 -0.88708002 1.80668996 -0.88708002 1.78798996 -0.88708002 6 P 0 N;2
A 1.80255 -0.83923996 1.80255 -0.83923996 1.78798996 -0.83923996 6 P 0 N;2
A 1.8919 -0.88538002 1.8919 -0.88538002 1.87906998 -0.88538002 6 P 0 N;2
A 1.87838996 -0.92456998 1.87838996 -0.92456998 1.86255 -0.92456998 6 P 0 N;2
A 1.65531004 -0.94981004 1.65531004 -0.94981004 1.63661998 -0.94981004 6 P 0 N;2
A 1.73123002 -0.92378002 1.73123002 -0.92378002 1.71538996 -0.92378002 6 P 0 N;2
A 1.71216998 -0.88443996 1.71216998 -0.88443996 1.69935 -0.88443996 6 P 0 N;2
A 1.86225 -0.97178002 1.86225 -0.97178002 1.84253996 -0.97178002 6 P 0 N;2
A 1.75451998 -0.97123996 1.75451998 -0.97123996 1.73483996 -0.97123996 6 P 0 N;2
A 1.61741998 -0.91601004 1.61741998 -0.91601004 1.60283996 -0.91601004 6 P 0 N;2
A 1.5853 -0.88808996 1.5853 -0.88808996 1.57488996 -0.88808996 6 P 0 N;2
A 1.79841004 -0.79975 1.79841004 -0.79975 1.78798996 -0.79975 6 P 0 N;2
A 1.79433002 -0.76648002 1.79433002 -0.76648002 1.78798996 -0.76648002 6 P 0 N;2
A 1.92135 -1.36781004 1.92135 -1.36781004 1.91503996 -1.36781004 6 P 0 N;2
A 1.91096004 -1.34658002 1.91096004 -1.34658002 1.90203996 -1.34658002 6 P 0 N;2
A 2.19078996 -1.1806 2.26591004 -1.16473002 2.21741014 -1.12088169 6 P 0 N;2
A 2.15903002 -1.1402 2.19078996 -1.18061004 2.22093406 -1.12423278 6 P 0 N;2
A 2.05721004 -1.16178996 2.08853002 -1.16658996 2.08281614 -1.09929134 6 P 0 N;2
A 2.00546998 -1.13951998 2.03345 -1.17196004 2.07793927 -1.10530069 6 P 0 N;2
A 2.03346004 -1.17195 2.0847 -1.18461004 2.07891181 -1.09801299 6 P 0 N;2
A 2.0847 -1.18461998 2.14261004 -1.15663002 2.07348435 -1.08751378 6 P 0 N;2
A 2.08853996 -1.16658002 2.13313002 -1.14451998 2.06368967 -1.06025512 6 P 0 N;2
A 1.95808002 -1.25255 1.95808002 -1.25255 1.93938996 -1.25255 6 P 0 N;2
A 1.98775 -1.28635 1.98775 -1.28635 1.97316998 -1.28635 6 P 0 N;2
A 2.27411998 -1.11835 2.15906004 -1.11835 2.21658996 -1.11611998 6 P 0 N;2
L 2.25188002 -1.11418002 2.1807 -1.11418002 6 P 0 ;2
L 2.1807 -1.11418002 2.1807 -1.11398996 6 P 8191 ;2
A 2.25188996 -1.11398996 2.18071004 -1.11398996 2.2163 -1.1124 6 P 0 N;2
A 2.08028996 -1.03428996 2.02048996 -1.08258996 2.0798126 -1.09486801 6 P 0 N;2
A 2.13151998 -1.05146004 2.0803 -1.0343 2.0802999 -1.11932195 6 P 0 N;2
A 2.1315 -1.05146998 2.14175 -1.03951004 2.1356003 -1.04461171 6 P 0 N;2
A 2.14175 -1.03951004 2.08283002 -1.01613002 2.07772461 -1.11492805 6 P 0 N;2
A 2.08283996 -1.01611998 2.00698002 -1.05835 2.08064724 -1.10143169 6 P 0 N;2
L 2.27413002 -1.12868996 2.18073996 -1.12868996 6 P 0 ;2
A 2.18075 -1.12868996 2.19083002 -1.15751998 2.22417795 -1.12968307 6 P 0 N;2
A 2.19083002 -1.15753002 2.25311004 -1.15211004 2.21927195 -1.12381791 6 P 0 N;2
L 2.15903996 -1.1402 2.15903996 -1.11835 6 P 8191 ;2
A 2.02048996 -1.0826 2.05721998 -1.16181004 2.09087933 -1.0980811 6 P 0 N;2
A 2.00698996 -1.05836004 2.00546998 -1.13953002 2.09672953 -1.10063967 6 P 0 N;2
A 2.14258996 -1.15661004 2.13313996 -1.14453002 2.13544892 -1.15246004 6 P 0 N;2
A 1.95808002 -0.94981004 1.95808002 -0.94981004 1.93938996 -0.94981004 6 P 0 N;2
A 1.90183996 -0.8525 1.90183996 -0.8525 1.89291004 -0.8525 6 P 0 N;2
A 1.91108002 -0.82726998 1.91108002 -0.82726998 1.90473996 -0.82726998 6 P 0 N;2
L 2.32081004 -1.02041004 2.32081004 -1.17625 6 P 0 ;2
A 2.49568002 -1.15528996 2.47898002 -1.16443002 2.4882003 -1.1614502 6 P 0 N;2
A 2.47896998 -1.16443996 2.50283002 -1.18086004 2.51649242 -1.13546152 6 P 0 N;2
A 2.50281998 -1.18086998 2.54318002 -1.1834 2.52887392 -1.08843022 6 P 0 N;2
A 2.52306998 -1.16761004 2.52848996 -1.16771998 2.52673258 -1.12070098 6 P 0 N;2
A 2.49566004 -1.15528996 2.52306998 -1.1676 2.5255122 -1.12549094 6 P 0 N;2
A 2.37851998 -1.15753002 2.4408 -1.15211004 2.40696191 -1.12381791 6 P 0 N;2
A 2.45358002 -1.16471998 2.44078996 -1.1521 2.44541191 -1.16020689 6 P 0 N;2
A 2.37848002 -1.1806 2.4536 -1.16473002 2.4051001 -1.12088169 6 P 0 N;2
A 2.34673002 -1.1402 2.37848996 -1.18061004 2.40863406 -1.12423278 6 P 0 N;2
A 2.2659 -1.16471998 2.25311004 -1.1521 2.25773199 -1.16020689 6 P 0 N;2
A 2.3006 -1.17626004 2.3208 -1.17626004 2.3107 -1.17386841 6 P 0 N;2
L 2.30058996 -1.17625 2.30058996 -1.02033996 6 P 0 ;2
A 2.50836998 -1.10106004 2.54306004 -1.11513002 2.56106673 -1.02093386 6 P 0 N;2
A 2.51081004 -1.07948002 2.50836998 -1.10103996 2.51886093 -1.09130915 6 P 0 N;2
A 2.53611004 -1.07688996 2.5108 -1.07948996 2.52742205 -1.11680827 6 P 0 N;2
A 2.56883996 -1.07368002 2.50178002 -1.06358996 2.5273123 -1.12178858 6 P 0 N;2
A 2.50178996 -1.06358996 2.48536998 -1.08248996 2.52926211 -1.10403986 6 P 0 N;2
L 2.48536998 -1.0825 2.48536998 -1.09748002 6 P 8191 ;2
A 2.48536998 -1.09748002 2.49956004 -1.12031004 2.51189104 -1.09682067 6 P 0 N;2
A 2.46181004 -1.11835 2.34675 -1.11835 2.40428002 -1.11611998 6 P 0 N;2
L 2.43956998 -1.11418002 2.36841004 -1.11418002 6 P 0 ;2
L 2.36841004 -1.11418002 2.36841004 -1.11398996 6 P 8191 ;2
A 2.43958002 -1.11398996 2.3684 -1.11398996 2.40398996 -1.1124 6 P 0 N;2
L 2.43956998 -1.11398996 2.43956998 -1.11418002 6 P 8191 ;2
A 2.49955 -1.1203 2.52723002 -1.12985 2.58163209 -0.92727982 6 P 0 N;2
A 2.55001998 -1.14328002 2.52723002 -1.12986004 2.51462185 -1.17733228 6 P 0 N;2
L 2.46181004 -1.12868996 2.36843996 -1.12868996 6 P 0 ;2
A 2.36843996 -1.12868996 2.37851998 -1.15751998 2.41186801 -1.12968307 6 P 0 N;2
L 2.34675 -1.1402 2.34675 -1.11835 6 P 8191 ;2
L 2.46181004 -1.11835 2.46181004 -1.12868996 6 P 8191 ;2
L 2.25188002 -1.11398996 2.25188002 -1.11418002 6 P 8191 ;2
A 2.3208 -1.02041004 2.3006 -1.02033996 2.31069163 -1.02276978 6 P 0 N;2
L 2.27413002 -1.11835 2.27413002 -1.12868996 6 P 8191 ;2
A 2.52848996 -1.16771004 2.54891998 -1.15895 2.52774557 -1.13777087 6 P 0 N;2
A 2.55608002 -1.08618002 2.53611998 -1.07688996 2.5249185 -1.12704419 6 P 0 N;2
L 2.71926004 -1.06796998 2.71926004 -1.17483996 6 P 0 ;2
A 2.78888996 -1.16296998 2.81508002 -1.16676998 2.8083499 -1.12100167 6 P 0 N;2
A 2.8151 -1.16675 2.83966004 -1.15211998 2.80521398 -1.12222392 6 P 0 N;2
A 2.85201004 -1.16508002 2.83966004 -1.15211004 2.84505768 -1.15933514 6 P 0 N;2
L 2.85201004 -1.16508002 2.84523996 -1.17161004 6 P 8191 ;2
A 2.81425 -1.1835 2.84525 -1.17161004 2.81425 -1.13714291 6 P 0 N;2
L 2.81425 -1.1835 2.79571004 -1.1835 6 P 8191 ;2
A 2.75886998 -1.16443002 2.79571998 -1.18351998 2.80278976 -1.12476142 6 P 0 N;2
A 2.74528996 -1.13568002 2.75888002 -1.16443002 2.80246565 -1.12624016 6 P 0 N;2
A 2.54316998 -1.1834 2.56906004 -1.1647 2.5305814 -1.13869892 6 P 0 N;2
A 2.56906004 -1.1647 2.57053996 -1.13728002 2.53763041 -1.14925374 6 P 0 N;2
A 2.65463996 -1.18351998 2.66863996 -1.17373996 2.65440246 -1.16826969 6 P 0 N;2
L 2.65463002 -1.1835 2.64165 -1.1835 6 P 8191 ;2
A 2.60955 -1.16043002 2.64163996 -1.18351004 2.63911063 -1.15317815 6 P 0 N;2
A 2.62978002 -1.15461998 2.66001998 -1.16328996 2.6502374 -1.14033868 6 P 0 N;2
A 2.66863996 -1.17375 2.66001998 -1.16328996 2.66100344 -1.17126132 6 P 0 N;2
A 2.6962 -1.17483996 2.71926004 -1.17483996 2.70773002 -1.17286427 6 P 0 N;2
L 2.69618996 -1.17483996 2.69618996 -1.06796998 6 P 0 ;2
A 2.83833002 -1.09275 2.82661998 -1.08201998 2.74555758 -1.18224094 6 P 0 N;2
A 2.82661998 -1.08198996 2.80036998 -1.07538996 2.80348839 -1.11848878 6 P 0 N;2
A 2.80036004 -1.07541998 2.76848996 -1.09933002 2.80700217 -1.1174685 6 P 0 N;2
A 2.76848996 -1.09931998 2.76446004 -1.12066004 2.82315728 -1.120694 6 P 0 N;2
A 2.74998002 -1.09273996 2.74528996 -1.11838996 2.8498563 -1.12425591 6 P 0 N;2
A 2.7954 -1.05776998 2.74998996 -1.09273996 2.80799961 -1.12109961 6 P 0 N;2
L 2.79541004 -1.05776998 2.80918996 -1.05776998 6 P 8191 ;2
A 2.85401998 -1.08106004 2.80918996 -1.05776998 2.80626024 -1.1181998 6 P 0 N;2
A 2.83833002 -1.09273996 2.85403002 -1.08106004 2.84418386 -1.08421683 6 P 0 N;2
L 2.76445 -1.12066004 2.76445 -1.12943002 6 P 8191 ;2
A 2.76446004 -1.12943002 2.76836998 -1.14305 2.80607844 -1.12485364 6 P 0 N;2
A 2.76836998 -1.14305 2.78891004 -1.16296998 2.80906152 -1.12164144 6 P 0 N;2
L 2.74528996 -1.13566004 2.74528996 -1.11838996 6 P 8191 ;2
A 2.55606004 -1.0862 2.56885 -1.07366998 2.56205354 -1.0795252 6 P 0 N;2
L 2.60953996 -1.07953996 2.59981998 -1.07953996 6 P 8191 ;2
A 2.5993 -1.05931998 2.59981004 -1.07955 2.6022813 -1.06936624 6 P 0 N;2
L 2.5993 -1.05931998 2.60953996 -1.05931998 6 P 8191 ;2
L 2.60953996 -1.05931998 2.60953996 -1.03491998 6 P 8191 ;2
A 2.62971998 -1.03418002 2.60953996 -1.03491004 2.61966791 -1.03559478 6 P 0 N;2
L 2.62971004 -1.03418996 2.62978002 -1.05931998 6 P 8191 ;2
L 2.62978002 -1.05931998 2.66008002 -1.05931998 6 P 8191 ;2
A 2.66003996 -1.07955 2.66008002 -1.05931998 2.65827421 -1.0694314 6 P 0 N;2
L 2.66003002 -1.07953996 2.62978002 -1.07953996 6 P 8191 ;2
A 2.71926004 -1.06796998 2.6962 -1.06796998 2.70773002 -1.0720561 6 P 0 N;2
A 2.71968996 -1.02341998 2.71968996 -1.02341998 2.70775 -1.02341998 6 P 0 N;2
A 2.57053996 -1.13728996 2.54306998 -1.11513002 2.53584449 -1.15219301 6 P 0 N;2
A 2.54891998 -1.15895 2.55001004 -1.14328002 2.54127923 -1.15054557 6 P 0 N;2
L 2.60953996 -1.16041004 2.60953996 -1.07953996 6 P 0 ;2
L 2.62978002 -1.07953996 2.62978002 -1.15463002 6 P 0 ;2
L 2.98495 -1.09393996 2.98495 -1.17625 6 P 0 ;2
A 2.96473996 -1.17626998 2.98493996 -1.17626998 2.97483996 -1.17442303 6 P 0 N;2
L 2.96473002 -1.17625 2.96473002 -1.17226004 6 P 8191 ;2
A 2.94165 -1.1835 2.96471004 -1.17226004 2.93076516 -1.1318935 6 P 0 N;2
L 2.94165 -1.1835 2.90701004 -1.1835 6 P 8191 ;2
A 2.90671004 -1.10841998 2.90703002 -1.18351004 2.9153065 -1.14592904 6 P 0 N;2
A 2.91853002 -1.12288996 2.91853002 -1.16618996 2.92048209 -1.14453996 6 P 0 N;2
L 2.91853002 -1.1662 2.94456004 -1.1662 6 P 8191 ;2
A 2.94456998 -1.16618996 2.94456998 -1.12288996 2.94406004 -1.14453996 6 P 0 N;2
A 2.96473002 -1.09686004 2.94741998 -1.07955 2.94874833 -1.09553169 6 P 0 N;2
L 2.9474 -1.07953996 2.90986998 -1.07953996 6 P 8191 ;2
A 2.90986998 -1.07953996 2.89821004 -1.0852 2.92433445 -1.12417766 6 P 0 N;2
A 2.89111998 -1.07086004 2.8982 -1.0852 2.8969689 -1.07688996 6 P 0 N;2
A 2.91561998 -1.05931998 2.89111998 -1.07085 2.92146033 -1.103525 6 P 0 N;2
L 2.91563002 -1.05931998 2.95031004 -1.05931998 6 P 8191 ;2
A 2.98496004 -1.09393996 2.95031004 -1.05933002 2.9453438 -1.09895197 6 P 0 N;2
A 2.92878996 -1.10535 2.9067 -1.10841998 2.93158484 -1.20646998 6 P 0 N;2
A 2.96471998 -1.10841004 2.92878002 -1.10536004 2.93215738 -1.27883829 6 P 0 N;2
L 2.96473002 -1.10841004 2.96473002 -1.09686004 6 P 8191 ;2
L 2.94456004 -1.12288002 2.91853002 -1.12288002 6 P 8191 ;2
L 3.04731004 -1.06001004 3.04191998 -1.07631998 6 P 8191 ;2
L 3.04191998 -1.07631998 3.03648002 -1.06001004 6 P 8191 ;2
L 3.03648002 -1.06001004 3.03243002 -1.06001004 6 P 8191 ;2
L 3.03243002 -1.06001004 3.02698002 -1.08543996 6 P 8191 ;2
L 3.02698002 -1.08543996 3.03226004 -1.08543996 6 P 8191 ;2
L 3.03226004 -1.08543996 3.03501004 -1.06886998 6 P 8191 ;2
L 3.03501004 -1.06886998 3.04086004 -1.08543996 6 P 8191 ;2
L 3.04086004 -1.08543996 3.04308996 -1.08543996 6 P 8191 ;2
L 3.04308996 -1.08543996 3.04888996 -1.06871004 6 P 8191 ;2
L 3.04888996 -1.06871004 3.05171004 -1.08543996 6 P 8191 ;2
L 3.05171004 -1.08543996 3.05713002 -1.08543996 6 P 8191 ;2
L 3.05713002 -1.08543996 3.05163996 -1.06001004 6 P 8191 ;2
L 3.05163996 -1.06001004 3.04731004 -1.06001004 6 P 8191 ;2
L 3.01066998 -1.06508002 3.00223002 -1.06508002 6 P 8191 ;2
L 3.00223002 -1.06508002 3.00223002 -1.06001004 6 P 8191 ;2
L 3.00223002 -1.06001004 3.02461004 -1.06001004 6 P 8191 ;2
L 3.02461004 -1.06001004 3.02461004 -1.06508002 6 P 8191 ;2
L 3.02461004 -1.06508002 3.01615 -1.06508002 6 P 8191 ;2
L 3.01615 -1.06508002 3.01615 -1.08533996 6 P 8191 ;2
L 3.01615 -1.08533996 3.01066998 -1.08533996 6 P 8191 ;2
L 3.01066998 -1.08533996 3.01066998 -1.06508002 6 P 8191 ;2
L 3.36933297 -0.955 3.36933297 -0.88 4 P 0 ;2,4=46,6=0.000000
L 3.36933297 -0.88 3.39173337 -0.88 4 P 0 ;2,4=46,6=0.000000
L 3.39173337 -0.88 3.3992001 -0.88375157 4 P 0 ;2,4=46,6=0.000000
L 3.3992001 -0.88375157 3.40480059 -0.8924997 4 P 0 ;2,4=46,6=0.000000
L 3.40480059 -0.8924997 3.40666693 -0.9024998 4 P 0 ;2,4=46,6=0.000000
L 3.40666693 -0.9024998 3.40480059 -0.9125 4 P 0 ;2,4=46,6=0.000000
L 3.40480059 -0.9125 3.40013327 -0.92000069 4 P 0 ;2,4=46,6=0.000000
L 3.40013327 -0.92000069 3.39173337 -0.92375217 4 P 0 ;2,4=46,6=0.000000
L 3.39173337 -0.92375217 3.36933297 -0.92375217 4 P 0 ;2,4=46,6=0.000000
L 3.44619931 -0.95749941 3.47980059 -0.88 4 P 0 ;2,4=46,6=0.000000
L 3.51653356 -0.955 3.51653356 -0.88 4 P 0 ;2,4=46,6=0.000000
L 3.51653356 -0.88 3.55946634 -0.955 4 P 0 ;2,4=46,6=0.000000
L 3.55946634 -0.955 3.55946634 -0.88 4 P 0 ;2,4=46,6=0.000000
L 3.68799911 -0.95749941 3.68613287 -0.9562497 4 P 0 ;2,4=46,6=0.000000
L 3.68613287 -0.9562497 3.68613287 -0.9537503 4 P 0 ;2,4=46,6=0.000000
L 3.68613287 -0.9537503 3.68799911 -0.95250059 4 P 0 ;2,4=46,6=0.000000
L 3.68799911 -0.95250059 3.68986703 -0.9537503 4 P 0 ;2,4=46,6=0.000000
L 3.68986703 -0.9537503 3.68986703 -0.9562497 4 P 0 ;2,4=46,6=0.000000
L 3.68986703 -0.9562497 3.68799911 -0.95749941 4 P 0 ;2,4=46,6=0.000000
L 3.68799911 -0.92375217 3.68613287 -0.9225001 4 P 0 ;2,4=46,6=0.000000
L 3.68613287 -0.9225001 3.68613287 -0.92000069 4 P 0 ;2,4=46,6=0.000000
L 3.68613287 -0.92000069 3.68799911 -0.91875089 4 P 0 ;2,4=46,6=0.000000
L 3.68799911 -0.91875089 3.68986703 -0.92000069 4 P 0 ;2,4=46,6=0.000000
L 3.68986703 -0.92000069 3.68986703 -0.9225001 4 P 0 ;2,4=46,6=0.000000
L 3.68986703 -0.9225001 3.68799911 -0.92375217 4 P 0 ;2,4=46,6=0.000000
L 3.81933297 -0.955 3.81933297 -0.88 4 P 0 ;2,4=46,6=0.000000
L 3.81933297 -0.88 3.84266644 -0.88 4 P 0 ;2,4=46,6=0.000000
L 3.84266644 -0.88 3.85013327 -0.88375157 4 P 0 ;2,4=46,6=0.000000
L 3.85013327 -0.88375157 3.85480059 -0.88875049 4 P 0 ;2,4=46,6=0.000000
L 3.85480059 -0.88875049 3.85666693 -0.89875059 4 P 0 ;2,4=46,6=0.000000
L 3.85666693 -0.89875059 3.85480059 -0.90875079 4 P 0 ;2,4=46,6=0.000000
L 3.85480059 -0.90875079 3.8492001 -0.91499941 4 P 0 ;2,4=46,6=0.000000
L 3.8492001 -0.91499941 3.84266644 -0.91875089 4 P 0 ;2,4=46,6=0.000000
L 3.84266644 -0.91875089 3.81933297 -0.91875089 4 P 0 ;2,4=46,6=0.000000
L 3.84266644 -0.91875089 3.85666693 -0.955 4 P 0 ;2,4=46,6=0.000000
L 3.9242001 -0.955 3.9242001 -0.88 4 P 0 ;2,4=46,6=0.000000
L 3.9242001 -0.88 3.88966565 -0.93375 4 P 0 ;2,4=46,6=0.000000
L 3.88966565 -0.93375 3.93633425 -0.93375 4 P 0 ;2,4=46,6=0.000000
L 3.98799911 -0.88 3.98053228 -0.88249951 4 P 0 ;2,4=46,6=0.000000
L 3.98053228 -0.88249951 3.97493346 -0.88875049 4 P 0 ;2,4=46,6=0.000000
L 3.97493346 -0.88875049 3.97119931 -0.89624882 4 P 0 ;2,4=46,6=0.000000
L 3.97119931 -0.89624882 3.9683999 -0.90625128 4 P 0 ;2,4=46,6=0.000000
L 3.9683999 -0.90625128 3.96746673 -0.91750118 4 P 0 ;2,4=46,6=0.000000
L 3.96746673 -0.91750118 3.9683999 -0.92875108 4 P 0 ;2,4=46,6=0.000000
L 3.9683999 -0.92875108 3.97119931 -0.93875128 4 P 0 ;2,4=46,6=0.000000
L 3.97119931 -0.93875128 3.97493346 -0.94625187 4 P 0 ;2,4=46,6=0.000000
L 3.97493346 -0.94625187 3.98053228 -0.95250059 4 P 0 ;2,4=46,6=0.000000
L 3.98053228 -0.95250059 3.98799911 -0.955 4 P 0 ;2,4=46,6=0.000000
L 3.98799911 -0.955 3.99546585 -0.95250059 4 P 0 ;2,4=46,6=0.000000
L 3.99546585 -0.95250059 4.00106644 -0.94625187 4 P 0 ;2,4=46,6=0.000000
L 4.00106644 -0.94625187 4.00480059 -0.93875128 4 P 0 ;2,4=46,6=0.000000
L 4.00480059 -0.93875128 4.0076 -0.92875108 4 P 0 ;2,4=46,6=0.000000
L 4.0076 -0.92875108 4.00853317 -0.91750118 4 P 0 ;2,4=46,6=0.000000
L 4.00853317 -0.91750118 4.0076 -0.90625128 4 P 0 ;2,4=46,6=0.000000
L 4.0076 -0.90625128 4.00480059 -0.89624882 4 P 0 ;2,4=46,6=0.000000
L 4.00480059 -0.89624882 4.00106644 -0.88875049 4 P 0 ;2,4=46,6=0.000000
L 4.00106644 -0.88875049 3.99546585 -0.88249951 4 P 0 ;2,4=46,6=0.000000
L 3.99546585 -0.88249951 3.98799911 -0.88 4 P 0 ;2,4=46,6=0.000000
L 4.06299911 -0.88 4.05553228 -0.88249951 4 P 0 ;2,4=46,6=0.000000
L 4.05553228 -0.88249951 4.04993346 -0.88875049 4 P 0 ;2,4=46,6=0.000000
L 4.04993346 -0.88875049 4.04619931 -0.89624882 4 P 0 ;2,4=46,6=0.000000
L 4.04619931 -0.89624882 4.0433999 -0.90625128 4 P 0 ;2,4=46,6=0.000000
L 4.0433999 -0.90625128 4.04246673 -0.91750118 4 P 0 ;2,4=46,6=0.000000
L 4.04246673 -0.91750118 4.0433999 -0.92875108 4 P 0 ;2,4=46,6=0.000000
L 4.0433999 -0.92875108 4.04619931 -0.93875128 4 P 0 ;2,4=46,6=0.000000
L 4.04619931 -0.93875128 4.04993346 -0.94625187 4 P 0 ;2,4=46,6=0.000000
L 4.04993346 -0.94625187 4.05553228 -0.95250059 4 P 0 ;2,4=46,6=0.000000
L 4.05553228 -0.95250059 4.06299911 -0.955 4 P 0 ;2,4=46,6=0.000000
L 4.06299911 -0.955 4.07046585 -0.95250059 4 P 0 ;2,4=46,6=0.000000
L 4.07046585 -0.95250059 4.07606644 -0.94625187 4 P 0 ;2,4=46,6=0.000000
L 4.07606644 -0.94625187 4.07980059 -0.93875128 4 P 0 ;2,4=46,6=0.000000
L 4.07980059 -0.93875128 4.0826 -0.92875108 4 P 0 ;2,4=46,6=0.000000
L 4.0826 -0.92875108 4.08353317 -0.91750118 4 P 0 ;2,4=46,6=0.000000
L 4.08353317 -0.91750118 4.0826 -0.90625128 4 P 0 ;2,4=46,6=0.000000
L 4.0826 -0.90625128 4.07980059 -0.89624882 4 P 0 ;2,4=46,6=0.000000
L 4.07980059 -0.89624882 4.07606644 -0.88875049 4 P 0 ;2,4=46,6=0.000000
L 4.07606644 -0.88875049 4.07046585 -0.88249951 4 P 0 ;2,4=46,6=0.000000
L 4.07046585 -0.88249951 4.06299911 -0.88 4 P 0 ;2,4=46,6=0.000000
L 4.12026614 -0.92375217 4.1267998 -0.91499941 4 P 0 ;2,4=46,6=0.000000
L 4.1267998 -0.91499941 4.1324003 -0.91000049 4 P 0 ;2,4=46,6=0.000000
L 4.1324003 -0.91000049 4.13986703 -0.90750108 4 P 0 ;2,4=46,6=0.000000
L 4.13986703 -0.90750108 4.14640069 -0.91000049 4 P 0 ;2,4=46,6=0.000000
L 4.14640069 -0.91000049 4.15106644 -0.91499941 4 P 0 ;2,4=46,6=0.000000
L 4.15106644 -0.91499941 4.15480059 -0.9225001 4 P 0 ;2,4=46,6=0.000000
L 4.15480059 -0.9225001 4.15573376 -0.93125059 4 P 0 ;2,4=46,6=0.000000
L 4.15573376 -0.93125059 4.15480059 -0.93875128 4 P 0 ;2,4=46,6=0.000000
L 4.15480059 -0.93875128 4.15106644 -0.94625187 4 P 0 ;2,4=46,6=0.000000
L 4.15106644 -0.94625187 4.14546585 -0.95250059 4 P 0 ;2,4=46,6=0.000000
L 4.14546585 -0.95250059 4.13893396 -0.955 4 P 0 ;2,4=46,6=0.000000
L 4.13893396 -0.955 4.13146713 -0.95250059 4 P 0 ;2,4=46,6=0.000000
L 4.13146713 -0.95250059 4.12493346 -0.94500217 4 P 0 ;2,4=46,6=0.000000
L 4.12493346 -0.94500217 4.12119931 -0.93375 4 P 0 ;2,4=46,6=0.000000
L 4.12119931 -0.93375 4.12026614 -0.92125039 4 P 0 ;2,4=46,6=0.000000
L 4.12026614 -0.92125039 4.12213238 -0.90500157 4 P 0 ;2,4=46,6=0.000000
L 4.12213238 -0.90500157 4.12493346 -0.89624882 4 P 0 ;2,4=46,6=0.000000
L 4.12493346 -0.89624882 4.12959921 -0.88750069 4 P 0 ;2,4=46,6=0.000000
L 4.12959921 -0.88750069 4.13613287 -0.8812498 4 P 0 ;2,4=46,6=0.000000
L 4.13613287 -0.8812498 4.14266644 -0.88 4 P 0 ;2,4=46,6=0.000000
L 4.14266644 -0.88 4.1492001 -0.88249951 4 P 0 ;2,4=46,6=0.000000
L 4.1492001 -0.88249951 4.15386752 -0.88875049 4 P 0 ;2,4=46,6=0.000000
L 4.20086663 -0.93000079 4.22513327 -0.93000079 4 P 0 ;2,4=46,6=0.000000
L 4.29546585 -0.91499941 4.2992001 -0.9112502 4 P 0 ;2,4=46,6=0.000000
L 4.2992001 -0.9112502 4.30199951 -0.90500157 4 P 0 ;2,4=46,6=0.000000
L 4.30199951 -0.90500157 4.30386752 -0.89624882 4 P 0 ;2,4=46,6=0.000000
L 4.30386752 -0.89624882 4.30199951 -0.88875049 4 P 0 ;2,4=46,6=0.000000
L 4.30199951 -0.88875049 4.29826703 -0.88375157 4 P 0 ;2,4=46,6=0.000000
L 4.29826703 -0.88375157 4.29173337 -0.88 4 P 0 ;2,4=46,6=0.000000
L 4.29173337 -0.88 4.26653356 -0.88 4 P 0 ;2,4=46,6=0.000000
L 4.26653356 -0.88 4.26653356 -0.955 4 P 0 ;2,4=46,6=0.000000
L 4.26653356 -0.955 4.29733386 -0.955 4 P 0 ;2,4=46,6=0.000000
L 4.29733386 -0.955 4.30386752 -0.95000108 4 P 0 ;2,4=46,6=0.000000
L 4.30386752 -0.95000108 4.3076 -0.94250039 4 P 0 ;2,4=46,6=0.000000
L 4.3076 -0.94250039 4.30946634 -0.93375 4 P 0 ;2,4=46,6=0.000000
L 4.30946634 -0.93375 4.3076 -0.92500187 4 P 0 ;2,4=46,6=0.000000
L 4.3076 -0.92500187 4.30199951 -0.91750118 4 P 0 ;2,4=46,6=0.000000
L 4.30199951 -0.91750118 4.29546585 -0.91499941 4 P 0 ;2,4=46,6=0.000000
L 4.29546585 -0.91499941 4.26653356 -0.91499941 4 P 0 ;2,4=46,6=0.000000
L 4.36299911 -0.88 4.35553228 -0.88249951 4 P 0 ;2,4=46,6=0.000000
L 4.35553228 -0.88249951 4.34993346 -0.88875049 4 P 0 ;2,4=46,6=0.000000
L 4.34993346 -0.88875049 4.34619931 -0.89624882 4 P 0 ;2,4=46,6=0.000000
L 4.34619931 -0.89624882 4.3433999 -0.90625128 4 P 0 ;2,4=46,6=0.000000
L 4.3433999 -0.90625128 4.34246673 -0.91750118 4 P 0 ;2,4=46,6=0.000000
L 4.34246673 -0.91750118 4.3433999 -0.92875108 4 P 0 ;2,4=46,6=0.000000
L 4.3433999 -0.92875108 4.34619931 -0.93875128 4 P 0 ;2,4=46,6=0.000000
L 4.34619931 -0.93875128 4.34993346 -0.94625187 4 P 0 ;2,4=46,6=0.000000
L 4.34993346 -0.94625187 4.35553228 -0.95250059 4 P 0 ;2,4=46,6=0.000000
L 4.35553228 -0.95250059 4.36299911 -0.955 4 P 0 ;2,4=46,6=0.000000
L 4.36299911 -0.955 4.37046585 -0.95250059 4 P 0 ;2,4=46,6=0.000000
L 4.37046585 -0.95250059 4.37606644 -0.94625187 4 P 0 ;2,4=46,6=0.000000
L 4.37606644 -0.94625187 4.37980059 -0.93875128 4 P 0 ;2,4=46,6=0.000000
L 4.37980059 -0.93875128 4.3826 -0.92875108 4 P 0 ;2,4=46,6=0.000000
L 4.3826 -0.92875108 4.38353317 -0.91750118 4 P 0 ;2,4=46,6=0.000000
L 4.38353317 -0.91750118 4.3826 -0.90625128 4 P 0 ;2,4=46,6=0.000000
L 4.3826 -0.90625128 4.37980059 -0.89624882 4 P 0 ;2,4=46,6=0.000000
L 4.37980059 -0.89624882 4.37606644 -0.88875049 4 P 0 ;2,4=46,6=0.000000
L 4.37606644 -0.88875049 4.37046585 -0.88249951 4 P 0 ;2,4=46,6=0.000000
L 4.37046585 -0.88249951 4.36299911 -0.88 4 P 0 ;2,4=46,6=0.000000
L 4.43799911 -0.88 4.43053228 -0.88249951 4 P 0 ;2,4=46,6=0.000000
L 4.43053228 -0.88249951 4.42493346 -0.88875049 4 P 0 ;2,4=46,6=0.000000
L 4.42493346 -0.88875049 4.42119931 -0.89624882 4 P 0 ;2,4=46,6=0.000000
L 4.42119931 -0.89624882 4.4183999 -0.90625128 4 P 0 ;2,4=46,6=0.000000
L 4.4183999 -0.90625128 4.41746673 -0.91750118 4 P 0 ;2,4=46,6=0.000000
L 4.41746673 -0.91750118 4.4183999 -0.92875108 4 P 0 ;2,4=46,6=0.000000
L 4.4183999 -0.92875108 4.42119931 -0.93875128 4 P 0 ;2,4=46,6=0.000000
L 4.42119931 -0.93875128 4.42493346 -0.94625187 4 P 0 ;2,4=46,6=0.000000
L 4.42493346 -0.94625187 4.43053228 -0.95250059 4 P 0 ;2,4=46,6=0.000000
L 4.43053228 -0.95250059 4.43799911 -0.955 4 P 0 ;2,4=46,6=0.000000
L 4.43799911 -0.955 4.44546585 -0.95250059 4 P 0 ;2,4=46,6=0.000000
L 4.44546585 -0.95250059 4.45106644 -0.94625187 4 P 0 ;2,4=46,6=0.000000
L 4.45106644 -0.94625187 4.45480059 -0.93875128 4 P 0 ;2,4=46,6=0.000000
L 4.45480059 -0.93875128 4.4576 -0.92875108 4 P 0 ;2,4=46,6=0.000000
L 4.4576 -0.92875108 4.45853317 -0.91750118 4 P 0 ;2,4=46,6=0.000000
L 4.45853317 -0.91750118 4.4576 -0.90625128 4 P 0 ;2,4=46,6=0.000000
L 4.4576 -0.90625128 4.45480059 -0.89624882 4 P 0 ;2,4=46,6=0.000000
L 4.45480059 -0.89624882 4.45106644 -0.88875049 4 P 0 ;2,4=46,6=0.000000
L 4.45106644 -0.88875049 4.44546585 -0.88249951 4 P 0 ;2,4=46,6=0.000000
L 4.44546585 -0.88249951 4.43799911 -0.88 4 P 0 ;2,4=46,6=0.000000
L 4.51299911 -0.88 4.50553228 -0.88249951 4 P 0 ;2,4=46,6=0.000000
L 4.50553228 -0.88249951 4.49993346 -0.88875049 4 P 0 ;2,4=46,6=0.000000
L 4.49993346 -0.88875049 4.49619931 -0.89624882 4 P 0 ;2,4=46,6=0.000000
L 4.49619931 -0.89624882 4.4933999 -0.90625128 4 P 0 ;2,4=46,6=0.000000
L 4.4933999 -0.90625128 4.49246673 -0.91750118 4 P 0 ;2,4=46,6=0.000000
L 4.49246673 -0.91750118 4.4933999 -0.92875108 4 P 0 ;2,4=46,6=0.000000
L 4.4933999 -0.92875108 4.49619931 -0.93875128 4 P 0 ;2,4=46,6=0.000000
L 4.49619931 -0.93875128 4.49993346 -0.94625187 4 P 0 ;2,4=46,6=0.000000
L 4.49993346 -0.94625187 4.50553228 -0.95250059 4 P 0 ;2,4=46,6=0.000000
L 4.50553228 -0.95250059 4.51299911 -0.955 4 P 0 ;2,4=46,6=0.000000
L 4.51299911 -0.955 4.52046585 -0.95250059 4 P 0 ;2,4=46,6=0.000000
L 4.52046585 -0.95250059 4.52606644 -0.94625187 4 P 0 ;2,4=46,6=0.000000
L 4.52606644 -0.94625187 4.52980059 -0.93875128 4 P 0 ;2,4=46,6=0.000000
L 4.52980059 -0.93875128 4.5326 -0.92875108 4 P 0 ;2,4=46,6=0.000000
L 4.5326 -0.92875108 4.53353317 -0.91750118 4 P 0 ;2,4=46,6=0.000000
L 4.53353317 -0.91750118 4.5326 -0.90625128 4 P 0 ;2,4=46,6=0.000000
L 4.5326 -0.90625128 4.52980059 -0.89624882 4 P 0 ;2,4=46,6=0.000000
L 4.52980059 -0.89624882 4.52606644 -0.88875049 4 P 0 ;2,4=46,6=0.000000
L 4.52606644 -0.88875049 4.52046585 -0.88249951 4 P 0 ;2,4=46,6=0.000000
L 4.52046585 -0.88249951 4.51299911 -0.88 4 P 0 ;2,4=46,6=0.000000
L 4.58799911 -0.955 4.58799911 -0.88 4 P 0 ;2,4=46,6=0.000000
L 4.58799911 -0.88 4.5767998 -0.89499911 4 P 0 ;2,4=46,6=0.000000
L 4.5767998 -0.955 4.59919843 -0.955 4 P 0 ;2,4=46,6=0.000000
L 4.65086663 -0.93000079 4.67513327 -0.93000079 4 P 0 ;2,4=46,6=0.000000
L 4.73799911 -0.88 4.73053228 -0.88249951 4 P 0 ;2,4=46,6=0.000000
L 4.73053228 -0.88249951 4.72493346 -0.88875049 4 P 0 ;2,4=46,6=0.000000
L 4.72493346 -0.88875049 4.72119931 -0.89624882 4 P 0 ;2,4=46,6=0.000000
L 4.72119931 -0.89624882 4.7183999 -0.90625128 4 P 0 ;2,4=46,6=0.000000
L 4.7183999 -0.90625128 4.71746673 -0.91750118 4 P 0 ;2,4=46,6=0.000000
L 4.71746673 -0.91750118 4.7183999 -0.92875108 4 P 0 ;2,4=46,6=0.000000
L 4.7183999 -0.92875108 4.72119931 -0.93875128 4 P 0 ;2,4=46,6=0.000000
L 4.72119931 -0.93875128 4.72493346 -0.94625187 4 P 0 ;2,4=46,6=0.000000
L 4.72493346 -0.94625187 4.73053228 -0.95250059 4 P 0 ;2,4=46,6=0.000000
L 4.73053228 -0.95250059 4.73799911 -0.955 4 P 0 ;2,4=46,6=0.000000
L 4.73799911 -0.955 4.74546585 -0.95250059 4 P 0 ;2,4=46,6=0.000000
L 4.74546585 -0.95250059 4.75106644 -0.94625187 4 P 0 ;2,4=46,6=0.000000
L 4.75106644 -0.94625187 4.75480059 -0.93875128 4 P 0 ;2,4=46,6=0.000000
L 4.75480059 -0.93875128 4.7576 -0.92875108 4 P 0 ;2,4=46,6=0.000000
L 4.7576 -0.92875108 4.75853317 -0.91750118 4 P 0 ;2,4=46,6=0.000000
L 4.75853317 -0.91750118 4.7576 -0.90625128 4 P 0 ;2,4=46,6=0.000000
L 4.7576 -0.90625128 4.75480059 -0.89624882 4 P 0 ;2,4=46,6=0.000000
L 4.75480059 -0.89624882 4.75106644 -0.88875049 4 P 0 ;2,4=46,6=0.000000
L 4.75106644 -0.88875049 4.74546585 -0.88249951 4 P 0 ;2,4=46,6=0.000000
L 4.74546585 -0.88249951 4.73799911 -0.88 4 P 0 ;2,4=46,6=0.000000
L 4.79526614 -0.8924997 4.80086663 -0.88500128 4 P 0 ;2,4=46,6=0.000000
L 4.80086663 -0.88500128 4.8074003 -0.8812498 4 P 0 ;2,4=46,6=0.000000
L 4.8074003 -0.8812498 4.81486703 -0.88 4 P 0 ;2,4=46,6=0.000000
L 4.81486703 -0.88 4.8242001 -0.88249951 4 P 0 ;2,4=46,6=0.000000
L 4.8242001 -0.88249951 4.83073376 -0.88875049 4 P 0 ;2,4=46,6=0.000000
L 4.83073376 -0.88875049 4.8326 -0.89624882 4 P 0 ;2,4=46,6=0.000000
L 4.8326 -0.89624882 4.83166693 -0.90375187 4 P 0 ;2,4=46,6=0.000000
L 4.83166693 -0.90375187 4.82793268 -0.91000049 4 P 0 ;2,4=46,6=0.000000
L 4.82793268 -0.91000049 4.80926654 -0.9225001 4 P 0 ;2,4=46,6=0.000000
L 4.80926654 -0.9225001 4.80086663 -0.93125059 4 P 0 ;2,4=46,6=0.000000
L 4.80086663 -0.93125059 4.79526614 -0.94375246 4 P 0 ;2,4=46,6=0.000000
L 4.79526614 -0.94375246 4.7933999 -0.955 4 P 0 ;2,4=46,6=0.000000
L 4.7933999 -0.955 4.8326 -0.955 4 P 0 ;2,4=46,6=0.000000
L 3.36746673 -1.205 3.36746673 -1.13 4 P 0 ;2,4=47,6=0.000000
L 3.36746673 -1.13 3.38613287 -1.13 4 P 0 ;2,4=47,6=0.000000
L 3.38613287 -1.13 3.39359961 -1.13375157 4 P 0 ;2,4=47,6=0.000000
L 3.39359961 -1.13375157 3.3992001 -1.13875049 4 P 0 ;2,4=47,6=0.000000
L 3.3992001 -1.13875049 3.40386752 -1.14624882 4 P 0 ;2,4=47,6=0.000000
L 3.40386752 -1.14624882 3.4076 -1.15500157 4 P 0 ;2,4=47,6=0.000000
L 3.4076 -1.15500157 3.40853317 -1.16750118 4 P 0 ;2,4=47,6=0.000000
L 3.40853317 -1.16750118 3.4076 -1.18000079 4 P 0 ;2,4=47,6=0.000000
L 3.4076 -1.18000079 3.40386752 -1.18875128 4 P 0 ;2,4=47,6=0.000000
L 3.40386752 -1.18875128 3.3992001 -1.19625187 4 P 0 ;2,4=47,6=0.000000
L 3.3992001 -1.19625187 3.39359961 -1.20125089 4 P 0 ;2,4=47,6=0.000000
L 3.39359961 -1.20125089 3.38613287 -1.205 4 P 0 ;2,4=47,6=0.000000
L 3.38613287 -1.205 3.36746673 -1.205 4 P 0 ;2,4=47,6=0.000000
L 3.47980059 -1.205 3.47980059 -1.15500157 4 P 0 ;2,4=47,6=0.000000
L 3.47980059 -1.1637497 3.47606644 -1.15875079 4 P 0 ;2,4=47,6=0.000000
L 3.47606644 -1.15875079 3.47046585 -1.15625128 4 P 0 ;2,4=47,6=0.000000
L 3.47046585 -1.15625128 3.46393396 -1.15500157 4 P 0 ;2,4=47,6=0.000000
L 3.46393396 -1.15500157 3.4574003 -1.15750108 4 P 0 ;2,4=47,6=0.000000
L 3.4574003 -1.15750108 3.4517998 -1.1625 4 P 0 ;2,4=47,6=0.000000
L 3.4517998 -1.1625 3.44806555 -1.17000069 4 P 0 ;2,4=47,6=0.000000
L 3.44806555 -1.17000069 3.44619931 -1.18000079 4 P 0 ;2,4=47,6=0.000000
L 3.44619931 -1.18000079 3.44806555 -1.19000098 4 P 0 ;2,4=47,6=0.000000
L 3.44806555 -1.19000098 3.4517998 -1.19750167 4 P 0 ;2,4=47,6=0.000000
L 3.4517998 -1.19750167 3.4574003 -1.20250059 4 P 0 ;2,4=47,6=0.000000
L 3.4574003 -1.20250059 3.46393396 -1.205 4 P 0 ;2,4=47,6=0.000000
L 3.46393396 -1.205 3.47046585 -1.2037503 4 P 0 ;2,4=47,6=0.000000
L 3.47046585 -1.2037503 3.47606644 -1.20000108 4 P 0 ;2,4=47,6=0.000000
L 3.47606644 -1.20000108 3.47980059 -1.19500217 4 P 0 ;2,4=47,6=0.000000
L 3.53799911 -1.13 3.53799911 -1.205 4 P 0 ;2,4=47,6=0.000000
L 3.52493346 -1.15500157 3.55106644 -1.15500157 4 P 0 ;2,4=47,6=0.000000
L 3.59900039 -1.17125039 3.62886752 -1.17125039 4 P 0 ;2,4=47,6=0.000000
L 3.62886752 -1.17125039 3.62606644 -1.1625 4 P 0 ;2,4=47,6=0.000000
L 3.62606644 -1.1625 3.62140069 -1.15750108 4 P 0 ;2,4=47,6=0.000000
L 3.62140069 -1.15750108 3.61486703 -1.15500157 4 P 0 ;2,4=47,6=0.000000
L 3.61486703 -1.15500157 3.60833346 -1.15625128 4 P 0 ;2,4=47,6=0.000000
L 3.60833346 -1.15625128 3.60273287 -1.16000049 4 P 0 ;2,4=47,6=0.000000
L 3.60273287 -1.16000049 3.59900039 -1.16875089 4 P 0 ;2,4=47,6=0.000000
L 3.59900039 -1.16875089 3.59713238 -1.17625157 4 P 0 ;2,4=47,6=0.000000
L 3.59713238 -1.17625157 3.59713238 -1.18375 4 P 0 ;2,4=47,6=0.000000
L 3.59713238 -1.18375 3.59900039 -1.19125069 4 P 0 ;2,4=47,6=0.000000
L 3.59900039 -1.19125069 3.60366604 -1.19875138 4 P 0 ;2,4=47,6=0.000000
L 3.60366604 -1.19875138 3.60926654 -1.2037503 4 P 0 ;2,4=47,6=0.000000
L 3.60926654 -1.2037503 3.6158002 -1.205 4 P 0 ;2,4=47,6=0.000000
L 3.6158002 -1.205 3.62233386 -1.20250059 4 P 0 ;2,4=47,6=0.000000
L 3.62233386 -1.20250059 3.62886752 -1.19500217 4 P 0 ;2,4=47,6=0.000000
L 3.68799911 -1.20749941 3.68613287 -1.2062497 4 P 0 ;2,4=47,6=0.000000
L 3.68613287 -1.2062497 3.68613287 -1.2037503 4 P 0 ;2,4=47,6=0.000000
L 3.68613287 -1.2037503 3.68799911 -1.20250059 4 P 0 ;2,4=47,6=0.000000
L 3.68799911 -1.20250059 3.68986703 -1.2037503 4 P 0 ;2,4=47,6=0.000000
L 3.68986703 -1.2037503 3.68986703 -1.2062497 4 P 0 ;2,4=47,6=0.000000
L 3.68986703 -1.2062497 3.68799911 -1.20749941 4 P 0 ;2,4=47,6=0.000000
L 3.68799911 -1.17375217 3.68613287 -1.1725001 4 P 0 ;2,4=47,6=0.000000
L 3.68613287 -1.1725001 3.68613287 -1.17000069 4 P 0 ;2,4=47,6=0.000000
L 3.68613287 -1.17000069 3.68799911 -1.16875089 4 P 0 ;2,4=47,6=0.000000
L 3.68799911 -1.16875089 3.68986703 -1.17000069 4 P 0 ;2,4=47,6=0.000000
L 3.68986703 -1.17000069 3.68986703 -1.1725001 4 P 0 ;2,4=47,6=0.000000
L 3.68986703 -1.1725001 3.68799911 -1.17375217 4 P 0 ;2,4=47,6=0.000000
L 3.82026614 -1.1424997 3.82586663 -1.13500128 4 P 0 ;2,4=47,6=0.000000
L 3.82586663 -1.13500128 3.8324003 -1.1312498 4 P 0 ;2,4=47,6=0.000000
L 3.8324003 -1.1312498 3.83986703 -1.13 4 P 0 ;2,4=47,6=0.000000
L 3.83986703 -1.13 3.8492001 -1.13249951 4 P 0 ;2,4=47,6=0.000000
L 3.8492001 -1.13249951 3.85573376 -1.13875049 4 P 0 ;2,4=47,6=0.000000
L 3.85573376 -1.13875049 3.8576 -1.14624882 4 P 0 ;2,4=47,6=0.000000
L 3.8576 -1.14624882 3.85666693 -1.15375187 4 P 0 ;2,4=47,6=0.000000
L 3.85666693 -1.15375187 3.85293268 -1.16000049 4 P 0 ;2,4=47,6=0.000000
L 3.85293268 -1.16000049 3.83426654 -1.1725001 4 P 0 ;2,4=47,6=0.000000
L 3.83426654 -1.1725001 3.82586663 -1.18125059 4 P 0 ;2,4=47,6=0.000000
L 3.82586663 -1.18125059 3.82026614 -1.19375246 4 P 0 ;2,4=47,6=0.000000
L 3.82026614 -1.19375246 3.8183999 -1.205 4 P 0 ;2,4=47,6=0.000000
L 3.8183999 -1.205 3.8576 -1.205 4 P 0 ;2,4=47,6=0.000000
L 3.91299911 -1.13 3.90553228 -1.13249951 4 P 0 ;2,4=47,6=0.000000
L 3.90553228 -1.13249951 3.89993346 -1.13875049 4 P 0 ;2,4=47,6=0.000000
L 3.89993346 -1.13875049 3.89619931 -1.14624882 4 P 0 ;2,4=47,6=0.000000
L 3.89619931 -1.14624882 3.8933999 -1.15625128 4 P 0 ;2,4=47,6=0.000000
L 3.8933999 -1.15625128 3.89246673 -1.16750118 4 P 0 ;2,4=47,6=0.000000
L 3.89246673 -1.16750118 3.8933999 -1.17875108 4 P 0 ;2,4=47,6=0.000000
L 3.8933999 -1.17875108 3.89619931 -1.18875128 4 P 0 ;2,4=47,6=0.000000
L 3.89619931 -1.18875128 3.89993346 -1.19625187 4 P 0 ;2,4=47,6=0.000000
L 3.89993346 -1.19625187 3.90553228 -1.20250059 4 P 0 ;2,4=47,6=0.000000
L 3.90553228 -1.20250059 3.91299911 -1.205 4 P 0 ;2,4=47,6=0.000000
L 3.91299911 -1.205 3.92046585 -1.20250059 4 P 0 ;2,4=47,6=0.000000
L 3.92046585 -1.20250059 3.92606644 -1.19625187 4 P 0 ;2,4=47,6=0.000000
L 3.92606644 -1.19625187 3.92980059 -1.18875128 4 P 0 ;2,4=47,6=0.000000
L 3.92980059 -1.18875128 3.9326 -1.17875108 4 P 0 ;2,4=47,6=0.000000
L 3.9326 -1.17875108 3.93353317 -1.16750118 4 P 0 ;2,4=47,6=0.000000
L 3.93353317 -1.16750118 3.9326 -1.15625128 4 P 0 ;2,4=47,6=0.000000
L 3.9326 -1.15625128 3.92980059 -1.14624882 4 P 0 ;2,4=47,6=0.000000
L 3.92980059 -1.14624882 3.92606644 -1.13875049 4 P 0 ;2,4=47,6=0.000000
L 3.92606644 -1.13875049 3.92046585 -1.13249951 4 P 0 ;2,4=47,6=0.000000
L 3.92046585 -1.13249951 3.91299911 -1.13 4 P 0 ;2,4=47,6=0.000000
L 3.97026614 -1.1424997 3.97586663 -1.13500128 4 P 0 ;2,4=47,6=0.000000
L 3.97586663 -1.13500128 3.9824003 -1.1312498 4 P 0 ;2,4=47,6=0.000000
L 3.9824003 -1.1312498 3.98986703 -1.13 4 P 0 ;2,4=47,6=0.000000
L 3.98986703 -1.13 3.9992001 -1.13249951 4 P 0 ;2,4=47,6=0.000000
L 3.9992001 -1.13249951 4.00573376 -1.13875049 4 P 0 ;2,4=47,6=0.000000
L 4.00573376 -1.13875049 4.0076 -1.14624882 4 P 0 ;2,4=47,6=0.000000
L 4.0076 -1.14624882 4.00666693 -1.15375187 4 P 0 ;2,4=47,6=0.000000
L 4.00666693 -1.15375187 4.00293268 -1.16000049 4 P 0 ;2,4=47,6=0.000000
L 4.00293268 -1.16000049 3.98426654 -1.1725001 4 P 0 ;2,4=47,6=0.000000
L 3.98426654 -1.1725001 3.97586663 -1.18125059 4 P 0 ;2,4=47,6=0.000000
L 3.97586663 -1.18125059 3.97026614 -1.19375246 4 P 0 ;2,4=47,6=0.000000
L 3.97026614 -1.19375246 3.9683999 -1.205 4 P 0 ;2,4=47,6=0.000000
L 3.9683999 -1.205 4.0076 -1.205 4 P 0 ;2,4=47,6=0.000000
L 4.04526614 -1.1424997 4.05086663 -1.13500128 4 P 0 ;2,4=47,6=0.000000
L 4.05086663 -1.13500128 4.0574003 -1.1312498 4 P 0 ;2,4=47,6=0.000000
L 4.0574003 -1.1312498 4.06486703 -1.13 4 P 0 ;2,4=47,6=0.000000
L 4.06486703 -1.13 4.0742001 -1.13249951 4 P 0 ;2,4=47,6=0.000000
L 4.0742001 -1.13249951 4.08073376 -1.13875049 4 P 0 ;2,4=47,6=0.000000
L 4.08073376 -1.13875049 4.0826 -1.14624882 4 P 0 ;2,4=47,6=0.000000
L 4.0826 -1.14624882 4.08166693 -1.15375187 4 P 0 ;2,4=47,6=0.000000
L 4.08166693 -1.15375187 4.07793268 -1.16000049 4 P 0 ;2,4=47,6=0.000000
L 4.07793268 -1.16000049 4.05926654 -1.1725001 4 P 0 ;2,4=47,6=0.000000
L 4.05926654 -1.1725001 4.05086663 -1.18125059 4 P 0 ;2,4=47,6=0.000000
L 4.05086663 -1.18125059 4.04526614 -1.19375246 4 P 0 ;2,4=47,6=0.000000
L 4.04526614 -1.19375246 4.0433999 -1.205 4 P 0 ;2,4=47,6=0.000000
L 4.0433999 -1.205 4.0826 -1.205 4 P 0 ;2,4=47,6=0.000000
L 4.12586663 -1.18000079 4.15013327 -1.18000079 4 P 0 ;2,4=47,6=0.000000
L 4.21299911 -1.13 4.20553228 -1.13249951 4 P 0 ;2,4=47,6=0.000000
L 4.20553228 -1.13249951 4.19993346 -1.13875049 4 P 0 ;2,4=47,6=0.000000
L 4.19993346 -1.13875049 4.19619931 -1.14624882 4 P 0 ;2,4=47,6=0.000000
L 4.19619931 -1.14624882 4.1933999 -1.15625128 4 P 0 ;2,4=47,6=0.000000
L 4.1933999 -1.15625128 4.19246673 -1.16750118 4 P 0 ;2,4=47,6=0.000000
L 4.19246673 -1.16750118 4.1933999 -1.17875108 4 P 0 ;2,4=47,6=0.000000
L 4.1933999 -1.17875108 4.19619931 -1.18875128 4 P 0 ;2,4=47,6=0.000000
L 4.19619931 -1.18875128 4.19993346 -1.19625187 4 P 0 ;2,4=47,6=0.000000
L 4.19993346 -1.19625187 4.20553228 -1.20250059 4 P 0 ;2,4=47,6=0.000000
L 4.20553228 -1.20250059 4.21299911 -1.205 4 P 0 ;2,4=47,6=0.000000
L 4.21299911 -1.205 4.22046585 -1.20250059 4 P 0 ;2,4=47,6=0.000000
L 4.22046585 -1.20250059 4.22606644 -1.19625187 4 P 0 ;2,4=47,6=0.000000
L 4.22606644 -1.19625187 4.22980059 -1.18875128 4 P 0 ;2,4=47,6=0.000000
L 4.22980059 -1.18875128 4.2326 -1.17875108 4 P 0 ;2,4=47,6=0.000000
L 4.2326 -1.17875108 4.23353317 -1.16750118 4 P 0 ;2,4=47,6=0.000000
L 4.23353317 -1.16750118 4.2326 -1.15625128 4 P 0 ;2,4=47,6=0.000000
L 4.2326 -1.15625128 4.22980059 -1.14624882 4 P 0 ;2,4=47,6=0.000000
L 4.22980059 -1.14624882 4.22606644 -1.13875049 4 P 0 ;2,4=47,6=0.000000
L 4.22606644 -1.13875049 4.22046585 -1.13249951 4 P 0 ;2,4=47,6=0.000000
L 4.22046585 -1.13249951 4.21299911 -1.13 4 P 0 ;2,4=47,6=0.000000
L 4.27026614 -1.1424997 4.27586663 -1.13500128 4 P 0 ;2,4=47,6=0.000000
L 4.27586663 -1.13500128 4.2824003 -1.1312498 4 P 0 ;2,4=47,6=0.000000
L 4.2824003 -1.1312498 4.28986703 -1.13 4 P 0 ;2,4=47,6=0.000000
L 4.28986703 -1.13 4.2992001 -1.13249951 4 P 0 ;2,4=47,6=0.000000
L 4.2992001 -1.13249951 4.30573376 -1.13875049 4 P 0 ;2,4=47,6=0.000000
L 4.30573376 -1.13875049 4.3076 -1.14624882 4 P 0 ;2,4=47,6=0.000000
L 4.3076 -1.14624882 4.30666693 -1.15375187 4 P 0 ;2,4=47,6=0.000000
L 4.30666693 -1.15375187 4.30293268 -1.16000049 4 P 0 ;2,4=47,6=0.000000
L 4.30293268 -1.16000049 4.28426654 -1.1725001 4 P 0 ;2,4=47,6=0.000000
L 4.28426654 -1.1725001 4.27586663 -1.18125059 4 P 0 ;2,4=47,6=0.000000
L 4.27586663 -1.18125059 4.27026614 -1.19375246 4 P 0 ;2,4=47,6=0.000000
L 4.27026614 -1.19375246 4.2683999 -1.205 4 P 0 ;2,4=47,6=0.000000
L 4.2683999 -1.205 4.3076 -1.205 4 P 0 ;2,4=47,6=0.000000
L 4.35086663 -1.18000079 4.37513327 -1.18000079 4 P 0 ;2,4=47,6=0.000000
L 4.42026614 -1.1424997 4.42586663 -1.13500128 4 P 0 ;2,4=47,6=0.000000
L 4.42586663 -1.13500128 4.4324003 -1.1312498 4 P 0 ;2,4=47,6=0.000000
L 4.4324003 -1.1312498 4.43986703 -1.13 4 P 0 ;2,4=47,6=0.000000
L 4.43986703 -1.13 4.4492001 -1.13249951 4 P 0 ;2,4=47,6=0.000000
L 4.4492001 -1.13249951 4.45573376 -1.13875049 4 P 0 ;2,4=47,6=0.000000
L 4.45573376 -1.13875049 4.4576 -1.14624882 4 P 0 ;2,4=47,6=0.000000
L 4.4576 -1.14624882 4.45666693 -1.15375187 4 P 0 ;2,4=47,6=0.000000
L 4.45666693 -1.15375187 4.45293268 -1.16000049 4 P 0 ;2,4=47,6=0.000000
L 4.45293268 -1.16000049 4.43426654 -1.1725001 4 P 0 ;2,4=47,6=0.000000
L 4.43426654 -1.1725001 4.42586663 -1.18125059 4 P 0 ;2,4=47,6=0.000000
L 4.42586663 -1.18125059 4.42026614 -1.19375246 4 P 0 ;2,4=47,6=0.000000
L 4.42026614 -1.19375246 4.4183999 -1.205 4 P 0 ;2,4=47,6=0.000000
L 4.4183999 -1.205 4.4576 -1.205 4 P 0 ;2,4=47,6=0.000000
L 4.49246673 -1.19375246 4.49806555 -1.20000108 4 P 0 ;2,4=47,6=0.000000
L 4.49806555 -1.20000108 4.50459921 -1.2037503 4 P 0 ;2,4=47,6=0.000000
L 4.50459921 -1.2037503 4.51299911 -1.205 4 P 0 ;2,4=47,6=0.000000
L 4.51299911 -1.205 4.52140069 -1.20250059 4 P 0 ;2,4=47,6=0.000000
L 4.52140069 -1.20250059 4.52793268 -1.19750167 4 P 0 ;2,4=47,6=0.000000
L 4.52793268 -1.19750167 4.5326 -1.18875128 4 P 0 ;2,4=47,6=0.000000
L 4.5326 -1.18875128 4.53353317 -1.17875108 4 P 0 ;2,4=47,6=0.000000
L 4.53353317 -1.17875108 4.53166693 -1.16875089 4 P 0 ;2,4=47,6=0.000000
L 4.53166693 -1.16875089 4.52699951 -1.1625 4 P 0 ;2,4=47,6=0.000000
L 4.52699951 -1.1625 4.52046585 -1.15750108 4 P 0 ;2,4=47,6=0.000000
L 4.52046585 -1.15750108 4.51393396 -1.15625128 4 P 0 ;2,4=47,6=0.000000
L 4.51393396 -1.15625128 4.5074003 -1.15750108 4 P 0 ;2,4=47,6=0.000000
L 4.5074003 -1.15750108 4.49900039 -1.1625 4 P 0 ;2,4=47,6=0.000000
L 4.49900039 -1.1625 4.5017998 -1.13 4 P 0 ;2,4=47,6=0.000000
L 4.5017998 -1.13 4.52699951 -1.13 4 P 0 ;2,4=47,6=0.000000
L 3.29433297 -1.255 3.29433297 -1.33 4 P 0 ;2,4=48,6=0.000000
L 3.29433297 -1.33 3.33166693 -1.33 4 P 0 ;2,4=48,6=0.000000
L 3.40480059 -1.33 3.40480059 -1.28000157 4 P 0 ;2,4=48,6=0.000000
L 3.40480059 -1.2887497 3.40106644 -1.28375079 4 P 0 ;2,4=48,6=0.000000
L 3.40106644 -1.28375079 3.39546585 -1.28125128 4 P 0 ;2,4=48,6=0.000000
L 3.39546585 -1.28125128 3.38893396 -1.28000157 4 P 0 ;2,4=48,6=0.000000
L 3.38893396 -1.28000157 3.3824003 -1.28250108 4 P 0 ;2,4=48,6=0.000000
L 3.3824003 -1.28250108 3.3767998 -1.2875 4 P 0 ;2,4=48,6=0.000000
L 3.3767998 -1.2875 3.37306555 -1.29500069 4 P 0 ;2,4=48,6=0.000000
L 3.37306555 -1.29500069 3.37119931 -1.30500079 4 P 0 ;2,4=48,6=0.000000
L 3.37119931 -1.30500079 3.37306555 -1.31500098 4 P 0 ;2,4=48,6=0.000000
L 3.37306555 -1.31500098 3.3767998 -1.32250167 4 P 0 ;2,4=48,6=0.000000
L 3.3767998 -1.32250167 3.3824003 -1.32750059 4 P 0 ;2,4=48,6=0.000000
L 3.3824003 -1.32750059 3.38893396 -1.33 4 P 0 ;2,4=48,6=0.000000
L 3.38893396 -1.33 3.39546585 -1.3287503 4 P 0 ;2,4=48,6=0.000000
L 3.39546585 -1.3287503 3.40106644 -1.32500108 4 P 0 ;2,4=48,6=0.000000
L 3.40106644 -1.32500108 3.40480059 -1.32000217 4 P 0 ;2,4=48,6=0.000000
L 3.4433999 -1.3524997 3.44900039 -1.35499921 4 P 0 ;2,4=48,6=0.000000
L 3.44900039 -1.35499921 3.45646713 -1.3524997 4 P 0 ;2,4=48,6=0.000000
L 3.45646713 -1.3524997 3.46113287 -1.34750079 4 P 0 ;2,4=48,6=0.000000
L 3.46113287 -1.34750079 3.46486703 -1.3412498 4 P 0 ;2,4=48,6=0.000000
L 3.46486703 -1.3412498 3.47046585 -1.32125187 4 P 0 ;2,4=48,6=0.000000
L 3.47046585 -1.32125187 3.4826 -1.28000157 4 P 0 ;2,4=48,6=0.000000
L 3.45273287 -1.28000157 3.47046585 -1.32125187 4 P 0 ;2,4=48,6=0.000000
L 3.52400039 -1.29625039 3.55386752 -1.29625039 4 P 0 ;2,4=48,6=0.000000
L 3.55386752 -1.29625039 3.55106644 -1.2875 4 P 0 ;2,4=48,6=0.000000
L 3.55106644 -1.2875 3.54640069 -1.28250108 4 P 0 ;2,4=48,6=0.000000
L 3.54640069 -1.28250108 3.53986703 -1.28000157 4 P 0 ;2,4=48,6=0.000000
L 3.53986703 -1.28000157 3.53333346 -1.28125128 4 P 0 ;2,4=48,6=0.000000
L 3.53333346 -1.28125128 3.52773287 -1.28500049 4 P 0 ;2,4=48,6=0.000000
L 3.52773287 -1.28500049 3.52400039 -1.29375089 4 P 0 ;2,4=48,6=0.000000
L 3.52400039 -1.29375089 3.52213238 -1.30125157 4 P 0 ;2,4=48,6=0.000000
L 3.52213238 -1.30125157 3.52213238 -1.30875 4 P 0 ;2,4=48,6=0.000000
L 3.52213238 -1.30875 3.52400039 -1.31625069 4 P 0 ;2,4=48,6=0.000000
L 3.52400039 -1.31625069 3.52866604 -1.32375138 4 P 0 ;2,4=48,6=0.000000
L 3.52866604 -1.32375138 3.53426654 -1.3287503 4 P 0 ;2,4=48,6=0.000000
L 3.53426654 -1.3287503 3.5408002 -1.33 4 P 0 ;2,4=48,6=0.000000
L 3.5408002 -1.33 3.54733386 -1.32750059 4 P 0 ;2,4=48,6=0.000000
L 3.54733386 -1.32750059 3.55386752 -1.32000217 4 P 0 ;2,4=48,6=0.000000
L 3.59993346 -1.33 3.59993346 -1.28000157 4 P 0 ;2,4=48,6=0.000000
L 3.59993346 -1.28999941 3.60459921 -1.28500049 4 P 0 ;2,4=48,6=0.000000
L 3.60459921 -1.28500049 3.60926654 -1.28125128 4 P 0 ;2,4=48,6=0.000000
L 3.60926654 -1.28125128 3.6158002 -1.28000157 4 P 0 ;2,4=48,6=0.000000
L 3.6158002 -1.28000157 3.62046585 -1.28125128 4 P 0 ;2,4=48,6=0.000000
L 3.62046585 -1.28125128 3.62606644 -1.28500049 4 P 0 ;2,4=48,6=0.000000
L 3.68799911 -1.33249941 3.68613287 -1.3312497 4 P 0 ;2,4=48,6=0.000000
L 3.68613287 -1.3312497 3.68613287 -1.3287503 4 P 0 ;2,4=48,6=0.000000
L 3.68613287 -1.3287503 3.68799911 -1.32750059 4 P 0 ;2,4=48,6=0.000000
L 3.68799911 -1.32750059 3.68986703 -1.3287503 4 P 0 ;2,4=48,6=0.000000
L 3.68986703 -1.3287503 3.68986703 -1.3312497 4 P 0 ;2,4=48,6=0.000000
L 3.68986703 -1.3312497 3.68799911 -1.33249941 4 P 0 ;2,4=48,6=0.000000
L 3.68799911 -1.29875217 3.68613287 -1.2975001 4 P 0 ;2,4=48,6=0.000000
L 3.68613287 -1.2975001 3.68613287 -1.29500069 4 P 0 ;2,4=48,6=0.000000
L 3.68613287 -1.29500069 3.68799911 -1.29375089 4 P 0 ;2,4=48,6=0.000000
L 3.68799911 -1.29375089 3.68986703 -1.29500069 4 P 0 ;2,4=48,6=0.000000
L 3.68986703 -1.29500069 3.68986703 -1.2975001 4 P 0 ;2,4=48,6=0.000000
L 3.68986703 -1.2975001 3.68799911 -1.29875217 4 P 0 ;2,4=48,6=0.000000
L 3.36933297 -1.08 3.36933297 -1.005 4 P 0 ;2,4=49,6=0.000000
L 3.36933297 -1.005 3.39266644 -1.005 4 P 0 ;2,4=49,6=0.000000
L 3.39266644 -1.005 3.40013327 -1.00875157 4 P 0 ;2,4=49,6=0.000000
L 3.40013327 -1.00875157 3.40480059 -1.01375049 4 P 0 ;2,4=49,6=0.000000
L 3.40480059 -1.01375049 3.40666693 -1.02375059 4 P 0 ;2,4=49,6=0.000000
L 3.40666693 -1.02375059 3.40480059 -1.03375079 4 P 0 ;2,4=49,6=0.000000
L 3.40480059 -1.03375079 3.3992001 -1.03999941 4 P 0 ;2,4=49,6=0.000000
L 3.3992001 -1.03999941 3.39266644 -1.04375089 4 P 0 ;2,4=49,6=0.000000
L 3.39266644 -1.04375089 3.36933297 -1.04375089 4 P 0 ;2,4=49,6=0.000000
L 3.39266644 -1.04375089 3.40666693 -1.08 4 P 0 ;2,4=49,6=0.000000
L 3.44900039 -1.04625039 3.47886752 -1.04625039 4 P 0 ;2,4=49,6=0.000000
L 3.47886752 -1.04625039 3.47606644 -1.0375 4 P 0 ;2,4=49,6=0.000000
L 3.47606644 -1.0375 3.47140069 -1.03250108 4 P 0 ;2,4=49,6=0.000000
L 3.47140069 -1.03250108 3.46486703 -1.03000157 4 P 0 ;2,4=49,6=0.000000
L 3.46486703 -1.03000157 3.45833346 -1.03125128 4 P 0 ;2,4=49,6=0.000000
L 3.45833346 -1.03125128 3.45273287 -1.03500049 4 P 0 ;2,4=49,6=0.000000
L 3.45273287 -1.03500049 3.44900039 -1.04375089 4 P 0 ;2,4=49,6=0.000000
L 3.44900039 -1.04375089 3.44713238 -1.05125157 4 P 0 ;2,4=49,6=0.000000
L 3.44713238 -1.05125157 3.44713238 -1.05875 4 P 0 ;2,4=49,6=0.000000
L 3.44713238 -1.05875 3.44900039 -1.06625069 4 P 0 ;2,4=49,6=0.000000
L 3.44900039 -1.06625069 3.45366604 -1.07375138 4 P 0 ;2,4=49,6=0.000000
L 3.45366604 -1.07375138 3.45926654 -1.0787503 4 P 0 ;2,4=49,6=0.000000
L 3.45926654 -1.0787503 3.4658002 -1.08 4 P 0 ;2,4=49,6=0.000000
L 3.4658002 -1.08 3.47233386 -1.07750059 4 P 0 ;2,4=49,6=0.000000
L 3.47233386 -1.07750059 3.47886752 -1.07000217 4 P 0 ;2,4=49,6=0.000000
L 3.52119931 -1.03000157 3.53799911 -1.08 4 P 0 ;2,4=49,6=0.000000
L 3.53799911 -1.08 3.55480059 -1.03000157 4 P 0 ;2,4=49,6=0.000000
L 3.68799911 -1.08249941 3.68613287 -1.0812497 4 P 0 ;2,4=49,6=0.000000
L 3.68613287 -1.0812497 3.68613287 -1.0787503 4 P 0 ;2,4=49,6=0.000000
L 3.68613287 -1.0787503 3.68799911 -1.07750059 4 P 0 ;2,4=49,6=0.000000
L 3.68799911 -1.07750059 3.68986703 -1.0787503 4 P 0 ;2,4=49,6=0.000000
L 3.68986703 -1.0787503 3.68986703 -1.0812497 4 P 0 ;2,4=49,6=0.000000
L 3.68986703 -1.0812497 3.68799911 -1.08249941 4 P 0 ;2,4=49,6=0.000000
L 3.68799911 -1.04875217 3.68613287 -1.0475001 4 P 0 ;2,4=49,6=0.000000
L 3.68613287 -1.0475001 3.68613287 -1.04500069 4 P 0 ;2,4=49,6=0.000000
L 3.68613287 -1.04500069 3.68799911 -1.04375089 4 P 0 ;2,4=49,6=0.000000
L 3.68799911 -1.04375089 3.68986703 -1.04500069 4 P 0 ;2,4=49,6=0.000000
L 3.68986703 -1.04500069 3.68986703 -1.0475001 4 P 0 ;2,4=49,6=0.000000
L 3.68986703 -1.0475001 3.68799911 -1.04875217 4 P 0 ;2,4=49,6=0.000000
L 3.83799911 -1.005 3.83053228 -1.00749951 4 P 0 ;2,4=49,6=0.000000
L 3.83053228 -1.00749951 3.82493346 -1.01375049 4 P 0 ;2,4=49,6=0.000000
L 3.82493346 -1.01375049 3.82119931 -1.02124882 4 P 0 ;2,4=49,6=0.000000
L 3.82119931 -1.02124882 3.8183999 -1.03125128 4 P 0 ;2,4=49,6=0.000000
L 3.8183999 -1.03125128 3.81746673 -1.04250118 4 P 0 ;2,4=49,6=0.000000
L 3.81746673 -1.04250118 3.8183999 -1.05375108 4 P 0 ;2,4=49,6=0.000000
L 3.8183999 -1.05375108 3.82119931 -1.06375128 4 P 0 ;2,4=49,6=0.000000
L 3.82119931 -1.06375128 3.82493346 -1.07125187 4 P 0 ;2,4=49,6=0.000000
L 3.82493346 -1.07125187 3.83053228 -1.07750059 4 P 0 ;2,4=49,6=0.000000
L 3.83053228 -1.07750059 3.83799911 -1.08 4 P 0 ;2,4=49,6=0.000000
L 3.83799911 -1.08 3.84546585 -1.07750059 4 P 0 ;2,4=49,6=0.000000
L 3.84546585 -1.07750059 3.85106644 -1.07125187 4 P 0 ;2,4=49,6=0.000000
L 3.85106644 -1.07125187 3.85480059 -1.06375128 4 P 0 ;2,4=49,6=0.000000
L 3.85480059 -1.06375128 3.8576 -1.05375108 4 P 0 ;2,4=49,6=0.000000
L 3.8576 -1.05375108 3.85853317 -1.04250118 4 P 0 ;2,4=49,6=0.000000
L 3.85853317 -1.04250118 3.8576 -1.03125128 4 P 0 ;2,4=49,6=0.000000
L 3.8576 -1.03125128 3.85480059 -1.02124882 4 P 0 ;2,4=49,6=0.000000
L 3.85480059 -1.02124882 3.85106644 -1.01375049 4 P 0 ;2,4=49,6=0.000000
L 3.85106644 -1.01375049 3.84546585 -1.00749951 4 P 0 ;2,4=49,6=0.000000
L 3.84546585 -1.00749951 3.83799911 -1.005 4 P 0 ;2,4=49,6=0.000000
L 3.91299911 -1.08 3.91299911 -1.005 4 P 0 ;2,4=49,6=0.000000
L 3.91299911 -1.005 3.9017998 -1.01999911 4 P 0 ;2,4=49,6=0.000000
L 3.9017998 -1.08 3.92419843 -1.08 4 P 0 ;2,4=49,6=0.000000

### steps/pcb/layers/comp_+_bot/features


### steps/pcb/layers/comp_+_top/features


### steps/pcb/layers/drill/features
#
#Num Features
#
F 2591

#
#Units
#
U INCH

#
#Feature symbol names
#
$0 r8
$1 r10
$2 r12
$3 r16
$4 r24
$5 r33
$6 r59
$7 r63
$8 r76
$9 r79
$10 r100
$11 r118
$12 r125
$13 r166

#
#Feature attribute names
#
@0 .pf_optimized
@1 .geometry
@2 .drill

#
#Feature attribute text strings
#
&0 059C086P
&1 063C090P
&2 033C057P
&3 024X051OB071X075P_L
&4 024X051OB071X075P_R
&5 016C024P
&6 024X063OB035X075P
&7 079C100P
&8 166CT244CB198P
&9 V012C024-NTH
&10 MTH125C115N
&11 MTH100C090N
&12 076S104P
&13 076C104P
&14 MTH118C108N
&15 TPV010CT020B030
&16 V010C020P
&17 V010C020P_SM014-NTH
&18 V010C020P_TP030B
&19 V008C018P
&20 V008C018P-ANTI28-NSM
&21 V008C018P_ANTI026_NSM
&22 V008C018P_ANTI026_TP030B
&23 V008C018P_ANTI28
&24 V008C018P_NATI28_TP030B_NSMT
&25 V008C018P_TP030B

#
#Layer features
#
P 0.16038996 1.28346004 6 P 8 8 0;0,1=0,2=0
P 0.06038996 1.38346004 7 P 9 8 0;0,1=1,2=0
P 0.26038996 1.38346004 7 P 9 8 0;0,1=1,2=0
P 0.06038996 1.18346004 7 P 9 8 0;0,1=1,2=0
P 0.26038996 1.18346004 7 P 9 8 0;0,1=1,2=0
P 6.40951998 2.01181004 5 P 7 8 0;0,1=2,2=0
P 6.40951998 2.20866998 5 P 7 8 0;0,1=2,2=0
L 6.50231998 1.97243996 6.52931998 1.97243996 4 P 6 ;1=3,2=0
L 6.50231998 2.24803996 6.52931998 2.24803996 4 P 6 ;1=4,2=0
P 0.24606004 3.4315 3 P 5 8 0;0,1=5,2=0
P 0.2815 3.4315 3 P 5 8 0;0,1=5,2=0
P 0.31693996 3.4315 3 P 5 8 0;0,1=5,2=0
P 0.35238002 3.4315 3 P 5 8 0;0,1=5,2=0
P 0.38781998 3.4315 3 P 5 8 0;0,1=5,2=0
P 0.42326004 3.4315 3 P 5 8 0;0,1=5,2=0
P 0.4587 3.4315 3 P 5 8 0;0,1=5,2=0
P 0.44098002 3.4008 3 P 5 8 0;0,1=5,2=0
P 0.40553996 3.4008 3 P 5 8 0;0,1=5,2=0
P 0.3701 3.4008 3 P 5 8 0;0,1=5,2=0
P 0.33466004 3.4008 3 P 5 8 0;0,1=5,2=0
P 0.29921998 3.4008 3 P 5 8 0;0,1=5,2=0
P 0.26378002 3.4008 3 P 5 8 0;0,1=5,2=0
P 0.22833996 3.4008 3 P 5 8 0;0,1=5,2=0
L 0.45655 3.51576004 0.41755 3.51576004 4 P 6 ;1=6,2=0
L 0.45655 3.31655 0.41755 3.31655 4 P 6 ;1=6,2=0
L 0.26756998 3.47245 0.22856998 3.47245 4 P 6 ;1=6,2=0
L 0.26756998 3.35985 0.22856998 3.35985 4 P 6 ;1=6,2=0
P 0.16038996 0.7126 6 P 8 8 0;0,1=0,2=0
P 0.06038996 0.8126 7 P 9 8 0;0,1=1,2=0
P 0.26038996 0.8126 7 P 9 8 0;0,1=1,2=0
P 0.06038996 0.6126 7 P 9 8 0;0,1=1,2=0
P 0.26038996 0.6126 7 P 9 8 0;0,1=1,2=0
P 0.16038996 2.4252 6 P 8 8 0;0,1=0,2=0
P 0.06038996 2.5252 7 P 9 8 0;0,1=1,2=0
P 0.26038996 2.5252 7 P 9 8 0;0,1=1,2=0
P 0.06038996 2.3252 7 P 9 8 0;0,1=1,2=0
P 0.26038996 2.3252 7 P 9 8 0;0,1=1,2=0
P 0.16038996 1.85433002 6 P 8 8 0;0,1=0,2=0
P 0.06038996 1.95433002 7 P 9 8 0;0,1=1,2=0
P 0.26038996 1.95433002 7 P 9 8 0;0,1=1,2=0
P 0.06038996 1.75433002 7 P 9 8 0;0,1=1,2=0
P 0.26038996 1.75433002 7 P 9 8 0;0,1=1,2=0
P 1.26066998 2.64043002 9 P 11 8 0;0,1=7,2=0
P 1.26066998 1.84043002 9 P 11 8 0;0,1=7,2=0
P 1.26066998 1.04043002 9 P 11 8 0;0,1=7,2=0
P 2.86066998 1.04043002 9 P 11 8 0;0,1=7,2=0
P 2.86066998 2.64043002 9 P 11 8 0;0,1=7,2=0
P 2.77866998 0.93443002 9 P 11 8 0;0,1=7,2=0
P 2.65966998 0.93443002 9 P 11 8 0;0,1=7,2=0
P 2.53966998 0.93443002 9 P 11 8 0;0,1=7,2=0
P 2.55906004 4.12008002 13 P 15 8 0;0,1=8,2=0
P 0.29528002 0.46461004 2 P 4 8 0;0,1=9,2=0
P 0.36351998 0.43635 2 P 4 8 0;0,1=9,2=0
P 0.39178002 0.36811004 2 P 4 8 0;0,1=9,2=0
P 0.36351998 0.29986998 2 P 4 8 0;0,1=9,2=0
P 0.29528002 0.27161004 2 P 4 8 0;0,1=9,2=0
P 0.22703996 0.29986998 2 P 4 8 0;0,1=9,2=0
P 0.19878002 0.36811004 2 P 4 8 0;0,1=9,2=0
P 0.22703996 0.43635 2 P 4 8 0;0,1=9,2=0
P 0.29528002 0.36811004 12 P 14 8 0;0,1=10,2=1
P 6.40038996 4.27485 2 P 4 8 0;0,1=9,2=0
P 6.46863002 4.24658996 2 P 4 8 0;0,1=9,2=0
P 6.49688996 4.17835 2 P 4 8 0;0,1=9,2=0
P 6.46863002 4.11011004 2 P 4 8 0;0,1=9,2=0
P 6.40038996 4.08185 2 P 4 8 0;0,1=9,2=0
P 6.33215 4.11011004 2 P 4 8 0;0,1=9,2=0
P 6.30388996 4.17835 2 P 4 8 0;0,1=9,2=0
P 6.33215 4.24658996 2 P 4 8 0;0,1=9,2=0
P 6.40038996 4.17835 12 P 14 8 0;0,1=10,2=1
P 6.40038996 0.75003996 2 P 4 8 0;0,1=9,2=0
P 6.46863002 0.72178002 2 P 4 8 0;0,1=9,2=0
P 6.49688996 0.65353996 2 P 4 8 0;0,1=9,2=0
P 6.46863002 0.5853 2 P 4 8 0;0,1=9,2=0
P 6.40038996 0.55703996 2 P 4 8 0;0,1=9,2=0
P 6.33215 0.5853 2 P 4 8 0;0,1=9,2=0
P 6.30388996 0.65353996 2 P 4 8 0;0,1=9,2=0
P 6.33215 0.72178002 2 P 4 8 0;0,1=9,2=0
P 6.40038996 0.65353996 12 P 14 8 0;0,1=10,2=1
P 2.55906004 3.09646004 13 P 15 8 0;0,1=8,2=0
P 4.94093996 4.12008002 13 P 15 8 0;0,1=8,2=0
P 4.94093996 3.09646004 13 P 15 8 0;0,1=8,2=0
P 1.46066998 2.68043002 10 P 12 8 0;0,1=11,2=1
P 2.68566998 2.55943002 10 P 12 8 0;0,1=11,2=1
P 1.43566998 1.06043002 10 P 12 8 0;0,1=11,2=1
P 2.68566998 1.12143002 10 P 12 8 0;0,1=11,2=1
P 0.29528002 3.82681004 2 P 4 8 0;0,1=9,2=0
P 0.36351998 3.79855 2 P 4 8 0;0,1=9,2=0
P 0.39178002 3.73031004 2 P 4 8 0;0,1=9,2=0
P 0.36351998 3.66206998 2 P 4 8 0;0,1=9,2=0
P 0.29528002 3.63381004 2 P 4 8 0;0,1=9,2=0
P 0.22703996 3.66206998 2 P 4 8 0;0,1=9,2=0
P 0.19878002 3.73031004 2 P 4 8 0;0,1=9,2=0
P 0.22703996 3.79855 2 P 4 8 0;0,1=9,2=0
P 0.29528002 3.73031004 12 P 14 8 0;0,1=10,2=1
P 6.05315 3.67518996 8 P 10 8 0;0,1=12,2=0
P 6.05315 3.50983996 8 P 10 8 0;0,1=13,2=0
P 6.05315 3.34448996 8 P 10 8 0;0,1=13,2=0
P 5.88778996 3.67518996 8 P 10 8 0;0,1=13,2=0
P 5.88778996 3.50983996 8 P 10 8 0;0,1=13,2=0
P 5.88778996 3.34448996 8 P 10 8 0;0,1=13,2=0
P 6.34055 3.34448996 11 P 13 8 0;0,1=14,2=1
P 6.34055 3.67518996 11 P 13 8 0;0,1=14,2=1
P 3.32 3.015 1 P 2 8 0;0,1=15,2=0
P 0.95 2.915 1 P 2 8 0;0,1=15,2=0
P 0.995 3.7 1 P 2 8 0;0,1=15,2=0
P 4.795 0.925 1 P 2 8 0;0,1=15,2=0
P 4.08 3.27 1 P 2 8 0;0,1=15,2=0
P 4.73806998 1.54816004 1 P 2 8 0;0,1=15,2=0
P 4.73806998 1.50878996 1 P 2 8 0;0,1=15,2=0
P 5.03 1.55 1 P 2 8 0;0,1=15,2=0
P 4.975 1.485 1 P 2 8 0;0,1=15,2=0
P 4.85 1.54 1 P 2 8 0;0,1=15,2=0
P 4.91 1.54 1 P 2 8 0;0,1=15,2=0
P 5.035 1.49 1 P 2 8 0;0,1=15,2=0
P 4.915 1.485 1 P 2 8 0;0,1=15,2=0
P 3.95 3.82 1 P 2 8 0;0,1=15,2=0
P 4.61996004 1.6269 1 P 2 8 0;0,1=15,2=0
P 4.65933002 1.6269 1 P 2 8 0;0,1=15,2=0
P 4.67 3.555 1 P 2 8 0;0,1=15,2=0
P 3.235 2.63 1 P 2 8 0;0,1=15,2=0
P 3.305 2.65 1 P 2 8 0;0,1=15,2=0
P 3.375 2.65 1 P 2 8 0;0,1=15,2=0
P 3.83 2.325 1 P 2 8 0;0,1=15,2=0
P 3.75 2.1 1 P 2 8 0;0,1=15,2=0
P 3.8 2.1 1 P 2 8 0;0,1=15,2=0
P 4.149 2.298 1 P 2 8 0;0,1=15,2=0
P 4.161 2.354 1 P 2 8 0;0,1=15,2=0
P 4.23 2.354 1 P 2 8 0;0,1=15,2=0
P 3.94 2.235 1 P 2 8 0;0,1=15,2=0
P 4.205 2.295 1 P 2 8 0;0,1=15,2=0
P 4.254 2.296 1 P 2 8 0;0,1=15,2=0
P 3.445 2.65 1 P 2 8 0;0,1=15,2=0
P 4.768 1.207 1 P 2 8 0;0,1=15,2=0
P 4.828 1.103 1 P 2 8 0;0,1=15,2=0
P 4.15 1.235 1 P 2 8 0;0,1=15,2=0
P 4.185 1.17 1 P 2 8 0;0,1=15,2=0
P 4.83 1.33 1 P 2 8 0;0,1=15,2=0
P 3.24 3.01 1 P 2 8 0;0,1=15,2=0
P 0.755 0.62 1 P 2 8 0;0,1=15,2=0
P 4.22 1.235 1 P 2 8 0;0,1=15,2=0
P 4.816 1.258 1 P 2 8 0;0,1=15,2=0
P 4.665 1.104 1 P 2 8 0;0,1=15,2=0
P 4.712 1.157 1 P 2 8 0;0,1=15,2=0
P 4.29 1.235 1 P 2 8 0;0,1=15,2=0
P 3.37 3.44 1 P 2 8 0;0,1=15,2=0
P 5.8 1.048 1 P 2 8 0;0,1=15,2=0
P 2.017 3.279 1 P 2 8 0;0,1=15,2=0
P 0.636 2.915 1 P 2 8 0;0,1=15,2=0
P 4.3 3.865 1 P 2 8 0;0,1=15,2=0
P 5.955 2.39 1 P 2 8 0;0,1=15,2=0
P 5.87 1.84 1 P 2 8 0;0,1=15,2=0
P 0.575 2.265 1 P 2 8 0;0,1=15,2=0
P 0.545 1.71 1 P 2 8 0;0,1=15,2=0
P 1.535 3.105 1 P 2 8 0;0,1=15,2=0
P 0.565 1.13 1 P 2 8 0;0,1=15,2=0
P 0.644 0.7 1 P 2 8 0;0,1=15,2=0
P 0.647 2.517 1 P 2 8 0;0,1=15,2=0
P 0.62 1.995 1 P 2 8 0;0,1=15,2=0
P 0.645 1.295 1 P 2 8 0;0,1=15,2=0
P 0.635 0.845 1 P 2 8 0;0,1=15,2=0
P 5.6 4.01 1 P 2 8 0;0,1=15,2=0
P 5.718 3.965 1 P 2 8 0;0,1=15,2=0
P 3.745 4.185 1 P 2 8 0;0,1=15,2=0
P 5.76 2.465 1 P 2 8 0;0,1=15,2=0
P 0.71 3.305 1 P 2 8 0;0,1=15,2=0
P 4.831 2.728 1 P 2 8 0;0,1=15,2=0
P 5.765 0.98 1 P 2 8 0;0,1=15,2=0
P 0.978 3.918 1 P 2 8 0;0,1=15,2=0
P 5.66 3.47 1 P 2 8 0;0,1=15,2=0
P 5.3 4.065 1 P 2 8 0;0,1=15,2=0
P 4.82 2.125 1 P 2 8 0;0,1=15,2=0
P 5.41 0.96 1 P 2 8 0;1=15,2=0
P 3.746 1.782 1 P 2 8 0;0,1=15,2=0
P 2.29581998 0.48918002 1 P 2 8 0;0,1=15,2=0
P 4.205 0.82 1 P 2 8 0;0,1=15,2=0
P 0.78 3.305 1 P 2 8 0;0,1=15,2=0
P 3.705 0.84 1 P 2 8 0;0,1=15,2=0
P 3.065 1.695 1 P 2 8 0;0,1=15,2=0
P 5.406 2.346 1 P 2 8 0;0,1=15,2=0
P 4.29 2.74 1 P 2 8 0;0,1=15,2=0
P 5.58 1.615 1 P 2 8 0;0,1=15,2=0
P 3.655 2.795 1 P 2 8 0;0,1=15,2=0
P 5.345 2.536 1 P 2 8 0;0,1=15,2=0
P 5.445 0.795 1 P 2 8 0;0,1=15,2=0
P 3.58 2.615 1 P 2 8 0;0,1=15,2=0
P 3.69 4.135 1 P 2 8 0;0,1=15,2=0
P 0.795 3.085 1 P 2 8 0;0,1=15,2=0
P 2.25 3.96 1 P 2 8 0;0,1=15,2=0
P 3.385 2.135 1 P 2 8 0;0,1=15,2=0
P 4.97 1.54 1 P 2 8 0;0,1=15,2=0
P 0.875 2.955 1 P 2 8 0;0,1=15,2=0
P 3.9 2.325 1 P 2 8 0;0,1=15,2=0
P 0.885 3.03 1 P 2 8 0;0,1=15,2=0
P 0.945 2.99 1 P 2 8 0;0,1=15,2=0
P 0.525 2.78 1 P 3 8 0;0,1=16,2=2
P 0.48231998 2.6453 1 P 3 8 0;0,1=16,2=2
P 0.45 2.13 1 P 3 8 0;0,1=16,2=2
P 0.54 2.135 1 P 3 8 0;0,1=16,2=2
P 0.4839 1.28311998 1 P 3 8 0;0,1=16,2=2
P 0.625 1.005 1 P 3 8 0;1=16,2=2
P 2.078 0.8301 1 P 3 8 0;1=16,2=2
P 4.175 0.75 1 P 3 8 0;0,1=16,2=2
P 4.6 0.76 1 P 3 8 0;0,1=16,2=2
P 0.905 1.05 1 P 3 8 0;0,1=16,2=2
P 4.975 2.14 1 P 3 8 0;0,1=16,2=2
P 1.889 0.5496 1 P 3 8 0;0,1=16,2=2
P 3.495 0.61 1 P 3 8 0;1=16,2=2
P 5.04 0.645 1 P 3 8 0;0,1=16,2=2
P 3.545 0.6092 1 P 3 8 0;1=16,2=2
P 5.085 0.645 1 P 3 8 0;0,1=16,2=2
P 0.695 1.3 1 P 3 8 0;0,1=16,2=2
P 0.76321004 0.783 1 P 3 8 0;0,1=16,2=2
P 0.74 1.3 1 P 3 8 0;0,1=16,2=2
P 0.785 0.8225 1 P 3 8 0;0,1=16,2=2
P 4.085 3.165 1 P 3 8 0;0,1=16,2=2
P 4.33 3.1432 1 P 3 8 0;0,1=16,2=2
P 4.35143002 3.06643002 1 P 3 8 0;0,1=16,2=2
P 4.365 2.33 1 P 3 8 0;0,1=16,2=2
P 4.565 3.055 1 P 3 8 0;0,1=16,2=2
P 4.85033002 1.74933996 1 P 3 8 0;0,1=16,2=2
P 5.26 2.955 1 P 3 8 0;0,1=16,2=2
P 4.35 2.505 1 P 3 8 0;0,1=16,2=2
P 4.61 2.345 1 P 3 8 0;0,1=16,2=2
P 4.485 2.5 1 P 3 8 0;0,1=16,2=2
P 4.575 2.374 1 P 3 8 0;0,1=16,2=2
P 4.53 2.5 1 P 3 8 0;0,1=16,2=2
P 4.685 2.645 1 P 3 8 0;0,1=16,2=2
P 3.12 2.69 1 P 3 8 0;1=16,2=2
P 3.125 2.254 1 P 3 8 0;0,1=16,2=2
P 4.885 3.46 1 P 3 8 0;0,1=16,2=2
P 3.125 3.075 1 P 3 8 0;1=16,2=2
P 4.775 1.705 1 P 3 8 0;0,1=16,2=2
P 5.155 2.01 1 P 3 8 0;0,1=16,2=2
P 3.978 2.468 1 P 3 8 0;0,1=16,2=2
P 5.13 2.105 1 P 3 8 0;0,1=16,2=2
P 3.919 2.468 1 P 3 8 0;0,1=16,2=2
P 5.115 2.065 1 P 3 8 0;0,1=16,2=2
P 3.86 2.468 1 P 3 8 0;0,1=16,2=2
P 5.135 2.155 1 P 3 8 0;0,1=16,2=2
P 3.801 2.468 1 P 3 8 0;0,1=16,2=2
P 5.09 2.155 1 P 3 8 0;0,1=16,2=2
P 4.037 2.468 1 P 3 8 0;0,1=16,2=2
P 4.093 2.468 1 P 3 8 0;0,1=16,2=2
P 4.975 2.26 1 P 3 8 0;0,1=16,2=2
P 4.209 2.468 1 P 3 8 0;0,1=16,2=2
P 4.685 2.7 1 P 3 8 0;0,1=16,2=2
P 4.15 2.468 1 P 3 8 0;0,1=16,2=2
P 4.615 2.68408996 1 P 3 8 0;0,1=16,2=2
P 4.615 3.11 1 P 3 8 0;0,1=16,2=2
P 3.674 1.744 1 P 3 8 0;0,1=16,2=2
P 3.74 1.41 1 P 3 8 0;0,1=16,2=2
P 3.765 1.41 1 P 3 8 0;0,1=16,2=2
P 3.79 1.41 1 P 3 8 0;0,1=16,2=2
P 3.12 2.565 1 P 3 8 0;1=16,2=2
P 0.975 2.14 1 P 3 8 0;1=16,2=2
P 0.395 3.09 1 P 3 8 0;0,1=16,2=2
P 0.99 2.065 1 P 3 8 0;1=16,2=2
P 0.345 3.09 1 P 3 8 0;0,1=16,2=2
P 0.99 1.885 1 P 3 8 0;1=16,2=2
P 3.445 1.815 1 P 3 8 0;0,1=16,2=2
P 4.13 3.005 1 P 3 8 0;0,1=16,2=2
P 4.39 3.02 1 P 3 8 0;0,1=16,2=2
P 4.075 3.005 1 P 3 8 0;0,1=16,2=2
P 4.345 3.02 1 P 3 8 0;0,1=16,2=2
P 3.73648996 1.85735 1 P 3 8 0;0,1=16,2=2
P 4.33 3.535 1 P 3 8 0;0,1=16,2=2
P 5.83 2.97 1 P 3 8 0;1=16,2=2
P 0.236 1.48798002 1 P 3 8 0;0,1=16,2=2
P 0.371 1.48798002 1 P 3 8 0;0,1=16,2=2
P 0.281 1.48798002 1 P 3 8 0;0,1=16,2=2
P 0.63 2.06 1 P 3 8 0;0,1=16,2=2
P 0.99 1.975 1 P 3 8 0;0,1=16,2=2
P 0.63 2.105 1 P 3 8 0;0,1=16,2=2
P 0.99 2.015 1 P 3 8 0;0,1=16,2=2
P 0.287 2.62508002 1 P 3 8 0;0,1=16,2=2
P 0.63 2.15 1 P 3 8 0;0,1=16,2=2
P 4.575 2.275 1 P 3 8 0;0,1=16,2=2
P 4.575 2.235 1 P 3 8 0;0,1=16,2=2
P 5.015 1.925 1 P 3 8 0;0,1=16,2=2
P 1.46 3.34 1 P 3 8 0;0,1=16,2=2
P 2.255 3.475 1 P 3 8 0;1=16,2=2
P 5.09 3.405 1 P 3 8 0;1=16,2=2
P 1.35 3.12 1 P 3 8 0;0,1=16,2=2
P 2.3 3.475 1 P 3 8 0;1=16,2=2
P 5.045 3.405 1 P 3 8 0;1=16,2=2
P 4.135 3.735 1 P 3 8 0;0,1=16,2=2
P 3.895 3.7 1 P 3 8 0;0,1=16,2=2
P 4.19 3.735 1 P 3 8 0;0,1=16,2=2
P 4.205 3.81 1 P 3 8 0;0,1=16,2=2
P 3.62 1.235 1 P 3 8 0;0,1=16,2=2
P 4.937 0.79161004 1 P 3 8 0;0,1=16,2=2
P 0.66 3.235 1 P 3 8 0;0,1=16,2=2
P 3.62 1.28 1 P 3 8 0;0,1=16,2=2
P 4.96 0.85 1 P 3 8 0;0,1=16,2=2
P 0.66 3.185 1 P 3 8 0;0,1=16,2=2
P 0.795 3.4179 1 P 3 8 0;0,1=16,2=2
P 0.825 3.39 1 P 3 8 0;0,1=16,2=2
P 3.38 1.025 1 P 3 8 0;0,1=16,2=2
P 0.62 3.235 1 P 3 8 0;0,1=16,2=2
P 4.34 3.28 1 P 3 8 0;0,1=16,2=2
P 4.51 3.065 1 P 3 8 0;0,1=16,2=2
P 4.1184 3.5362 1 P 3 8 0;0,1=16,2=2
P 0.915 3.595 1 P 3 8 0;0,1=16,2=2
P 0.835 3.6 1 P 3 8 0;0,1=16,2=2
P 1.015 3.41 1 P 3 8 0;0,1=16,2=2
P 0.975 3.41 1 P 3 8 0;0,1=16,2=2
P 1.04018996 3.47425 1 P 3 8 0;0,1=16,2=2
P 1.29 3.215 1 P 3 8 0;0,1=16,2=2
P 1.3 3.49663996 1 P 3 8 0;0,1=16,2=2
P 4.285 3.46 1 P 3 8 0;0,1=16,2=2
P 0.18 3.145 1 P 3 8 0;0,1=16,2=2
P 0.43 3.145 1 P 3 8 0;0,1=16,2=2
P 0.33 3.145 1 P 3 8 0;0,1=16,2=2
P 3.325 3.065 1 P 3 8 0;0,1=16,2=2
P 3.28 3.065 1 P 3 8 0;0,1=16,2=2
P 2.265 3.34 1 P 3 8 0;0,1=16,2=2
P 4.02 3.03 1 P 3 8 0;0,1=16,2=2
P 4.57 2.585 1 P 3 8 0;0,1=16,2=2
P 0.645 2.9675 1 P 3 8 0;0,1=16,2=2
P 2.225 3.245 1 P 3 8 0;0,1=16,2=2
P 4.025 3.08 1 P 3 8 0;0,1=16,2=2
P 4.595 2.62 1 P 3 8 0;0,1=16,2=2
P 0.62 3.07 1 P 3 8 0;0,1=16,2=2
P 2.98283996 1.75183996 1 P 3 8 0;0,1=16,2=2
P 3.405 0.87 1 P 3 8 0;0,1=16,2=2
P 4.78 0.78 1 P 3 8 0;0,1=16,2=2
P 0.965 0.98 1 P 3 8 0;0,1=16,2=2
P 3.455 0.87 1 P 3 8 0;0,1=16,2=2
P 0.8825 1.7725 1 P 3 8 0;0,1=16,2=2
P 0.9225 0.9775 1 P 3 8 0;0,1=16,2=2
P 5.08 1.055 1 P 3 8 0;0,1=16,2=2
P 5.08 1.155 1 P 3 8 0;0,1=16,2=2
P 2.0816 0.7399 1 P 3 8 0;0,1=16,2=2
P 5.132 0.66 1 P 3 8 0;1=16,2=2
P 5.225 1.145 1 P 3 8 0;0,1=16,2=2
P 5.08 1.105 1 P 3 8 0;0,1=16,2=2
P 3.12 2.645 1 P 3 8 0;1=16,2=2
P 3.65 2.68 1 P 3 8 0;0,1=16,2=2
P 0.905 1.445 1 P 3 8 0;0,1=16,2=2
P 1.512 0.75191004 1 P 3 8 0;0,1=16,2=2
P 0.965 1.4 1 P 3 8 0;1=16,2=2
P 0.915 1.4 1 P 3 8 0;1=16,2=2
P 3.27923002 2.21576998 1 P 3 8 0;0,1=16,2=2
P 3.35153002 2.17875 1 P 3 8 0;0,1=16,2=2
P 3.54 0.825 1 P 3 8 0;0,1=16,2=2
P 5.07 1.925 1 P 3 8 0;0,1=16,2=2
P 5.07 1.885 1 P 3 8 0;0,1=16,2=2
P 3.075 1.605 1 P 3 8 0;1=16,2=2
P 1.025 4.2 1 P 3 8 0;0,1=16,2=2
P 1.03 3.64 1 P 3 8 0;0,1=16,2=2
P 1.038 0.7624 1 P 3 8 0;0,1=16,2=2
P 1.045 3.055 1 P 3 8 0;0,1=16,2=2
P 1.065 3.64 1 P 3 8 0;0,1=16,2=2
P 1.1 3.64 1 P 3 8 0;0,1=16,2=2
P 1.155 3.89 1 P 3 8 0;0,1=16,2=2
P 1.17 3.97 1 P 3 8 0;0,1=16,2=2
P 1.185 3.79 1 P 3 8 0;0,1=16,2=2
P 1.195 0.57693996 1 P 3 8 0;0,1=16,2=2
P 1.2 3.645 1 P 3 8 0;0,1=16,2=2
P 1.2 3.68 1 P 3 8 0;0,1=16,2=2
P 1.2 3.715 1 P 3 8 0;0,1=16,2=2
P 1.21168996 3.96891998 1 P 3 8 0;0,1=16,2=2
P 1.235 3.475 1 P 3 8 0;0,1=16,2=2
P 1.25095 3.06095 1 P 3 8 0;0,1=16,2=2
P 1.27 3.97061004 1 P 3 8 0;0,1=16,2=2
P 1.275 2.905 1 P 3 8 0;0,1=16,2=2
P 1.29 3.65 1 P 3 8 0;0,1=16,2=2
P 1.29 3.705 1 P 3 8 0;0,1=16,2=2
P 1.32 3.755 1 P 3 8 0;0,1=16,2=2
P 1.32 3.79 1 P 3 8 0;0,1=16,2=2
P 1.355 3.83 1 P 3 8 0;0,1=16,2=2
P 1.355 3.905 1 P 3 8 0;0,1=16,2=2
P 1.355 3.96 1 P 3 8 0;0,1=16,2=2
P 1.401 3.956 1 P 3 8 0;0,1=16,2=2
P 1.40123002 3.91603996 1 P 3 8 0;0,1=16,2=2
P 1.409 3.554 1 P 3 8 0;0,1=16,2=2
P 1.41 2.985 1 P 3 8 0;0,1=16,2=2
P 1.42 3.5 1 P 3 8 0;0,1=16,2=2
P 1.4213 3.2563 1 P 3 8 0;0,1=16,2=2
P 1.45 2.965 1 P 3 8 0;0,1=16,2=2
P 1.48 3.7 1 P 3 8 0;0,1=16,2=2
P 1.51 3.242 1 P 3 8 0;0,1=16,2=2
P 1.515 3.7 1 P 3 8 0;0,1=16,2=2
P 1.591 3.504 1 P 3 8 0;0,1=16,2=2
P 0.16 3.025 1 P 3 8 0;0,1=16,2=2
P 0.16 3.075 1 P 3 8 0;0,1=16,2=2
P 1.65 2.94 1 P 3 8 0;0,1=16,2=2
P 1.667 3.388 1 P 3 8 0;0,1=16,2=2
P 1.685 2.94 1 P 3 8 0;0,1=16,2=2
P 0.17 2.045 1 P 3 8 0;0,1=16,2=2
P 1.746 4.016 1 P 3 8 0;0,1=16,2=2
P 1.746 4.061 1 P 3 8 0;0,1=16,2=2
P 0.175 0.91 1 P 3 8 0;0,1=16,2=2
P 1.751 3.871 1 P 3 8 0;0,1=16,2=2
P 1.76 4.16 1 P 3 8 0;0,1=16,2=2
P 1.786 3.746 1 P 3 8 0;0,1=16,2=2
P 1.786 3.786 1 P 3 8 0;0,1=16,2=2
P 1.89 3.26 1 P 3 8 0;0,1=16,2=2
P 1.895 3.19 1 P 3 8 0;0,1=16,2=2
P 1.9 3.015 1 P 3 8 0;0,1=16,2=2
P 1.9 3.055 1 P 3 8 0;0,1=16,2=2
P 1.915 4.13 1 P 3 8 0;0,1=16,2=2
P 1.9216 0.7784 1 P 3 8 0;0,1=16,2=2
P 0.199 2.83 1 P 3 8 0;0,1=16,2=2
P 2.15 0.69 1 P 3 8 0;0,1=16,2=2
P 2.176 4.151 1 P 3 8 0;0,1=16,2=2
P 2.18 3.811 1 P 3 8 0;0,1=16,2=2
P 2.2 0.69 1 P 3 8 0;0,1=16,2=2
P 2.215 3.785 1 P 3 8 0;0,1=16,2=2
P 2.215 4.15 1 P 3 8 0;0,1=16,2=2
P 2.256 4.151 1 P 3 8 0;0,1=16,2=2
P 2.26 3.785 1 P 3 8 0;0,1=16,2=2
P 2.295 4.15 1 P 3 8 0;0,1=16,2=2
P 2.41441004 2.15 1 P 3 8 0;0,1=16,2=2
P 2.419 2.388 1 P 3 8 0;0,1=16,2=2
P 2.54 2.135 1 P 3 8 0;0,1=16,2=2
P 2.59 2.23 1 P 3 8 0;0,1=16,2=2
P 2.595 0.701 1 P 3 8 0;0,1=16,2=2
P 2.69 2.15 1 P 3 8 0;0,1=16,2=2
P 2.71 1.845 1 P 3 8 0;0,1=16,2=2
P 2.7233 0.54871004 1 P 3 8 0;0,1=16,2=2
P 2.7526 2.23 1 P 3 8 0;0,1=16,2=2
P 2.805 2.243 1 P 3 8 0;0,1=16,2=2
P 2.822 1.79121004 1 P 3 8 0;0,1=16,2=2
P 2.88 2.93 1 P 3 8 0;0,1=16,2=2
P 2.885 3.17 1 P 3 8 0;0,1=16,2=2
P 2.92 2.9472 1 P 3 8 0;0,1=16,2=2
P 2.985 1.845 1 P 3 8 0;0,1=16,2=2
P 2.995 2.955 1 P 3 8 0;0,1=16,2=2
P 3.01 3.12 1 P 3 8 0;0,1=16,2=2
P 3.035 0.694 1 P 3 8 0;0,1=16,2=2
P 3.08966998 2.04 1 P 3 8 0;0,1=16,2=2
P 3.11 1.935 1 P 3 8 0;0,1=16,2=2
P 3.116 2.524 1 P 3 8 0;0,1=16,2=2
P 3.12 2.344 1 P 3 8 0;0,1=16,2=2
P 3.12 2.955 1 P 3 8 0;0,1=16,2=2
P 3.145 2.765 1 P 3 8 0;0,1=16,2=2
P 3.213 4.167 1 P 3 8 0;0,1=16,2=2
P 3.21898996 3.43 1 P 3 8 0;0,1=16,2=2
P 3.248 4.107 1 P 3 8 0;0,1=16,2=2
P 3.248 4.152 1 P 3 8 0;0,1=16,2=2
P 3.253 3.872 1 P 3 8 0;0,1=16,2=2
P 3.253 3.917 1 P 3 8 0;0,1=16,2=2
P 3.253 3.962 1 P 3 8 0;0,1=16,2=2
P 3.26 3.74 1 P 3 8 0;0,1=16,2=2
P 3.305 2.915 1 P 3 8 0;0,1=16,2=2
P 3.315 3.76 1 P 3 8 0;0,1=16,2=2
P 3.38 3.15 1 P 3 8 0;0,1=16,2=2
P 3.385 3.76 1 P 3 8 0;0,1=16,2=2
P 3.40953002 2.37 1 P 3 8 0;0,1=16,2=2
P 3.415 2.335 1 P 3 8 0;0,1=16,2=2
P 3.42 3.76 1 P 3 8 0;0,1=16,2=2
P 3.435 2.589 1 P 3 8 0;0,1=16,2=2
P 3.473 1.79 1 P 3 8 0;0,1=16,2=2
P 3.49 3.03 1 P 3 8 0;0,1=16,2=2
P 3.501 1.694 1 P 3 8 0;0,1=16,2=2
P 3.505 2.295 1 P 3 8 0;0,1=16,2=2
P 3.51 1.305 1 P 3 8 0;0,1=16,2=2
P 3.512 1.966 1 P 3 8 0;0,1=16,2=2
P 3.526 1.694 1 P 3 8 0;0,1=16,2=2
P 3.535 1.305 1 P 3 8 0;0,1=16,2=2
P 3.54 1.28 1 P 3 8 0;0,1=16,2=2
P 3.54975 2.479 1 P 3 8 0;0,1=16,2=2
P 3.55 2.425 1 P 3 8 0;0,1=16,2=2
P 3.551 1.694 1 P 3 8 0;0,1=16,2=2
P 3.555 3.065 1 P 3 8 0;0,1=16,2=2
P 3.56 1.305 1 P 3 8 0;0,1=16,2=2
P 3.576 1.694 1 P 3 8 0;0,1=16,2=2
P 3.6 4.024 1 P 3 8 0;0,1=16,2=2
P 3.60311004 4.0988 1 P 3 8 0;0,1=16,2=2
P 3.605 2.43 1 P 3 8 0;0,1=16,2=2
P 3.615 2.961 1 P 3 8 0;0,1=16,2=2
P 3.621 2.91 1 P 3 8 0;0,1=16,2=2
P 3.623 2.861 1 P 3 8 0;0,1=16,2=2
P 3.631 4.183 1 P 3 8 0;0,1=16,2=2
P 3.631 4.228 1 P 3 8 0;0,1=16,2=2
P 3.636 1.766 1 P 3 8 0;0,1=16,2=2
P 3.645 2.13 1 P 3 8 0;0,1=16,2=2
P 3.647 1.694 1 P 3 8 0;0,1=16,2=2
P 3.658 2.861 1 P 3 8 0;0,1=16,2=2
P 3.658 2.911 1 P 3 8 0;0,1=16,2=2
P 3.67 1.26 1 P 3 8 0;0,1=16,2=2
P 3.67 2.13 1 P 3 8 0;0,1=16,2=2
P 3.67 2.41243002 1 P 3 8 0;0,1=16,2=2
P 3.676 1.693 1 P 3 8 0;0,1=16,2=2
P 3.695 2.675 1 P 3 8 0;0,1=16,2=2
P 3.6956 2.13 1 P 3 8 0;0,1=16,2=2
P 3.703 2.911 1 P 3 8 0;0,1=16,2=2
P 3.718 1.29 1 P 3 8 0;0,1=16,2=2
P 3.718 1.32 1 P 3 8 0;0,1=16,2=2
P 3.7206 2.13 1 P 3 8 0;0,1=16,2=2
P 3.725 2.32 1 P 3 8 0;0,1=16,2=2
P 3.743 1.29 1 P 3 8 0;0,1=16,2=2
P 3.743 1.32 1 P 3 8 0;0,1=16,2=2
P 3.748 2.911 1 P 3 8 0;0,1=16,2=2
P 3.76838002 1.0023 1 P 3 8 0;0,1=16,2=2
P 3.78 2.735 1 P 3 8 0;0,1=16,2=2
P 3.78 2.932 1 P 3 8 0;0,1=16,2=2
P 3.798 1.771 1 P 3 8 0;0,1=16,2=2
P 3.8 2.045 1 P 3 8 0;0,1=16,2=2
P 3.83 2.932 1 P 3 8 0;0,1=16,2=2
P 3.83 3.415 1 P 3 8 0;0,1=16,2=2
P 3.839 3.726 1 P 3 8 0;0,1=16,2=2
P 3.84 1.0298 1 P 3 8 0;0,1=16,2=2
P 3.84 1.095 1 P 3 8 0;0,1=16,2=2
P 3.843 3.687 1 P 3 8 0;0,1=16,2=2
P 3.933 3.125 1 P 3 8 0;0,1=16,2=2
P 3.973 3.207 1 P 3 8 0;0,1=16,2=2
P 3.975 3.129 1 P 3 8 0;0,1=16,2=2
P 3.978 2.593 1 P 3 8 0;0,1=16,2=2
P 3.98 3.52 1 P 3 8 0;0,1=16,2=2
P 3.99 2.21406998 1 P 3 8 0;0,1=16,2=2
P 3.99 2.25 1 P 3 8 0;0,1=16,2=2
P 3.995 1.2 1 P 3 8 0;0,1=16,2=2
P 3.998 2.784 1 P 3 8 0;0,1=16,2=2
P 4.037 2.593 1 P 3 8 0;0,1=16,2=2
P 4.07 1.2 1 P 3 8 0;0,1=16,2=2
P 4.075 3.05 1 P 3 8 0;0,1=16,2=2
P 4.091 2.813 1 P 3 8 0;0,1=16,2=2
P 4.092 2.917 1 P 3 8 0;0,1=16,2=2
P 4.093 2.863 1 P 3 8 0;0,1=16,2=2
P 4.1 3.58543002 1 P 3 8 0;0,1=16,2=2
P 4.135 0.885 1 P 3 8 0;0,1=16,2=2
P 4.175 3.52 1 P 3 8 0;0,1=16,2=2
P 0.42 2.368 1 P 3 8 0;0,1=16,2=2
P 4.22 0.775 1 P 3 8 0;0,1=16,2=2
P 4.23 1.005 1 P 3 8 0;0,1=16,2=2
P 4.278 1.003 1 P 3 8 0;0,1=16,2=2
P 4.294 1.075 1 P 3 8 0;0,1=16,2=2
P 4.31 1.165 1 P 3 8 0;0,1=16,2=2
P 4.31 4.16 1 P 3 8 0;0,1=16,2=2
P 4.335 1.005 1 P 3 8 0;0,1=16,2=2
P 4.345 0.77 1 P 3 8 0;0,1=16,2=2
P 4.395 2.665 1 P 3 8 0;0,1=16,2=2
P 4.44 2.26 1 P 3 8 0;0,1=16,2=2
P 4.44 2.5 1 P 3 8 0;0,1=16,2=2
P 4.44 2.63 1 P 3 8 0;0,1=16,2=2
P 4.442 1.005 1 P 3 8 0;0,1=16,2=2
P 4.46 3.745 1 P 3 8 0;0,1=16,2=2
P 4.472 3.475 1 P 3 8 0;0,1=16,2=2
P 4.4843 0.8954 1 P 3 8 0;0,1=16,2=2
P 4.5 1.082 1 P 3 8 0;0,1=16,2=2
P 4.5 4.07 1 P 3 8 0;0,1=16,2=2
P 4.54 3.935 1 P 3 8 0;0,1=16,2=2
P 4.54 3.97 1 P 3 8 0;0,1=16,2=2
P 4.546 1.085 1 P 3 8 0;0,1=16,2=2
P 0.455 1.26 1 P 3 8 0;0,1=16,2=2
P 0.455 1.61 1 P 3 8 0;0,1=16,2=2
P 4.59 3.26 1 P 3 8 0;0,1=16,2=2
P 4.595 3.22 1 P 3 8 0;0,1=16,2=2
P 4.6 2.845 1 P 3 8 0;0,1=16,2=2
P 4.6 2.895 1 P 3 8 0;0,1=16,2=2
P 4.62 2.245 1 P 3 8 0;0,1=16,2=2
P 4.62 2.5 1 P 3 8 0;0,1=16,2=2
P 4.635 0.865 1 P 3 8 0;0,1=16,2=2
P 0.47 1 1 P 3 8 0;0,1=16,2=2
P 4.71 3.47 1 P 3 8 0;0,1=16,2=2
P 4.714 3.633 1 P 3 8 0;0,1=16,2=2
P 0.476 0.689 1 P 3 8 0;0,1=16,2=2
P 4.775 2.59 1 P 3 8 0;0,1=16,2=2
P 4.78 1.98 1 P 3 8 0;0,1=16,2=2
P 4.79866998 1.38866998 1 P 3 8 0;0,1=16,2=2
P 4.81 0.707 1 P 3 8 0;0,1=16,2=2
P 4.815 1.82016004 1 P 3 8 0;0,1=16,2=2
P 0.485 2.715 1 P 3 8 0;0,1=16,2=2
P 4.894 1.263 1 P 3 8 0;0,1=16,2=2
P 4.918 2.777 1 P 3 8 0;0,1=16,2=2
P 4.925 2.722 1 P 3 8 0;0,1=16,2=2
P 4.933 1.215 1 P 3 8 0;0,1=16,2=2
P 4.96 1.675 1 P 3 8 0;0,1=16,2=2
P 4.96 1.79258002 1 P 3 8 0;0,1=16,2=2
P 4.96 2.055 1 P 3 8 0;0,1=16,2=2
P 4.965 1.925 1 P 3 8 0;0,1=16,2=2
P 5.0395 1.43 1 P 3 8 0;0,1=16,2=2
P 5.045 3.76 1 P 3 8 0;0,1=16,2=2
P 5.05 3.795 1 P 3 8 0;0,1=16,2=2
P 5.061 2.806 1 P 3 8 0;0,1=16,2=2
P 5.071 2.407 1 P 3 8 0;0,1=16,2=2
P 5.119 2.762 1 P 3 8 0;0,1=16,2=2
P 5.121 2.407 1 P 3 8 0;0,1=16,2=2
P 5.121 2.447 1 P 3 8 0;0,1=16,2=2
P 5.121 2.495 1 P 3 8 0;0,1=16,2=2
P 5.121 2.625 1 P 3 8 0;0,1=16,2=2
P 5.122 2.587 1 P 3 8 0;0,1=16,2=2
P 5.123 2.544 1 P 3 8 0;0,1=16,2=2
P 0.51771998 1.305 1 P 3 8 0;0,1=16,2=2
P 0.51771998 1.87986998 1 P 3 8 0;0,1=16,2=2
P 0.51771998 2.45073996 1 P 3 8 0;0,1=16,2=2
P 0.51771998 0.736 1 P 3 8 0;0,1=16,2=2
P 5.17 2.125 1 P 3 8 0;0,1=16,2=2
P 5.237 3.777 1 P 3 8 0;0,1=16,2=2
P 5.237 3.841 1 P 3 8 0;0,1=16,2=2
P 5.25176004 4.11925 1 P 3 8 0;0,1=16,2=2
P 5.271 3.406 1 P 3 8 0;0,1=16,2=2
P 5.271 3.456 1 P 3 8 0;0,1=16,2=2
P 5.276 3.189 1 P 3 8 0;0,1=16,2=2
P 5.282 3.777 1 P 3 8 0;0,1=16,2=2
P 5.298 2.23 1 P 3 8 0;0,1=16,2=2
P 5.3035 2.5748 1 P 3 8 0;0,1=16,2=2
P 5.322 3.777 1 P 3 8 0;0,1=16,2=2
P 5.324 3.406 1 P 3 8 0;0,1=16,2=2
P 5.324 3.456 1 P 3 8 0;0,1=16,2=2
P 5.325 2.725 1 P 3 8 0;0,1=16,2=2
P 5.329 3.189 1 P 3 8 0;0,1=16,2=2
P 5.33 0.87 1 P 3 8 0;0,1=16,2=2
P 5.335 1.245 1 P 3 8 0;0,1=16,2=2
P 5.34 1.605 1 P 3 8 0;0,1=16,2=2
P 5.345 1.3 1 P 3 8 0;0,1=16,2=2
P 5.345 1.365 1 P 3 8 0;0,1=16,2=2
P 5.346 1.483 1 P 3 8 0;0,1=16,2=2
P 5.346 1.52 1 P 3 8 0;0,1=16,2=2
P 5.369 2.015 1 P 3 8 0;0,1=16,2=2
P 5.37 0.69 1 P 3 8 0;0,1=16,2=2
P 5.381 3.406 1 P 3 8 0;0,1=16,2=2
P 5.381 3.456 1 P 3 8 0;0,1=16,2=2
P 5.385 1.895 1 P 3 8 0;0,1=16,2=2
P 5.385 4.07875 1 P 3 8 0;0,1=16,2=2
P 5.386 3.189 1 P 3 8 0;0,1=16,2=2
P 0.539 1.57 1 P 3 8 0;0,1=16,2=2
P 5.409 2.015 1 P 3 8 0;0,1=16,2=2
P 5.41346004 3.03506998 1 P 3 8 0;0,1=16,2=2
P 5.425 1.895 1 P 3 8 0;0,1=16,2=2
P 5.43 3.967 1 P 3 8 0;0,1=16,2=2
P 5.435 2.05 1 P 3 8 0;0,1=16,2=2
P 5.43956998 0.60543002 1 P 3 8 0;0,1=16,2=2
P 5.44 1.59 1 P 3 8 0;0,1=16,2=2
P 5.49 2.675 1 P 3 8 0;0,1=16,2=2
P 5.517 2.563 1 P 3 8 0;0,1=16,2=2
P 5.538 2.402 1 P 3 8 0;0,1=16,2=2
P 5.59 0.85 1 P 3 8 0;0,1=16,2=2
P 5.59 0.888 1 P 3 8 0;0,1=16,2=2
P 5.59941004 0.6212 1 P 3 8 0;0,1=16,2=2
P 5.602 3.865 1 P 3 8 0;0,1=16,2=2
P 5.602 0.815 1 P 3 8 0;0,1=16,2=2
P 5.625 0.746 1 P 3 8 0;0,1=16,2=2
P 5.63341004 0.62101998 1 P 3 8 0;0,1=16,2=2
P 5.645 3.79 1 P 3 8 0;0,1=16,2=2
P 5.647 2.044 1 P 3 8 0;0,1=16,2=2
P 5.687 2.043 1 P 3 8 0;0,1=16,2=2
P 5.732 2.043 1 P 3 8 0;0,1=16,2=2
P 0.575 2.185 1 P 3 8 0;0,1=16,2=2
P 5.75071998 1.655 1 P 3 8 0;0,1=16,2=2
P 5.763 3.712 1 P 3 8 0;0,1=16,2=2
P 5.76458996 1.61971004 1 P 3 8 0;0,1=16,2=2
P 5.801 3.667 1 P 3 8 0;0,1=16,2=2
P 5.802 3.617 1 P 3 8 0;0,1=16,2=2
P 5.803 3.567 1 P 3 8 0;0,1=16,2=2
P 5.803 3.757 1 P 3 8 0;0,1=16,2=2
P 5.803 3.807 1 P 3 8 0;0,1=16,2=2
P 5.803 3.857 1 P 3 8 0;0,1=16,2=2
P 5.805 1.945 1 P 3 8 0;0,1=16,2=2
P 5.805 0.658 1 P 3 8 0;0,1=16,2=2
P 5.80643002 0.609 1 P 3 8 0;0,1=16,2=2
P 5.814 2.9225 1 P 3 8 0;0,1=16,2=2
P 5.815 2.67 1 P 3 8 0;0,1=16,2=2
P 5.83 1.92 1 P 3 8 0;0,1=16,2=2
P 5.859 0.796 1 P 3 8 0;0,1=16,2=2
P 5.865 2.3 1 P 3 8 0;0,1=16,2=2
P 5.97703002 1.87 1 P 3 8 0;0,1=16,2=2
P 5.99 0.925 1 P 3 8 0;0,1=16,2=2
P 0.606 1.612 1 P 3 8 0;0,1=16,2=2
P 6.105 2.27 1 P 3 8 0;0,1=16,2=2
P 0.614 1.049 1 P 3 8 0;0,1=16,2=2
P 0.61488996 3.32328996 1 P 3 8 0;0,1=16,2=2
P 6.141 2.241 1 P 3 8 0;0,1=16,2=2
P 6.165 1.94873996 1 P 3 8 0;0,1=16,2=2
P 6.22 1.36 1 P 3 8 0;0,1=16,2=2
P 6.26988996 2.37988996 1 P 3 8 0;0,1=16,2=2
P 6.335 1.96873996 1 P 3 8 0;0,1=16,2=2
P 6.335 3.015 1 P 3 8 0;0,1=16,2=2
P 0.635 3.596 1 P 3 8 0;0,1=16,2=2
P 6.36 2.16141998 1 P 3 8 0;0,1=16,2=2
P 6.47 1.135 1 P 3 8 0;0,1=16,2=2
P 0.66 4.19 1 P 3 8 0;0,1=16,2=2
P 0.66 0.911 1 P 3 8 0;0,1=16,2=2
P 0.664 0.774 1 P 3 8 0;0,1=16,2=2
P 0.675 2.229 1 P 3 8 0;0,1=16,2=2
P 0.677 0.65 1 P 3 8 0;0,1=16,2=2
P 0.695 1 1 P 3 8 0;0,1=16,2=2
P 0.714 2.217 1 P 3 8 0;0,1=16,2=2
P 0.715 2.478 1 P 3 8 0;0,1=16,2=2
P 0.72 3.35 1 P 3 8 0;0,1=16,2=2
P 0.74593002 2.02206998 1 P 3 8 0;0,1=16,2=2
P 0.80148002 2.53648002 1 P 3 8 0;0,1=16,2=2
P 0.83 4.17 1 P 3 8 0;0,1=16,2=2
P 0.833 0.871 1 P 3 8 0;0,1=16,2=2
P 0.8575 2.0275 1 P 3 8 0;0,1=16,2=2
P 0.866 1.413 1 P 3 8 0;0,1=16,2=2
P 0.872 2.583 1 P 3 8 0;0,1=16,2=2
P 0.889 0.67 1 P 3 8 0;0,1=16,2=2
P 0.93031998 2.46476998 1 P 3 8 0;0,1=16,2=2
P 0.94 4.2 1 P 3 8 0;0,1=16,2=2
P 0.945 1.05 1 P 3 8 0;0,1=16,2=2
P 0.95593002 3.33346998 1 P 3 8 0;0,1=16,2=2
P 0.988 2.724 1 P 3 8 0;0,1=16,2=2
P 0.99 3.5 1 P 3 8 0;0,1=16,2=2
P 3.81 3.65 1 P 3 8 0;0,1=16,2=2
P 3.865 3.65 1 P 3 8 0;0,1=16,2=2
P 0.191 1.48798002 1 P 3 8 0;0,1=16,2=2
P 0.416 1.48798002 1 P 3 8 0;0,1=16,2=2
P 0.326 1.487 1 P 3 8 0;0,1=16,2=2
P 0.939 1.552 1 P 3 8 0;1=16,2=2
P 0.41408996 1.32591004 1 P 3 8 0;0,1=16,2=2
P 0.89 1.105 1 P 3 8 0;0,1=16,2=2
P 0.465 1.33 1 P 3 8 0;0,1=16,2=2
P 0.87 1.3 1 P 3 8 0;0,1=16,2=2
P 0.415 1.275 1 P 3 8 0;0,1=16,2=2
P 0.87 1.2 1 P 3 8 0;0,1=16,2=2
P 0.75 1.417 1 P 3 8 0;1=16,2=2
P 0.99 1.755 1 P 3 8 0;1=16,2=2
P 0.955 1.92 1 P 3 8 0;1=16,2=2
P 0.835 1.78 1 P 3 8 0;0,1=16,2=2
P 0.835 1.93 1 P 3 8 0;0,1=16,2=2
P 0.835 1.885 1 P 3 8 0;0,1=16,2=2
P 0.975 1.72 1 P 3 8 0;0,1=16,2=2
P 0.945 1.63 1 P 3 8 0;0,1=16,2=2
P 0.959 2.789 1 P 3 8 0;0,1=16,2=2
P 3.035 1.64 1 P 3 8 0;1=16,2=2
P 1.125 2.9 1 P 3 8 0;0,1=16,2=2
P 1.025 2.9 1 P 3 8 0;0,1=16,2=2
P 4.81 3.41 1 P 3 8 0;0,1=16,2=2
P 0.675 1.145 1 P 3 8 0;0,1=16,2=2
P 0.68 1.19 1 P 3 8 0;0,1=16,2=2
P 0.735 1.19 1 P 3 8 0;0,1=16,2=2
P 0.69 1.875 1 P 3 8 0;0,1=16,2=2
P 0.69 1.93 1 P 3 8 0;0,1=16,2=2
P 0.69023002 1.98523996 1 P 3 8 0;0,1=16,2=2
P 3.51 2.33243002 1 P 3 8 0;0,1=16,2=2
P 3.51 2.37 1 P 3 8 0;0,1=16,2=2
P 3.01 3.17 1 P 3 8 0;0,1=16,2=2
P 5.458 2.165 1 P 3 8 0;0,1=16,2=2
P 5.465 2.405 1 P 3 8 0;0,1=16,2=2
P 5.71 2.179 1 P 3 8 0;0,1=16,2=2
P 3.363 4.152 1 P 3 8 0;0,1=16,2=2
P 3.363 4.192 1 P 3 8 0;0,1=16,2=2
P 3.392 3.803 1 P 3 8 0;0,1=16,2=2
P 3.393 3.84 1 P 3 8 0;0,1=16,2=2
P 3.393 3.877 1 P 3 8 0;0,1=16,2=2
P 3.408 4.152 1 P 3 8 0;0,1=16,2=2
P 3.607 4.062 1 P 3 8 0;0,1=16,2=2
P 1.591 3.826 1 P 3 8 0;0,1=16,2=2
P 1.6055 4.134 1 P 3 8 0;0,1=16,2=2
P 1.60581998 4.1 1 P 3 8 0;0,1=16,2=2
P 1.636 3.786 1 P 3 8 0;0,1=16,2=2
P 1.45 3.78 1 P 3 8 0;0,1=16,2=2
P 1.485 3.8 1 P 3 8 0;0,1=16,2=2
P 3.46 4.16 1 P 3 8 0;0,1=16,2=2
P 3.495 4.15 1 P 3 8 0;0,1=16,2=2
P 3.5 4.195 1 P 3 8 0;0,1=16,2=2
P 3.53 4.165 1 P 3 8 0;0,1=16,2=2
P 5.34 2.315 1 P 3 8 0;0,1=16,2=2
P 5.375 2.32 1 P 3 8 0;0,1=16,2=2
P 5.39 3.6 1 P 3 8 0;0,1=16,2=2
P 5.39 3.7 1 P 3 8 0;0,1=16,2=2
P 5.393 3.651 1 P 3 8 0;0,1=16,2=2
P 5.43 3.7 1 P 3 8 0;0,1=16,2=2
P 5.433 3.651 1 P 3 8 0;0,1=16,2=2
P 5.769 4.031 1 P 3 8 0;0,1=16,2=2
P 5.803 3.907 1 P 3 8 0;0,1=16,2=2
P 0.828 3.646 1 P 3 8 0;0,1=16,2=2
P 0.828 3.846 1 P 3 8 0;0,1=16,2=2
P 0.865 3.645 1 P 3 8 0;0,1=16,2=2
P 0.865 3.845 1 P 3 8 0;0,1=16,2=2
P 0.905 3.645 1 P 3 8 0;0,1=16,2=2
P 0.905 3.845 1 P 3 8 0;0,1=16,2=2
P 0.94 3.845 1 P 3 8 0;0,1=16,2=2
P 0.945 3.645 1 P 3 8 0;0,1=16,2=2
P 0.945 3.69 1 P 3 8 0;0,1=16,2=2
P 0.945 3.73 1 P 3 8 0;0,1=16,2=2
P 0.945 3.765 1 P 3 8 0;0,1=16,2=2
P 5.275 3.931 1 P 3 8 0;0,1=16,2=2
P 5.321 3.99 1 P 3 8 0;0,1=16,2=2
P 5.567 3.203 1 P 3 8 0;0,1=16,2=2
P 5.62 3.316 1 P 3 8 0;0,1=16,2=2
P 5.625 3.361 1 P 3 8 0;0,1=16,2=2
P 0.603 4.011 1 P 3 8 0;0,1=16,2=2
P 0.603 4.131 1 P 3 8 0;0,1=16,2=2
P 0.643 3.956 1 P 3 8 0;0,1=16,2=2
P 0.643 4.076 1 P 3 8 0;0,1=16,2=2
P 0.713 3.942 1 P 3 8 0;0,1=16,2=2
P 0.713 3.992 1 P 3 8 0;0,1=16,2=2
P 0.713 4.042 1 P 3 8 0;0,1=16,2=2
P 0.713 4.092 1 P 3 8 0;0,1=16,2=2
P 0.76 3.942 1 P 3 8 0;0,1=16,2=2
P 0.76 3.992 1 P 3 8 0;0,1=16,2=2
P 0.76 4.042 1 P 3 8 0;0,1=16,2=2
P 0.76 4.092 1 P 3 8 0;0,1=16,2=2
P 0.807 3.942 1 P 3 8 0;0,1=16,2=2
P 0.807 3.992 1 P 3 8 0;0,1=16,2=2
P 0.807 4.042 1 P 3 8 0;0,1=16,2=2
P 0.807 4.092 1 P 3 8 0;0,1=16,2=2
P 0.854 3.942 1 P 3 8 0;0,1=16,2=2
P 0.854 3.992 1 P 3 8 0;0,1=16,2=2
P 0.854 4.042 1 P 3 8 0;0,1=16,2=2
P 0.854 4.092 1 P 3 8 0;0,1=16,2=2
P 0.928 3.961 1 P 3 8 0;0,1=16,2=2
P 0.928 4.081 1 P 3 8 0;0,1=16,2=2
P 0.968 3.961 1 P 3 8 0;0,1=16,2=2
P 0.968 4.021 1 P 3 8 0;0,1=16,2=2
P 0.968 4.141 1 P 3 8 0;0,1=16,2=2
P 0.625 3.65 1 P 3 8 0;0,1=16,2=2
P 0.625 3.69 1 P 3 8 0;0,1=16,2=2
P 0.625 3.82 1 P 3 8 0;0,1=16,2=2
P 0.66 3.65 1 P 3 8 0;0,1=16,2=2
P 0.665 3.82 1 P 3 8 0;0,1=16,2=2
P 0.695 3.65 1 P 3 8 0;0,1=16,2=2
P 0.705 3.82 1 P 3 8 0;0,1=16,2=2
P 0.73 3.65 1 P 3 8 0;0,1=16,2=2
P 5.6 2.4 1 P 3 8 0;0,1=16,2=2
P 5.6695 2.2 1 P 3 8 0;0,1=16,2=2
P 5.789 2.366 1 P 3 8 0;0,1=16,2=2
P 3.50085 1.543 1 P 3 8 0;0,1=16,2=2
P 3.53481998 1.54156998 1 P 3 8 0;0,1=16,2=2
P 3.57 1.542 1 P 3 8 0;0,1=16,2=2
P 3.605 1.545 1 P 3 8 0;0,1=16,2=2
P 5.3977 1.699 1 P 3 8 0;0,1=16,2=2
P 5.3977 1.724 1 P 3 8 0;0,1=16,2=2
P 5.3977 1.749 1 P 3 8 0;0,1=16,2=2
P 5.4227 1.699 1 P 3 8 0;0,1=16,2=2
P 5.4227 1.724 1 P 3 8 0;0,1=16,2=2
P 5.4352 1.7497 1 P 3 8 0;0,1=16,2=2
P 5.654 2.447 1 P 3 8 0;0,1=16,2=2
P 3.679 1.54228002 1 P 3 8 0;0,1=16,2=2
P 3.714 1.543 1 P 3 8 0;0,1=16,2=2
P 3.749 1.54228002 1 P 3 8 0;0,1=16,2=2
P 3.784 1.543 1 P 3 8 0;0,1=16,2=2
P 3.755 3.092 1 P 3 8 0;0,1=16,2=2
P 5.145 1.48 1 P 3 8 0;0,1=16,2=2
P 5.145 1.51 1 P 3 8 0;0,1=16,2=2
P 5.145 1.54 1 P 3 8 0;0,1=16,2=2
P 5.145 1.57 1 P 3 8 0;0,1=16,2=2
P 5.546 2.024 1 P 3 8 0;0,1=16,2=2
P 3.475 1.415 1 P 3 8 0;0,1=16,2=2
P 3.5 1.415 1 P 3 8 0;0,1=16,2=2
P 3.525 1.415 1 P 3 8 0;0,1=16,2=2
P 3.55 1.415 1 P 3 8 0;0,1=16,2=2
P 3.7 2.76 1 P 3 8 0;0,1=16,2=2
P 3.745 2.76 1 P 3 8 0;0,1=16,2=2
P 3.78 2.81 1 P 3 8 0;0,1=16,2=2
P 3.822 2.81 1 P 3 8 0;0,1=16,2=2
P 3.555 2.18 1 P 3 8 0;0,1=16,2=2
P 3.555 2.205 1 P 3 8 0;0,1=16,2=2
P 3.555 2.23 1 P 3 8 0;0,1=16,2=2
P 3.555 2.255 1 P 3 8 0;0,1=16,2=2
P 5.22 2.47 1 P 3 8 0;0,1=16,2=2
P 5.239 2.571 1 P 3 8 0;0,1=16,2=2
P 5.243 2.617 1 P 3 8 0;0,1=16,2=2
P 5.254 2.47 1 P 3 8 0;0,1=16,2=2
P 0.985 2.56661004 1 P 3 8 0;0,1=16,2=2
P 0.99 2.60025 1 P 3 8 0;0,1=16,2=2
P 4.25 3.81 1 P 3 8 0;0,1=16,2=2
P 4.608 2.942 1 P 3 8 0;0,1=16,2=2
P 5.31 2.855 1 P 3 8 0;0,1=16,2=2
P 3.775 2.185 1 P 3 8 0;0,1=16,2=2
P 3.775 2.21 1 P 3 8 0;0,1=16,2=2
P 3.775 2.235 1 P 3 8 0;0,1=16,2=2
P 0.64248002 2.58 1 P 3 8 0;0,1=16,2=2
P 0.714 2.329 1 P 3 8 0;0,1=16,2=2
P 0.869 2.672 1 P 3 8 0;0,1=16,2=2
P 3.105 3.21 1 P 3 8 0;0,1=16,2=2
P 3.66 3.5085 1 P 3 8 0;0,1=16,2=2
P 3.69171998 1.02828002 1 P 3 8 0;0,1=16,2=2
P 3.6931 1.095 1 P 3 8 0;0,1=16,2=2
P 3.795 4.175 1 P 3 8 0;0,1=16,2=2
P 4.485 1.005 1 P 3 8 0;0,1=16,2=2
P 4.625 1.17 1 P 3 8 0;0,1=16,2=2
P 5.0386 1.2415 1 P 3 8 0;0,1=16,2=2
P 5.039 1.2869 1 P 3 8 0;0,1=16,2=2
P 5.443 0.871 1 P 3 8 0;0,1=16,2=2
P 5.49 0.78223002 1 P 3 8 0;0,1=16,2=2
P 5.494 0.816 1 P 3 8 0;0,1=16,2=2
P 5.55 4.02 1 P 3 8 0;0,1=16,2=2
P 6.04 3.98 1 P 3 8 0;0,1=16,2=2
P 1.41 3.795 1 P 3 8 0;0,1=16,2=2
P 2.31 0.68 1 P 3 8 0;0,1=16,2=2
P 2.31 0.715 1 P 3 8 0;0,1=16,2=2
P 2.38 3.45 1 P 3 8 0;0,1=16,2=2
P 2.595 0.547 1 P 3 8 0;0,1=16,2=2
P 3.25 3.63 1 P 3 8 0;0,1=16,2=2
P 3.325 3.613 1 P 3 8 0;0,1=16,2=2
P 3.405 3.613 1 P 3 8 0;0,1=16,2=2
P 3.445 3.613 1 P 3 8 0;0,1=16,2=2
P 3.48418002 3.613 1 P 3 8 0;0,1=16,2=2
P 3.614 3.015 1 P 3 8 0;0,1=16,2=2
P 3.614 3.058 1 P 3 8 0;0,1=16,2=2
P 3.614 3.099 1 P 3 8 0;0,1=16,2=2
P 3.645 4.135 1 P 3 8 0;0,1=16,2=2
P 3.655 3.059 1 P 3 8 0;0,1=16,2=2
P 4 2.655 1 P 3 8 0;0,1=16,2=2
P 4.23 0.7295 1 P 3 8 0;0,1=16,2=2
P 4.346 2.783 1 P 3 8 0;0,1=16,2=2
P 4.355 2.745 1 P 3 8 0;0,1=16,2=2
P 4.4 2.785 1 P 3 8 0;0,1=16,2=2
P 4.456 2.783 1 P 3 8 0;0,1=16,2=2
P 4.923 2.408 1 P 3 8 0;0,1=16,2=2
P 4.971 2.447 1 P 3 8 0;0,1=16,2=2
P 4.972 2.406 1 P 3 8 0;0,1=16,2=2
P 5.022 2.407 1 P 3 8 0;0,1=16,2=2
P 5.236 2.811 1 P 3 8 0;0,1=16,2=2
P 5.2871 2.275 1 P 3 8 0;0,1=16,2=2
P 5.62533002 1.02001004 1 P 3 8 0;0,1=16,2=2
P 5.65933002 1.02 1 P 3 8 0;0,1=16,2=2
P 0.68 2.355 1 P 3 8 0;0,1=16,2=2
P 0.96 2.41 1 P 3 8 0;1=16,2=2
P 3.405 3.916 1 P 3 8 0;0,1=16,2=2
P 3.598 3.977 1 P 3 8 0;0,1=16,2=2
P 2.135 0.54 1 P 3 8 0;0,1=16,2=2
P 3.36 0.6106 1 P 3 8 0;0,1=16,2=2
P 3.48278996 4.05678002 1 P 3 8 0;0,1=16,2=2
P 1.1133 0.5981 1 P 3 8 0;0,1=16,2=2
P 0.11263996 1.52263996 1 P 3 8 0;0,1=16,2=2
P 0.11963002 2.66436998 1 P 3 8 0;0,1=16,2=2
P 0.11976004 3.23523996 1 P 3 8 0;0,1=16,2=2
P 0.125 2.095 1 P 3 8 0;0,1=16,2=2
P 0.125 0.96 1 P 3 8 0;0,1=16,2=2
P 1.25 0.765 1 P 3 8 0;0,1=16,2=2
P 1.401 3.069 1 P 3 8 0;0,1=16,2=2
P 1.5327 0.584 1 P 3 8 0;0,1=16,2=2
P 0.16 2.975 1 P 3 8 0;0,1=16,2=2
P 1.605 0.715 1 P 3 8 0;0,1=16,2=2
P 1.605 0.755 1 P 3 8 0;0,1=16,2=2
P 1.826 2.895 1 P 3 8 0;0,1=16,2=2
P 1.959 3.325 1 P 3 8 0;0,1=16,2=2
P 2.0477 0.6778 1 P 3 8 0;0,1=16,2=2
P 2.285 0.755 1 P 3 8 0;0,1=16,2=2
P 2.285 0.79 1 P 3 8 0;0,1=16,2=2
P 0.241 3.109 1 P 3 8 0;0,1=16,2=2
P 2.49 2.903 1 P 3 8 0;0,1=16,2=2
P 2.964 0.702 1 P 3 8 0;0,1=16,2=2
P 3.09 1.645 1 P 3 8 0;0,1=16,2=2
P 3.106 3.26 1 P 3 8 0;0,1=16,2=2
P 3.119 2.434 1 P 3 8 0;0,1=16,2=2
P 3.24 2.2075 1 P 3 8 0;0,1=16,2=2
P 3.335 2.589 1 P 3 8 0;0,1=16,2=2
P 3.395 2.82 1 P 3 8 0;0,1=16,2=2
P 3.41 3.04 1 P 3 8 0;0,1=16,2=2
P 3.414 3.235 1 P 3 8 0;0,1=16,2=2
P 3.485 2.6 1 P 3 8 0;0,1=16,2=2
P 3.49 2.955 1 P 3 8 0;0,1=16,2=2
P 3.49128002 1.86628002 1 P 3 8 0;0,1=16,2=2
P 3.525 2.6 1 P 3 8 0;0,1=16,2=2
P 3.55 3.37 1 P 3 8 0;1=16,2=2
P 3.5768 2.7178 1 P 3 8 0;0,1=16,2=2
P 3.7 3.37 1 P 3 8 0;0,1=16,2=2
P 3.71 3.26 1 P 3 8 0;0,1=16,2=2
P 3.735 2.47 1 P 3 8 0;0,1=16,2=2
P 0.374 2.829 1 P 3 8 0;0,1=16,2=2
P 3.758 2.552 1 P 3 8 0;0,1=16,2=2
P 3.795 2.375 1 P 3 8 0;0,1=16,2=2
P 3.839 3.846 1 P 3 8 0;0,1=16,2=2
P 3.86 2.5925 1 P 3 8 0;0,1=16,2=2
P 3.98 3.365 1 P 3 8 0;0,1=16,2=2
P 4.075 2.25 1 P 3 8 0;0,1=16,2=2
P 4.175 3.37 1 P 3 8 0;0,1=16,2=2
P 4.209 2.59 1 P 3 8 0;0,1=16,2=2
P 4.235 4.155 1 P 3 8 0;0,1=16,2=2
P 4.384 3.824 1 P 3 8 0;0,1=16,2=2
P 4.395 2.5 1 P 3 8 0;0,1=16,2=2
P 4.505 3.685 1 P 3 8 0;0,1=16,2=2
P 4.509 3.309 1 P 3 8 0;0,1=16,2=2
P 4.535 3.815 1 P 3 8 0;0,1=16,2=2
P 4.575 2.5 1 P 3 8 0;0,1=16,2=2
P 4.61 3.025 1 P 3 8 0;0,1=16,2=2
P 4.635 0.92 1 P 3 8 0;0,1=16,2=2
P 4.645 2.985 1 P 3 8 0;0,1=16,2=2
P 4.655 0.785 1 P 3 8 0;0,1=16,2=2
P 4.71 2.39 1 P 3 8 0;0,1=16,2=2
P 4.77 2.39 1 P 3 8 0;0,1=16,2=2
P 4.85 2.02738996 1 P 3 8 0;0,1=16,2=2
P 4.905 2.1675 1 P 3 8 0;0,1=16,2=2
P 4.95 3.46 1 P 3 8 0;0,1=16,2=2
P 4.96 1.63 1 P 3 8 0;0,1=16,2=2
P 4.965 1.975 1 P 3 8 0;0,1=16,2=2
P 5.0395 1.335 1 P 3 8 0;0,1=16,2=2
P 0.505 1.048 1 P 3 8 0;0,1=16,2=2
P 0.514 1.616 1 P 3 8 0;0,1=16,2=2
P 0.51451998 2.199 1 P 3 8 0;0,1=16,2=2
P 5.19 3.075 1 P 3 8 0;0,1=16,2=2
P 5.221 4.165 1 P 3 8 0;1=16,2=2
P 5.249 0.99 1 P 3 8 0;0,1=16,2=2
P 5.265 0.675 1 P 3 8 0;0,1=16,2=2
P 5.33 0.82 1 P 3 8 0;0,1=16,2=2
P 5.375 3.04 1 P 3 8 0;0,1=16,2=2
P 5.41 2.815 1 P 3 8 0;0,1=16,2=2
P 5.42 2.9645 1 P 3 8 0;0,1=16,2=2
P 0.5459 2.6687 1 P 3 8 0;0,1=16,2=2
P 5.515 0.59596998 1 P 3 8 0;0,1=16,2=2
P 5.53 1.085 1 P 3 8 0;0,1=16,2=2
P 5.544 2.675 1 P 3 8 0;0,1=16,2=2
P 5.62 2.5487 1 P 3 8 0;0,1=16,2=2
P 0.58 2.135 1 P 3 8 0;0,1=16,2=2
P 5.84 4.219 1 P 3 8 0;0,1=16,2=2
P 5.85 2.265 1 P 3 8 0;0,1=16,2=2
P 5.88 0.965 1 P 3 8 0;0,1=16,2=2
P 5.92 1.27063002 1 P 3 8 0;0,1=16,2=2
P 5.94003002 1.87 1 P 3 8 0;0,1=16,2=2
P 0.596 0.602 1 P 3 8 0;0,1=16,2=2
P 5.975 4.219 1 P 3 8 0;0,1=16,2=2
P 5.995 1.165 1 P 3 8 0;0,1=16,2=2
P 0.601 0.73 1 P 3 8 0;0,1=16,2=2
P 0.605 1.52 1 P 3 8 0;0,1=16,2=2
P 6.105 1.905 1 P 3 8 0;0,1=16,2=2
P 6.141 2.364 1 P 3 8 0;0,1=16,2=2
P 6.145 3.98 1 P 3 8 0;0,1=16,2=2
P 6.1865 2.493 1 P 3 8 0;0,1=16,2=2
P 6.22 1.27063002 1 P 3 8 0;0,1=16,2=2
P 0.625 1.17 1 P 3 8 0;0,1=16,2=2
P 6.379 1.169 1 P 3 8 0;0,1=16,2=2
P 0.64445 1.68945 1 P 3 8 0;0,1=16,2=2
P 6.47 1.08 1 P 3 8 0;0,1=16,2=2
P 0.674 2.271 1 P 3 8 0;0,1=16,2=2
P 0.677 2.402 1 P 3 8 0;0,1=16,2=2
P 0.764 0.872 1 P 3 8 0;0,1=16,2=2
P 0.78 2.915 1 P 3 8 0;0,1=16,2=2
P 0.821 0.793 1 P 3 8 0;0,1=16,2=2
P 0.857 2.365 1 P 3 8 0;1=16,2=2
P 0.86 0.631 1 P 3 8 0;0,1=16,2=2
P 0.884 1.549 1 P 3 8 0;0,1=16,2=2
P 1.025 3.02 1 P 3 8 0;0,1=16,2=2
P 1.13 3.445 1 P 3 8 0;0,1=16,2=2
P 1.15253002 3.06246998 1 P 3 8 0;0,1=16,2=2
P 1.175 2.9 1 P 3 8 0;0,1=16,2=2
P 1.37 3.64 1 P 3 8 0;0,1=16,2=2
P 1.407 3.2 1 P 3 8 0;0,1=16,2=2
P 1.41916004 3.33916004 1 P 3 8 0;0,1=16,2=2
P 1.495 3.11033996 1 P 3 8 0;0,1=16,2=2
P 1.515 3.58 1 P 3 8 0;0,1=16,2=2
P 1.591 3.546 1 P 3 8 0;0,1=16,2=2
P 1.667 3.438 1 P 3 8 0;0,1=16,2=2
P 2.19 3.488 1 P 3 8 0;0,1=16,2=2
P 2.192 3.388 1 P 3 8 0;0,1=16,2=2
P 0.945 3.125 1 P 3 8 0;0,1=16,2=2
P 0.95 3.215 1 P 3 8 0;0,1=16,2=2
P 0.95 3.445 1 P 3 8 0;0,1=16,2=2
P 1.045 3.77 1 P 3 8 0;0,1=16,2=2
P 4.705 3.91 1 P 3 8 0;0,1=16,2=2
P 2.235 0.5825 1 P 3 8 0;0,1=16,2=2
P 3.405 0.635 1 P 3 8 0;0,1=16,2=2
P 5.9065 2.4568 1 P 3 8 0;0,1=16,2=2
P 3.2 3.985 1 P 3 8 0;0,1=16,2=2
P 1.351 4.126 1 P 3 8 0;0,1=16,2=2
P 1.56 3.25 1 P 3 8 0;0,1=16,2=2
P 1.56 3.29 1 P 3 8 0;0,1=16,2=2
P 2.155 3.925 1 P 3 8 0;0,1=16,2=2
P 2.165 3.96 1 P 3 8 0;0,1=16,2=2
P 2.19 3.925 1 P 3 8 0;0,1=16,2=2
P 2.2 3.96 1 P 3 8 0;0,1=16,2=2
P 2.47 3.445 1 P 3 8 0;0,1=16,2=2
P 2.51 3.445 1 P 3 8 0;0,1=16,2=2
P 2.55 3.445 1 P 3 8 0;0,1=16,2=2
P 2.59 3.445 1 P 3 8 0;0,1=16,2=2
P 3.175 2.955 1 P 3 8 0;0,1=16,2=2
P 3.21 2.955 1 P 3 8 0;0,1=16,2=2
P 3.245 2.955 1 P 3 8 0;0,1=16,2=2
P 5.14 3.74 1 P 3 8 0;0,1=16,2=2
P 5.175 3.74 1 P 3 8 0;0,1=16,2=2
P 5.18 3.825 1 P 3 8 0;0,1=16,2=2
P 5.675 4.03 1 P 3 8 0;0,1=16,2=2
P 1.4 4.01 1 P 3 8 0;0,1=16,2=2
P 1.435 4.18 1 P 3 8 0;0,1=16,2=2
P 1.585 4.052 1 P 3 8 0;0,1=16,2=2
P 1.56 3.165 1 P 3 8 0;0,1=16,2=2
P 0.72 3.463 1 P 3 8 0;0,1=16,2=2
P 2.97771998 1.88693996 1 P 3 8 0;0,1=16,2=2
P 3.00995 1.87611004 1 P 3 8 0;0,1=16,2=2
P 1.75 3.945 1 P 3 8 0;0,1=16,2=2
P 6.275 2.05373996 1 P 3 8 0;0,1=16,2=2
P 3.465 1.74 1 P 3 8 0;0,1=16,2=2
P 6.285 1.895 1 P 3 8 0;0,1=16,2=2
P 5.075 3.945 1 P 3 8 0;0,1=16,2=2
P 1.6985 2.9895 1 P 3 8 0;0,1=17,2=2
P 4.0965 3.9445 1 P 3 8 0;0,1=17,2=2
P 4.0965 4.0395 1 P 3 8 0;0,1=17,2=2
P 4.1235 3.9715 1 P 3 8 0;0,1=17,2=2
P 4.1235 4.0125 1 P 3 8 0;0,1=17,2=2
P 4.1645 3.9715 1 P 3 8 0;0,1=17,2=2
P 4.1645 4.0125 1 P 3 8 0;0,1=17,2=2
P 4.1915 3.9445 1 P 3 8 0;0,1=17,2=2
P 4.1915 4.0395 1 P 3 8 0;0,1=17,2=2
P 5.1265 2.6815 1 P 3 8 0;0,1=17,2=2
P 5.6435 0.6535 1 P 3 8 0;0,1=17,2=2
P 5.9645 2.1035 1 P 3 8 0;0,1=17,2=2
P 6.0155 2.0845 1 P 3 8 0;0,1=17,2=2
P 5.638 3.907 1 P 3 8 0;0,1=18,2=2
P 0.735 1.125 1 P 3 8 0;1=18,2=2
P 0.965 2.355 1 P 3 8 0;0,1=18,2=2
P 0.67 1.09 1 P 3 8 0;1=18,2=2
P 0.935 1.105 1 P 3 8 0;0,1=18,2=2
P 0.5413 1.525 1 P 3 8 0;0,1=18,2=2
P 0.485 2.525 1 P 3 8 0;0,1=18,2=2
P 0.48 2.005 1 P 3 8 0;0,1=18,2=2
P 0.475 1.405 1 P 3 8 0;0,1=18,2=2
P 0.515 0.835 1 P 3 8 0;0,1=18,2=2
P 5.03005 0.99493996 1 P 3 8 0;0,1=18,2=2
P 0.532 2.40186998 1 P 3 8 0;0,1=18,2=2
P 0.535 1.835 1 P 3 8 0;0,1=18,2=2
P 0.5374 1.26 1 P 3 8 0;0,1=18,2=2
P 0.505 0.60228002 1 P 3 8 0;0,1=18,2=2
P 3.57 2.955 1 P 3 8 0;0,1=18,2=2
P 3.56 3.023 1 P 3 8 0;0,1=18,2=2
P 3.3255 2.1355 1 P 3 8 0;0,1=18,2=2
P 4.365 2.375 1 P 3 8 0;0,1=18,2=2
P 3.82286004 0.86213996 1 P 3 8 0;0,1=18,2=2
P 5.91 2.715 1 P 3 8 0;0,1=18,2=2
P 5.91 2.915 1 P 3 8 0;0,1=18,2=2
P 5.91 2.785 1 P 3 8 0;0,1=18,2=2
P 3.83 3.235 1 P 3 8 0;0,1=18,2=2
P 3.7 3.325 1 P 3 8 0;0,1=18,2=2
P 4.0661 3.5341 1 P 3 8 0;0,1=18,2=2
P 4.485 2.375 1 P 3 8 0;0,1=18,2=2
P 4.3 3.81 1 P 3 8 0;0,1=18,2=2
P 4.435 2.365 1 P 3 8 0;0,1=18,2=2
P 4.49 2.325 1 P 3 8 0;0,1=18,2=2
P 4.435 2.315 1 P 3 8 0;0,1=18,2=2
P 4.49 2.275 1 P 3 8 0;0,1=18,2=2
P 5.365 0.845 1 P 3 8 0;0,1=18,2=2
P 5.365 0.79 1 P 3 8 0;0,1=18,2=2
P 4.61 2.3 1 P 3 8 0;0,1=18,2=2
P 4.085 3.21998002 1 P 3 8 0;0,1=18,2=2
P 4.54 3.125 1 P 3 8 0;0,1=18,2=2
P 4.29441998 3.10075 1 P 3 8 0;0,1=18,2=2
P 4.485 3.115 1 P 3 8 0;0,1=18,2=2
P 3.9 3.385 1 P 3 8 0;0,1=18,2=2
P 4.1 3.38 1 P 3 8 0;0,1=18,2=2
P 4.83501004 3.46 1 P 3 8 0;0,1=18,2=2
P 4.815 1.93 1 P 3 8 0;0,1=18,2=2
P 2.97 3.105 1 P 3 8 0;0,1=18,2=2
P 4.84 1.855 1 P 3 8 0;0,1=18,2=2
P 3.205 1.7 1 P 3 8 0;0,1=18,2=2
P 2.554 2.901 1 P 3 8 0;0,1=18,2=2
P 3.765 2.69 1 P 3 8 0;0,1=18,2=2
P 6.025 1.83 1 P 3 8 0;0,1=18,2=2
P 5.92 1.73 1 P 3 8 0;0,1=18,2=2
P 5.92 1.63 1 P 3 8 0;0,1=18,2=2
P 5.92 1.515 1 P 3 8 0;0,1=18,2=2
P 5.92 1.41 1 P 3 8 0;0,1=18,2=2
P 4.925 2.26 1 P 3 8 0;0,1=18,2=2
P 6.22 1.815 1 P 3 8 0;0,1=18,2=2
P 6.22 1.62 1 P 3 8 0;0,1=18,2=2
P 6.22 1.516 1 P 3 8 0;0,1=18,2=2
P 6.22 1.415 1 P 3 8 0;0,1=18,2=2
P 4.4 3.325 1 P 3 8 0;0,1=18,2=2
P 4.81 1.725 1 P 3 8 0;0,1=18,2=2
P 4.84 1.66 1 P 3 8 0;0,1=18,2=2
P 3.82 1.42 1 P 3 8 0;0,1=18,2=2
P 3.385 2.59 1 P 3 8 0;0,1=18,2=2
P 3.119 2.299 1 P 3 8 0;0,1=18,2=2
P 0.445 3.09 1 P 3 8 0;0,1=18,2=2
P 3.84091004 2.00091004 1 P 3 8 0;0,1=18,2=2
P 4.785 3.46 1 P 3 8 0;0,1=18,2=2
P 3.795 3.81 1 P 3 8 0;0,1=18,2=2
P 3.925 3.291 1 P 3 8 0;0,1=18,2=2
P 0.842 0.75 1 P 3 8 0;0,1=18,2=2
P 0.985 1.59 1 P 3 8 0;0,1=18,2=2
P 0.985 1.655 1 P 3 8 0;0,1=18,2=2
P 0.92 1.73 1 P 3 8 0;0,1=18,2=2
P 0.935 1.25 1 P 3 8 0;0,1=18,2=2
P 0.87 1.255 1 P 3 8 0;0,1=18,2=2
P 0.935 1.3 1 P 3 8 0;0,1=18,2=2
P 0.242 2.62508002 1 P 3 8 0;0,1=18,2=2
P 0.43 2.555 1 P 3 8 0;0,1=18,2=2
P 0.985 2.185 1 P 3 8 0;0,1=18,2=2
P 0.905 1.885 1 P 3 8 0;0,1=18,2=2
P 0.945 1.97 1 P 3 8 0;0,1=18,2=2
P 0.905 1.935 1 P 3 8 0;0,1=18,2=2
P 1.26 0.72 1 P 3 8 0;0,1=18,2=2
P 4.755 0.825 1 P 3 8 0;0,1=18,2=2
P 4.705 0.825 1 P 3 8 0;0,1=18,2=2
P 5.395 2.92 1 P 3 8 0;0,1=18,2=2
P 6.1437 4.175 1 P 3 8 0;0,1=18,2=2
P 6.02558996 4.175 1 P 3 8 0;0,1=18,2=2
P 6.33 2.865 1 P 3 8 0;0,1=18,2=2
P 5.195 0.815 1 P 3 8 0;0,1=18,2=2
P 5.195 0.755 1 P 3 8 0;0,1=18,2=2
P 3.795 3.758 1 P 3 8 0;0,1=18,2=2
P 3.925 3.239 1 P 3 8 0;0,1=18,2=2
P 4.585 0.865 1 P 3 8 0;0,1=18,2=2
P 4.09 3.71338996 1 P 3 8 0;0,1=18,2=2
P 4.335 3.665 1 P 3 8 0;0,1=18,2=2
P 4.33381998 3.60466004 1 P 3 8 0;0,1=18,2=2
P 4.085 3.11 1 P 3 8 0;0,1=18,2=2
P 3.95 3.7 1 P 3 8 0;0,1=18,2=2
P 3.95 3.6 1 P 3 8 0;0,1=18,2=2
P 4.225 3.545 1 P 3 8 0;0,1=18,2=2
P 4.205 3.66 1 P 3 8 0;0,1=18,2=2
P 1.0541 3.185 1 P 3 8 0;0,1=18,2=2
P 2.05 3.488 1 P 3 8 0;0,1=18,2=2
P 2.05 3.538 1 P 3 8 0;0,1=18,2=2
P 2.15 3.438 1 P 3 8 0;0,1=18,2=2
P 5.78936998 4.175 1 P 3 8 0;0,1=18,2=2
P 5.67126004 4.175 1 P 3 8 0;0,1=18,2=2
P 5.55315 4.175 1 P 3 8 0;0,1=18,2=2
P 5.48828996 4.16328996 1 P 3 8 0;0,1=18,2=2
P 5.865 1.07 1 P 3 8 0;0,1=18,2=2
P 5.865 1.125 1 P 3 8 0;0,1=18,2=2
P 0.91 1.815 1 P 3 8 0;0,1=18,2=2
P 4.82 0.835 1 P 3 8 0;0,1=18,2=2
P 1.7317 0.7084 1 P 3 8 0;0,1=18,2=2
P 3.125 1.605 1 P 3 8 0;0,1=18,2=2
P 0.955 1.455 1 P 3 8 0;0,1=18,2=2
P 4.5 4.165 1 P 3 8 0;0,1=18,2=2
P 4.5 4.115 1 P 3 8 0;0,1=18,2=2
P 3.44 2.12 1 P 3 8 0;0,1=18,2=2
P 3.24 2.275 1 P 3 8 0;0,1=18,2=2
P 4.79246004 1.78463996 1 P 3 8 0;0,1=18,2=2
P 1.125 3.02 1 P 3 8 0;0,1=18,2=2
P 1.075 3.02 1 P 3 8 0;0,1=18,2=2
P 1.295 3.28 1 P 3 8 0;0,1=18,2=2
P 1.26 3.18 1 P 3 8 0;0,1=18,2=2
P 0.78635 3.24491998 1 P 3 8 0;0,1=18,2=2
P 0.79 3.155 1 P 3 8 0;0,1=18,2=2
P 0.82951004 3.2794 1 P 3 8 0;0,1=18,2=2
P 0.951 3.519 1 P 3 8 0;0,1=18,2=2
P 0.83 3.525 1 P 3 8 0;0,1=18,2=2
P 0.795 3.485 1 P 3 8 0;0,1=18,2=2
P 0.83 3.445 1 P 3 8 0;0,1=18,2=2
P 0.724 2.646 1 P 3 8 0;0,1=18,2=2
P 6.0085 1.1235 1 P 3 8 0;0,1=18,2=2
P 4.9806 1.855 1 P 3 8 0;0,1=18,2=2
P 6.04 2.545 1 P 3 8 0;0,1=18,2=2
P 6.095 2.545 1 P 3 8 0;0,1=18,2=2
P 4.31 4.115 1 P 3 8 0;0,1=18,2=2
P 4.31 4.065 1 P 3 8 0;0,1=18,2=2
P 3.48863002 4.105 1 P 3 8 0;0,1=18,2=2
P 0.715 0.77 1 P 3 8 0;0,1=18,2=2
P 1.5086 0.674 1 P 3 8 0;0,1=18,2=2
P 1.746 4.106 1 P 3 8 0;0,1=18,2=2
P 1.751 3.826 1 P 3 8 0;0,1=18,2=2
P 2.285 3.825 1 P 3 8 0;0,1=18,2=2
P 3.12 2.17 1 P 3 8 0;0,1=18,2=2
P 3.213 4.236 1 P 3 8 0;0,1=18,2=2
P 3.285 2.589 1 P 3 8 0;0,1=18,2=2
P 3.67 2.32 1 P 3 8 0;0,1=18,2=2
P 4.414 0.781 1 P 3 8 0;0,1=18,2=2
P 4.71 2.592 1 P 3 8 0;0,1=18,2=2
P 5.332 2.2 1 P 3 8 0;0,1=18,2=2
P 5.48556998 3.877 1 P 3 8 0;0,1=18,2=2
P 5.637 3.524 1 P 3 8 0;0,1=18,2=2
P 0.575 2.89 1 P 3 8 0;0,1=18,2=2
P 5.92 1.36 1 P 3 8 0;0,1=18,2=2
P 0.987 2.683 1 P 3 8 0;0,1=18,2=2
P 6.06901998 1.86 1 P 3 8 0;0,1=18,2=2
P 5.875 1.9 1 P 3 8 0;0,1=18,2=2
P 0.09 2.79 1 P 3 8 0;1=18,2=2
P 0.09 2.86 1 P 3 8 0;1=18,2=2
P 0.15 2.79 1 P 3 8 0;1=18,2=2
P 0.957 2.275 1 P 3 8 0;0,1=18,2=2
P 0.46 2.195 1 P 3 8 0;0,1=18,2=2
P 0.805 4.205 1 P 3 8 0;0,1=18,2=2
P 0.952 1.51 1 P 3 8 0;0,1=18,2=2
P 0.455 1.825 1 P 3 8 0;0,1=18,2=2
P 0.19 2.625 1 P 3 8 0;0,1=18,2=2
P 0.405 2.62 1 P 3 8 0;0,1=18,2=2
P 0.332 2.62508002 1 P 3 8 0;0,1=18,2=2
P 0.885 1.49 1 P 3 8 0;0,1=18,2=2
P 0.455 1.0439 1 P 3 8 0;0,1=18,2=2
P 0.555 0.59 1 P 3 8 0;0,1=18,2=2
P 0.445 0.735 1 P 3 8 0;0,1=18,2=2
P 0.845 2.18 1 P 3 8 0;0,1=18,2=2
P 3.46 3.065 1 P 3 8 0;1=18,2=2
P 3.51 3.08 1 P 3 8 0;1=18,2=2
P 4.97 3.41 1 P 3 8 0;0,1=18,2=2
P 4.80288002 2.03788002 1 P 3 8 0;0,1=18,2=2
P 4.83871004 1.98241004 1 P 3 8 0;0,1=18,2=2
P 0.57 0.835 1 P 3 8 0;0,1=18,2=2
P 0.552 2.535 1 P 3 8 0;0,1=18,2=2
P 0.53 2.005 1 P 3 8 0;0,1=18,2=2
P 0.55921998 1.40543002 1 P 3 8 0;0,1=18,2=2
P 0.48956998 1.53618996 1 P 3 8 0;0,1=18,2=2
P 0.575 1.015 1 P 3 8 0;0,1=18,2=2
P 0.528 2.72 1 P 3 8 0;0,1=18,2=2
P 0.496 2.13455 1 P 3 8 0;0,1=18,2=2
P 0.1362 1.4872 1 P 3 8 0;0,1=18,2=2
P 0.13 1.57 1 P 3 8 0;0,1=18,2=2
P 0.125 1.62 1 P 3 8 0;0,1=18,2=2
P 0.125 0.91 1 P 3 8 0;0,1=18,2=2
P 0.125 1.01 1 P 3 8 0;0,1=18,2=2
P 0.125 1.06 1 P 3 8 0;0,1=18,2=2
P 0.125 2.615 1 P 3 8 0;0,1=18,2=2
P 0.287 2.743 1 P 3 8 0;0,1=18,2=2
P 0.13 2.73326998 1 P 3 8 0;0,1=18,2=2
P 0.125 2.045 1 P 3 8 0;0,1=18,2=2
P 0.125 2.145 1 P 3 8 0;0,1=18,2=2
P 0.125 2.195 1 P 3 8 0;0,1=18,2=2
P 0.13 3.187 1 P 3 8 0;0,1=18,2=2
P 0.28 3.27 1 P 3 8 0;0,1=18,2=2
P 0.355 3.27 1 P 3 8 0;0,1=18,2=2
P 5.50368996 4.27558002 1 P 3 8 0;0,1=18,2=2
P 5.38558002 4.27558002 1 P 3 8 0;0,1=18,2=2
P 5.6218 4.27558002 1 P 3 8 0;0,1=18,2=2
P 5.73991004 4.27558002 1 P 3 8 0;0,1=18,2=2
P 5.97613002 4.27558002 1 P 3 8 0;0,1=18,2=2
P 6.09423996 4.27558002 1 P 3 8 0;0,1=18,2=2
P 5.38558002 4.13778996 1 P 3 8 0;0,1=18,2=2
P 5.485 4.11 1 P 3 8 0;0,1=18,2=2
P 5.6218 4.13778996 1 P 3 8 0;0,1=18,2=2
P 5.725 4.135 1 P 3 8 0;0,1=18,2=2
P 5.90748002 4.18725 1 P 3 8 0;0,1=18,2=2
P 5.97613002 4.13778996 1 P 3 8 0;0,1=18,2=2
P 6.09423996 4.13778996 1 P 3 8 0;0,1=18,2=2
P 5.681 3.664 1 P 3 8 0;0,1=18,2=2
P 5.681 3.617 1 P 3 8 0;0,1=18,2=2
P 6.22 1.755 1 P 3 8 0;0,1=18,2=2
P 5.92 1.78 1 P 3 8 0;0,1=18,2=2
P 6.22035 1.67063002 1 P 3 8 0;0,1=18,2=2
P 5.92 1.68 1 P 3 8 0;0,1=18,2=2
P 6.22 1.465 1 P 3 8 0;0,1=18,2=2
P 5.92 1.46 1 P 3 8 0;0,1=18,2=2
P 6.22 1.57 1 P 3 8 0;0,1=18,2=2
P 5.92 1.57063002 1 P 3 8 0;0,1=18,2=2
P 3.655 2.465 1 P 3 8 0;0,1=18,2=2
P 5.49 0.635 1 P 3 8 0;0,1=18,2=2
P 1.352 4.084 1 P 3 8 0;0,1=18,2=2
P 0.55 3.554 1 P 3 8 0;0,1=18,2=2
P 0.55 3.36 1 P 3 8 0;0,1=18,2=2
P 1.19 3.52 1 P 3 8 0;0,1=18,2=2
P 1.03 3.515 1 P 3 8 0;0,1=18,2=2
P 4.385 3.645 1 P 3 8 0;0,1=18,2=2
P 4.47 3.21998002 1 P 3 8 0;0,1=18,2=2
P 5.2 0.87 1 P 3 8 0;0,1=18,2=2
P 1.795 2.946 1 P 3 8 0;0,1=18,2=2
P 1.78 3.095 1 P 3 8 0;0,1=18,2=2
P 1.765 2.9 1 P 3 8 0;0,1=18,2=2
P 1.738 3.241 1 P 3 8 0;0,1=18,2=2
P 1.568 3.011 1 P 3 8 0;0,1=18,2=2
P 0.84 1.005 1 P 3 8 0;0,1=18,2=2
P 0.79 1.005 1 P 3 8 0;0,1=18,2=2
P 0.74 1.005 1 P 3 8 0;0,1=18,2=2
P 0.835 1.73 1 P 3 8 0;0,1=18,2=2
P 0.606 1.57 1 P 3 8 0;0,1=18,2=2
P 0.285 3.02 1 P 3 8 0;0,1=18,2=2
P 0.28 2.965 1 P 3 8 0;0,1=18,2=2
P 0.29 2.915 1 P 3 8 0;0,1=18,2=2
P 6.335 1.08 1 P 3 8 0;0,1=18,2=2
P 6.335 1.02 1 P 3 8 0;0,1=18,2=2
P 6.335 0.965 1 P 3 8 0;0,1=18,2=2
P 0.695 2.578 1 P 3 8 0;0,1=18,2=2
P 0.832 2.603 1 P 3 8 0;0,1=18,2=2
P 4.25 0.877 1 P 3 8 0;0,1=18,2=2
P 6.01953002 2.18853002 1 P 3 8 0;0,1=18,2=2
P 2.937 3.173 1 P 3 8 0;0,1=18,2=2
P 5.41 2.164 1 P 3 8 0;0,1=18,2=2
P 5.765 2.197 1 P 3 8 0;0,1=18,2=2
P 3.363 4.232 1 P 3 8 0;0,1=18,2=2
P 5.43 3.6 1 P 3 8 0;0,1=18,2=2
P 5.644 3.967 1 P 3 8 0;0,1=18,2=2
P 5.406 3.863 1 P 3 8 0;0,1=18,2=2
P 5.675 3.865 1 P 3 8 0;0,1=18,2=2
P 5.686 3.76 1 P 3 8 0;0,1=18,2=2
P 5.686 3.807 1 P 3 8 0;0,1=18,2=2
P 5.68326004 3.712 1 P 3 8 0;0,1=18,2=2
P 0.945 3.805 1 P 3 8 0;0,1=18,2=2
P 5.275 3.891 1 P 3 8 0;0,1=18,2=2
P 5.275 3.971 1 P 3 8 0;0,1=18,2=2
P 5.6 3.421 1 P 3 8 0;0,1=18,2=2
P 5.617 3.203 1 P 3 8 0;0,1=18,2=2
P 5.625 3.261 1 P 3 8 0;0,1=18,2=2
P 0.603 3.951 1 P 3 8 0;0,1=18,2=2
P 0.603 4.071 1 P 3 8 0;0,1=18,2=2
P 0.643 4.016 1 P 3 8 0;0,1=18,2=2
P 0.643 4.136 1 P 3 8 0;0,1=18,2=2
P 0.928 4.021 1 P 3 8 0;0,1=18,2=2
P 0.928 4.141 1 P 3 8 0;0,1=18,2=2
P 0.968 4.081 1 P 3 8 0;0,1=18,2=2
P 0.625 3.73 1 P 3 8 0;0,1=18,2=2
P 0.625 3.78 1 P 3 8 0;0,1=18,2=2
P 5.483 2.226 1 P 3 8 0;0,1=18,2=2
P 5.145 1.44 1 P 3 8 0;0,1=18,2=2
P 5.69943002 2.233 1 P 3 8 0;0,1=18,2=2
P 5.589 2.025 1 P 3 8 0;0,1=18,2=2
P 3.894 2.811 1 P 3 8 0;0,1=18,2=2
P 3.948 2.813 1 P 3 8 0;0,1=18,2=2
P 3.96981004 3.04481998 1 P 3 8 0;0,1=18,2=2
P 3.775 2.265 1 P 3 8 0;0,1=18,2=2
P 5.01 2.635 1 P 3 8 0;0,1=18,2=2
P 3.365 3.613 1 P 3 8 0;0,1=18,2=2
P 3.477 3.816 1 P 3 8 0;0,1=18,2=2
P 5.215 0.6 1 P 3 8 0;0,1=18,2=2
P 6.025 4.04 1 P 3 8 0;0,1=18,2=2
P 3.437 4.099 1 P 3 8 0;0,1=18,2=2
P 3.476 3.988 1 P 3 8 0;0,1=18,2=2
P 3.47 3.912 1 P 3 8 0;0,1=18,2=2
P 4.239 2.785 1 P 3 8 0;0,1=18,2=2
P 4.249 2.843 1 P 3 8 0;0,1=18,2=2
P 4.249 2.929 1 P 3 8 0;0,1=18,2=2
P 4.97 1.75 1 P 3 8 0;0,1=18,2=2
P 0.59 0.965 1 P 3 8 0;0,1=18,2=2
P 4.47 2.83 1 P 3 8 0;0,1=18,2=2
P 4.46 2.94 1 P 3 8 0;0,1=18,2=2
P 6.145 4.035 1 P 3 8 0;0,1=18,2=2
P 1.566 2.95 1 P 3 8 0;0,1=18,2=2
P 5.295 0.605 1 P 3 8 0;0,1=18,2=2
P 5.91 4.04 1 P 3 8 0;0,1=18,2=2
P 3.23 4.015 1 P 3 8 0;0,1=18,2=2
P 1.245 3.52 1 P 3 8 0;0,1=18,2=2
P 1.14 3.52 1 P 3 8 0;0,1=18,2=2
P 1.579 3.874 1 P 3 8 0;0,1=18,2=2
P 1.45 3.59 1 P 3 8 0;0,1=18,2=2
P 1.56 3.205 1 P 3 8 0;0,1=18,2=2
P 1.517 4.113 1 P 3 8 0;0,1=18,2=2
P 1.77 3.98 1 P 3 8 0;0,1=18,2=2
P 3.44 1.03 1 P 3 8 0;1=18,2=2
P 5.035 3.945 1 P 3 8 0;0,1=18,2=2
P 3.755 3.505 0 P 1 8 0;0,1=19,2=2
P 0.755 2.825 0 P 1 8 0;0,1=19,2=2
P 0.638 2.74 0 P 1 8 0;0,1=19,2=2
P 1.3825 3.7225 0 P 1 8 0;0,1=19,2=2
P 5.285 2.99 0 P 1 8 0;1=19,2=2
P 4.5733 1.22166998 0 P 1 8 0;0,1=19,2=2
P 4.5413 1.22166998 0 P 1 8 0;0,1=19,2=2
P 4.425 3.36088996 0 P 1 8 0;0,1=19,2=2
P 4.395 3.415 0 P 1 8 0;0,1=19,2=2
P 3.83128002 1.78371998 0 P 1 8 0;0,1=19,2=2
P 4.0165 1.16098996 0 P 1 8 0;0,1=19,2=2
P 4.0485 1.16098996 0 P 1 8 0;0,1=19,2=2
P 4.3765 1.16598996 0 P 1 8 0;0,1=19,2=2
P 4.4085 1.16598996 0 P 1 8 0;0,1=19,2=2
P 2.633 0.522 0 P 1 8 0;0,1=19,2=2
P 1.91535 0.412 0 P 1 8 0;0,1=19,2=2
P 1.98135 0.365 0 P 1 8 0;0,1=19,2=2
P 1.459 0.752 0 P 1 8 0;0,1=19,2=2
P 1.36 2.905 0 P 1 8 0;0,1=19,2=2
P 2.896 3.301 0 P 1 8 0;0,1=19,2=2
P 1.315 2.905 0 P 1 8 0;0,1=19,2=2
P 2.932 3.295 0 P 1 8 0;0,1=19,2=2
P 3.523 1.75 0 P 1 8 0;0,1=19,2=2
P 2.845 1.843 0 P 1 8 0;0,1=19,2=2
P 2.845 1.875 0 P 1 8 0;0,1=19,2=2
P 2.834 1.987 0 P 1 8 0;0,1=19,2=2
P 2.802 1.987 0 P 1 8 0;0,1=19,2=2
P 5.33 0.95 0 P 1 8 0;0,1=19,2=2
P 5.33 0.995 0 P 1 8 0;0,1=19,2=2
P 2.987 3.27 0 P 1 8 0;0,1=19,2=2
P 2.987 3.235 0 P 1 8 0;0,1=19,2=2
P 1.535 3.905 0 P 1 8 0;0,1=19,2=2
P 1.00413002 4.33598002 0 P 1 8 0;0,1=19,2=2
P 1.0146 0.54196998 0 P 1 8 0;0,1=19,2=2
P 1.041 3.825 0 P 1 8 0;0,1=19,2=2
P 1.04413002 4.33598002 0 P 1 8 0;0,1=19,2=2
P 1.0546 0.54196998 0 P 1 8 0;0,1=19,2=2
P 1.08413002 4.33598002 0 P 1 8 0;0,1=19,2=2
P 1.0946 0.54196998 0 P 1 8 0;0,1=19,2=2
P 1.12413002 4.33598002 0 P 1 8 0;0,1=19,2=2
P 1.1346 0.54196998 0 P 1 8 0;0,1=19,2=2
P 1.137 3.825 0 P 1 8 0;0,1=19,2=2
P 1.16413002 4.33598002 0 P 1 8 0;0,1=19,2=2
P 1.1746 0.54196998 0 P 1 8 0;0,1=19,2=2
P 1.20413002 4.33598002 0 P 1 8 0;0,1=19,2=2
P 1.2146 0.54196998 0 P 1 8 0;0,1=19,2=2
P 0.12413002 4.33598002 0 P 1 8 0;0,1=19,2=2
P 1.24413002 4.33598002 0 P 1 8 0;0,1=19,2=2
P 1.2546 0.54196998 0 P 1 8 0;0,1=19,2=2
P 0.12878002 0.21716998 0 P 1 8 0;0,1=19,2=2
P 1.28413002 4.33598002 0 P 1 8 0;0,1=19,2=2
P 1.2945 0.53916998 0 P 1 8 0;0,1=19,2=2
P 1.32413002 4.33598002 0 P 1 8 0;0,1=19,2=2
P 1.3292 0.51926004 0 P 1 8 0;0,1=19,2=2
P 1.34976998 0.48496004 0 P 1 8 0;0,1=19,2=2
P 1.35298996 0.24508996 0 P 1 8 0;0,1=19,2=2
P 1.35298996 0.28508996 0 P 1 8 0;0,1=19,2=2
P 1.35298996 0.32508996 0 P 1 8 0;0,1=19,2=2
P 1.35298996 0.36508996 0 P 1 8 0;0,1=19,2=2
P 1.35298996 0.40508996 0 P 1 8 0;0,1=19,2=2
P 1.35298996 0.44508996 0 P 1 8 0;0,1=19,2=2
P 1.36413002 4.33598002 0 P 1 8 0;0,1=19,2=2
P 1.38163002 0.21716998 0 P 1 8 0;0,1=19,2=2
P 1.385 0.75 0 P 1 8 0;0,1=19,2=2
P 1.40413002 4.33598002 0 P 1 8 0;0,1=19,2=2
P 1.42163002 0.21716998 0 P 1 8 0;0,1=19,2=2
P 1.44 0.625 0 P 1 8 0;0,1=19,2=2
P 1.44413002 4.33598002 0 P 1 8 0;0,1=19,2=2
P 1.46163002 0.21716998 0 P 1 8 0;0,1=19,2=2
P 1.48413002 4.33598002 0 P 1 8 0;0,1=19,2=2
P 1.50163002 0.21716998 0 P 1 8 0;0,1=19,2=2
P 1.5184 0.79935 0 P 1 8 0;0,1=19,2=2
P 1.52413002 4.33598002 0 P 1 8 0;0,1=19,2=2
P 1.54163002 0.21716998 0 P 1 8 0;0,1=19,2=2
P 1.56413002 4.33598002 0 P 1 8 0;0,1=19,2=2
P 1.58163002 0.21716998 0 P 1 8 0;0,1=19,2=2
P 1.58795 0.25666998 0 P 1 8 0;0,1=19,2=2
P 1.58795 0.29666998 0 P 1 8 0;0,1=19,2=2
P 1.58795 0.33666998 0 P 1 8 0;0,1=19,2=2
P 1.58795 0.37666998 0 P 1 8 0;0,1=19,2=2
P 1.58795 0.41666998 0 P 1 8 0;0,1=19,2=2
P 1.59111998 0.45653996 0 P 1 8 0;0,1=19,2=2
P 1.60413002 4.33598002 0 P 1 8 0;0,1=19,2=2
P 1.60736004 0.49308996 0 P 1 8 0;0,1=19,2=2
P 1.63543002 0.52158996 0 P 1 8 0;0,1=19,2=2
P 0.16413002 4.33598002 0 P 1 8 0;0,1=19,2=2
P 1.64413002 4.33598002 0 P 1 8 0;0,1=19,2=2
P 1.671 4.056 0 P 1 8 0;0,1=19,2=2
P 0.16878002 0.21716998 0 P 1 8 0;0,1=19,2=2
P 1.68413002 4.33598002 0 P 1 8 0;0,1=19,2=2
P 1.72413002 4.33598002 0 P 1 8 0;0,1=19,2=2
P 1.76413002 4.33598002 0 P 1 8 0;0,1=19,2=2
P 1.78196004 0.50601004 0 P 1 8 0;0,1=19,2=2
P 1.80341004 0.47225 0 P 1 8 0;0,1=19,2=2
P 1.80413002 4.33598002 0 P 1 8 0;0,1=19,2=2
P 1.84413002 4.33598002 0 P 1 8 0;0,1=19,2=2
P 1.88413002 4.33598002 0 P 1 8 0;0,1=19,2=2
P 1.91535 0.289 0 P 1 8 0;0,1=19,2=2
P 1.92413002 4.33598002 0 P 1 8 0;0,1=19,2=2
P 1.96413002 4.33598002 0 P 1 8 0;0,1=19,2=2
P 2.00413002 4.33598002 0 P 1 8 0;0,1=19,2=2
P 2.0195 0.2905 0 P 1 8 0;0,1=19,2=2
P 0.20413002 4.33598002 0 P 1 8 0;0,1=19,2=2
P 2.04413002 4.33598002 0 P 1 8 0;0,1=19,2=2
P 0.20878002 0.21716998 0 P 1 8 0;0,1=19,2=2
P 2.083 2.895 0 P 1 8 0;0,1=19,2=2
P 2.08413002 4.33598002 0 P 1 8 0;0,1=19,2=2
P 2.0966 3.315 0 P 1 8 0;0,1=19,2=2
P 2.12413002 4.33598002 0 P 1 8 0;0,1=19,2=2
P 2.16413002 4.33598002 0 P 1 8 0;0,1=19,2=2
P 2.173 2.895 0 P 1 8 0;0,1=19,2=2
P 2.20413002 4.33598002 0 P 1 8 0;0,1=19,2=2
P 2.218 2.895 0 P 1 8 0;0,1=19,2=2
P 2.24413002 4.33598002 0 P 1 8 0;0,1=19,2=2
P 2.28413002 4.33598002 0 P 1 8 0;0,1=19,2=2
P 2.32413002 4.33598002 0 P 1 8 0;0,1=19,2=2
P 2.327 0.291 0 P 1 8 0;0,1=19,2=2
P 2.36413002 4.33598002 0 P 1 8 0;0,1=19,2=2
P 2.40413002 4.33598002 0 P 1 8 0;0,1=19,2=2
P 2.40508002 0.667 0 P 1 8 0;0,1=19,2=2
P 2.40508002 0.763 0 P 1 8 0;0,1=19,2=2
P 2.43821998 0.763 0 P 1 8 0;0,1=19,2=2
P 0.24413002 4.33598002 0 P 1 8 0;0,1=19,2=2
P 2.44413002 4.33598002 0 P 1 8 0;0,1=19,2=2
P 2.44618996 0.289 0 P 1 8 0;0,1=19,2=2
P 0.24878002 0.21716998 0 P 1 8 0;0,1=19,2=2
P 2.48413002 4.33598002 0 P 1 8 0;0,1=19,2=2
P 2.52413002 4.33598002 0 P 1 8 0;0,1=19,2=2
P 2.53421998 0.763 0 P 1 8 0;0,1=19,2=2
P 2.54526998 0.289 0 P 1 8 0;0,1=19,2=2
P 2.56413002 4.33598002 0 P 1 8 0;0,1=19,2=2
P 2.60413002 4.33598002 0 P 1 8 0;0,1=19,2=2
P 2.63506998 0.763 0 P 1 8 0;0,1=19,2=2
P 2.64303996 0.289 0 P 1 8 0;0,1=19,2=2
P 2.64338996 0.321 0 P 1 8 0;0,1=19,2=2
P 2.64338996 0.417 0 P 1 8 0;0,1=19,2=2
P 2.64413002 4.33598002 0 P 1 8 0;0,1=19,2=2
P 2.68413002 4.33598002 0 P 1 8 0;0,1=19,2=2
P 2.72308996 0.289 0 P 1 8 0;0,1=19,2=2
P 2.72413002 4.33598002 0 P 1 8 0;0,1=19,2=2
P 2.73106998 0.763 0 P 1 8 0;0,1=19,2=2
P 2.76413002 4.33598002 0 P 1 8 0;0,1=19,2=2
P 2.77 1.987 0 P 1 8 0;0,1=19,2=2
P 2.78655 0.763 0 P 1 8 0;0,1=19,2=2
P 2.80051998 0.289 0 P 1 8 0;0,1=19,2=2
P 2.80086998 0.321 0 P 1 8 0;0,1=19,2=2
P 2.80086998 0.417 0 P 1 8 0;0,1=19,2=2
P 2.80413002 4.33598002 0 P 1 8 0;0,1=19,2=2
P 0.28413002 4.33598002 0 P 1 8 0;0,1=19,2=2
P 2.84413002 4.33598002 0 P 1 8 0;0,1=19,2=2
P 2.845 1.811 0 P 1 8 0;0,1=19,2=2
P 2.845 1.907 0 P 1 8 0;0,1=19,2=2
P 2.86151004 3.295 0 P 1 8 0;0,1=19,2=2
P 2.866 1.987 0 P 1 8 0;0,1=19,2=2
P 0.28878002 0.21716998 0 P 1 8 0;0,1=19,2=2
P 2.88056998 0.289 0 P 1 8 0;0,1=19,2=2
P 2.88255 0.763 0 P 1 8 0;0,1=19,2=2
P 2.88413002 4.33598002 0 P 1 8 0;0,1=19,2=2
P 2.92413002 4.33598002 0 P 1 8 0;0,1=19,2=2
P 2.958 0.289 0 P 1 8 0;0,1=19,2=2
P 2.95835 0.321 0 P 1 8 0;0,1=19,2=2
P 2.95835 0.417 0 P 1 8 0;0,1=19,2=2
P 2.96413002 4.33598002 0 P 1 8 0;0,1=19,2=2
P 2.98726004 0.43528996 0 P 1 8 0;0,1=19,2=2
P 2.98726004 0.49471004 0 P 1 8 0;0,1=19,2=2
P 3.00413002 4.33598002 0 P 1 8 0;0,1=19,2=2
P 3.04413002 4.33598002 0 P 1 8 0;0,1=19,2=2
P 3.07708002 0.289 0 P 1 8 0;0,1=19,2=2
P 3.08413002 4.33598002 0 P 1 8 0;0,1=19,2=2
P 3.10236998 0.89763002 0 P 1 8 0;0,1=19,2=2
P 3.106 3.305 0 P 1 8 0;0,1=19,2=2
P 3.12413002 4.33598002 0 P 1 8 0;0,1=19,2=2
P 3.16413002 4.33598002 0 P 1 8 0;0,1=19,2=2
P 3.17025 0.82975 0 P 1 8 0;0,1=19,2=2
P 3.17401998 0.54196998 0 P 1 8 0;0,1=19,2=2
P 3.1951 1.90298996 0 P 1 8 0;0,1=19,2=2
P 3.20413002 4.33598002 0 P 1 8 0;0,1=19,2=2
P 3.21401998 0.54196998 0 P 1 8 0;0,1=19,2=2
P 3.222 3.25 0 P 1 8 0;0,1=19,2=2
P 0.32413002 4.33598002 0 P 1 8 0;0,1=19,2=2
P 3.24413002 4.33598002 0 P 1 8 0;0,1=19,2=2
P 3.25401998 0.54196998 0 P 1 8 0;0,1=19,2=2
P 0.32878002 0.21716998 0 P 1 8 0;0,1=19,2=2
P 3.28413002 4.33598002 0 P 1 8 0;0,1=19,2=2
P 3.2911 1.90298996 0 P 1 8 0;0,1=19,2=2
P 3.29401998 0.54196998 0 P 1 8 0;0,1=19,2=2
P 3.32413002 4.33598002 0 P 1 8 0;0,1=19,2=2
P 3.33401998 0.54196998 0 P 1 8 0;0,1=19,2=2
P 3.36413002 4.33598002 0 P 1 8 0;0,1=19,2=2
P 3.37401998 0.54196998 0 P 1 8 0;0,1=19,2=2
P 3.375 1.13 0 P 1 8 0;0,1=19,2=2
P 3.375 1.226 0 P 1 8 0;0,1=19,2=2
P 3.38598996 1.085 0 P 1 8 0;0,1=19,2=2
P 3.40413002 4.33598002 0 P 1 8 0;0,1=19,2=2
P 3.41401998 0.54196998 0 P 1 8 0;0,1=19,2=2
P 3.44413002 4.33598002 0 P 1 8 0;0,1=19,2=2
P 3.45301004 1.86698996 0 P 1 8 0;0,1=19,2=2
P 3.45301004 1.96298996 0 P 1 8 0;0,1=19,2=2
P 3.45401998 0.54196998 0 P 1 8 0;0,1=19,2=2
P 3.48198996 1.085 0 P 1 8 0;0,1=19,2=2
P 3.48263996 1.04706998 0 P 1 8 0;0,1=19,2=2
P 3.48413002 4.33598002 0 P 1 8 0;0,1=19,2=2
P 3.49401998 0.54196998 0 P 1 8 0;0,1=19,2=2
P 3.52413002 4.33598002 0 P 1 8 0;0,1=19,2=2
P 3.53401998 0.54196998 0 P 1 8 0;0,1=19,2=2
P 3.548 2.898 0 P 1 8 0;0,1=19,2=2
P 3.5485 2.761 0 P 1 8 0;0,1=19,2=2
P 3.55 3.325 0 P 1 8 0;0,1=19,2=2
P 3.56413002 4.33598002 0 P 1 8 0;0,1=19,2=2
P 3.57401998 0.54196998 0 P 1 8 0;0,1=19,2=2
P 3.57863996 1.04706998 0 P 1 8 0;0,1=19,2=2
P 3.593 0.92 0 P 1 8 0;0,1=19,2=2
P 3.60413002 4.33598002 0 P 1 8 0;0,1=19,2=2
P 3.61401998 0.54196998 0 P 1 8 0;0,1=19,2=2
P 0.36413002 4.33598002 0 P 1 8 0;0,1=19,2=2
P 3.64413002 4.33598002 0 P 1 8 0;0,1=19,2=2
P 3.65101004 1.85158996 0 P 1 8 0;0,1=19,2=2
P 3.65101004 1.94758996 0 P 1 8 0;0,1=19,2=2
P 3.65401998 0.54196998 0 P 1 8 0;0,1=19,2=2
P 0.36878002 0.21716998 0 P 1 8 0;0,1=19,2=2
P 3.68413002 4.33598002 0 P 1 8 0;0,1=19,2=2
P 3.689 0.92 0 P 1 8 0;0,1=19,2=2
P 3.69401998 0.54196998 0 P 1 8 0;0,1=19,2=2
P 3.72413002 4.33598002 0 P 1 8 0;0,1=19,2=2
P 3.73401998 0.54196998 0 P 1 8 0;0,1=19,2=2
P 3.735 0.78 0 P 1 8 0;0,1=19,2=2
P 3.735 0.94 0 P 1 8 0;0,1=19,2=2
P 3.76413002 4.33598002 0 P 1 8 0;0,1=19,2=2
P 3.77401998 0.54196998 0 P 1 8 0;0,1=19,2=2
P 3.80413002 4.33598002 0 P 1 8 0;0,1=19,2=2
P 3.805 0.774 0 P 1 8 0;0,1=19,2=2
P 3.81401998 0.54196998 0 P 1 8 0;0,1=19,2=2
P 3.84413002 4.33598002 0 P 1 8 0;0,1=19,2=2
P 3.85401998 0.54196998 0 P 1 8 0;0,1=19,2=2
P 3.88413002 4.33598002 0 P 1 8 0;0,1=19,2=2
P 3.89401998 0.54196998 0 P 1 8 0;0,1=19,2=2
P 3.9 1.005 0 P 1 8 0;0,1=19,2=2
P 3.92413002 4.33598002 0 P 1 8 0;0,1=19,2=2
P 3.93401998 0.54196998 0 P 1 8 0;0,1=19,2=2
P 3.96413002 4.33598002 0 P 1 8 0;0,1=19,2=2
P 3.97401998 0.54196998 0 P 1 8 0;0,1=19,2=2
P 3.9845 1.16098996 0 P 1 8 0;0,1=19,2=2
P 0.04 0.25618996 0 P 1 8 0;0,1=19,2=2
P 0.04 2.81618996 0 P 1 8 0;0,1=19,2=2
P 0.04 2.85618996 0 P 1 8 0;0,1=19,2=2
P 0.04 2.89618996 0 P 1 8 0;0,1=19,2=2
P 0.04 2.93618996 0 P 1 8 0;0,1=19,2=2
P 0.04 0.29618996 0 P 1 8 0;0,1=19,2=2
P 0.04 2.97618996 0 P 1 8 0;0,1=19,2=2
P 0.04 3.01618996 0 P 1 8 0;0,1=19,2=2
P 0.04 3.05618996 0 P 1 8 0;0,1=19,2=2
P 0.04 3.09618996 0 P 1 8 0;0,1=19,2=2
P 0.04 3.13618996 0 P 1 8 0;0,1=19,2=2
P 0.04 0.33618996 0 P 1 8 0;0,1=19,2=2
P 0.04 3.37618996 0 P 1 8 0;0,1=19,2=2
P 0.04 3.41618996 0 P 1 8 0;0,1=19,2=2
P 0.04 3.45618996 0 P 1 8 0;0,1=19,2=2
P 0.04 3.49618996 0 P 1 8 0;0,1=19,2=2
P 0.04 3.53618996 0 P 1 8 0;0,1=19,2=2
P 0.04 3.57618996 0 P 1 8 0;0,1=19,2=2
P 0.04 3.61618996 0 P 1 8 0;0,1=19,2=2
P 0.04 3.65618996 0 P 1 8 0;0,1=19,2=2
P 0.04 3.69618996 0 P 1 8 0;0,1=19,2=2
P 0.04 3.73618996 0 P 1 8 0;0,1=19,2=2
P 0.04 0.37618996 0 P 1 8 0;0,1=19,2=2
P 0.04 3.77618996 0 P 1 8 0;0,1=19,2=2
P 0.04 3.81618996 0 P 1 8 0;0,1=19,2=2
P 0.04 3.85618996 0 P 1 8 0;0,1=19,2=2
P 0.04 3.89618996 0 P 1 8 0;0,1=19,2=2
P 0.04 3.93618996 0 P 1 8 0;0,1=19,2=2
P 0.04 3.97618996 0 P 1 8 0;0,1=19,2=2
P 0.04 4.01618996 0 P 1 8 0;0,1=19,2=2
P 0.04 4.05618996 0 P 1 8 0;0,1=19,2=2
P 0.04 4.09618996 0 P 1 8 0;0,1=19,2=2
P 0.04 4.13618996 0 P 1 8 0;0,1=19,2=2
P 0.04 0.41618996 0 P 1 8 0;0,1=19,2=2
P 0.04 4.17618996 0 P 1 8 0;0,1=19,2=2
P 0.04 4.21618996 0 P 1 8 0;0,1=19,2=2
P 0.04 4.25618996 0 P 1 8 0;0,1=19,2=2
P 0.04 4.29618996 0 P 1 8 0;0,1=19,2=2
P 0.04 0.45618996 0 P 1 8 0;0,1=19,2=2
P 0.04 0.49618996 0 P 1 8 0;0,1=19,2=2
P 4.00413002 4.33598002 0 P 1 8 0;0,1=19,2=2
P 4.01401998 0.54196998 0 P 1 8 0;0,1=19,2=2
P 0.40413002 4.33598002 0 P 1 8 0;0,1=19,2=2
P 4.04413002 4.33598002 0 P 1 8 0;0,1=19,2=2
P 4.05401998 0.54196998 0 P 1 8 0;0,1=19,2=2
P 0.40878002 0.21716998 0 P 1 8 0;0,1=19,2=2
P 4.0805 1.16098996 0 P 1 8 0;0,1=19,2=2
P 4.08413002 4.33598002 0 P 1 8 0;0,1=19,2=2
P 4.092 1.005 0 P 1 8 0;0,1=19,2=2
P 4.09401998 0.54196998 0 P 1 8 0;0,1=19,2=2
P 4.12413002 4.33598002 0 P 1 8 0;0,1=19,2=2
P 4.13401998 0.54196998 0 P 1 8 0;0,1=19,2=2
P 4.13621998 0.75 0 P 1 8 0;0,1=19,2=2
P 4.16413002 4.33598002 0 P 1 8 0;0,1=19,2=2
P 4.17401998 0.54196998 0 P 1 8 0;0,1=19,2=2
P 4.20413002 4.33598002 0 P 1 8 0;0,1=19,2=2
P 4.21401998 0.54196998 0 P 1 8 0;0,1=19,2=2
P 4.24413002 4.33598002 0 P 1 8 0;0,1=19,2=2
P 4.25401998 0.54196998 0 P 1 8 0;0,1=19,2=2
P 4.28413002 4.33598002 0 P 1 8 0;0,1=19,2=2
P 4.29401998 0.54196998 0 P 1 8 0;0,1=19,2=2
P 4.32413002 4.33598002 0 P 1 8 0;0,1=19,2=2
P 4.33401998 0.54196998 0 P 1 8 0;0,1=19,2=2
P 4.3445 1.16598996 0 P 1 8 0;0,1=19,2=2
P 4.36413002 4.33598002 0 P 1 8 0;0,1=19,2=2
P 4.37401998 0.54196998 0 P 1 8 0;0,1=19,2=2
P 4.395 3.37891998 0 P 1 8 0;0,1=19,2=2
P 0.04413002 4.33598002 0 P 1 8 0;0,1=19,2=2
P 4.40413002 4.33598002 0 P 1 8 0;0,1=19,2=2
P 4.41401998 0.54196998 0 P 1 8 0;0,1=19,2=2
P 4.43 3.965 0 P 1 8 0;0,1=19,2=2
P 4.43 4.015 0 P 1 8 0;0,1=19,2=2
P 0.44413002 4.33598002 0 P 1 8 0;0,1=19,2=2
P 4.44 4.165 0 P 1 8 0;0,1=19,2=2
P 4.4405 1.16598996 0 P 1 8 0;0,1=19,2=2
P 4.44413002 4.33598002 0 P 1 8 0;0,1=19,2=2
P 4.45401998 0.54196998 0 P 1 8 0;0,1=19,2=2
P 4.465 2.895 0 P 1 8 0;0,1=19,2=2
P 0.44878002 0.21716998 0 P 1 8 0;0,1=19,2=2
P 4.48413002 4.33598002 0 P 1 8 0;0,1=19,2=2
P 4.49401998 0.54196998 0 P 1 8 0;0,1=19,2=2
P 4.5093 1.22166998 0 P 1 8 0;0,1=19,2=2
P 4.52413002 4.33598002 0 P 1 8 0;0,1=19,2=2
P 4.53401998 0.54196998 0 P 1 8 0;0,1=19,2=2
P 4.56413002 4.33598002 0 P 1 8 0;0,1=19,2=2
P 4.57401998 0.54196998 0 P 1 8 0;0,1=19,2=2
P 4.60413002 4.33598002 0 P 1 8 0;0,1=19,2=2
P 4.6053 1.22166998 0 P 1 8 0;0,1=19,2=2
P 4.61401998 0.54196998 0 P 1 8 0;0,1=19,2=2
P 4.64413002 4.33598002 0 P 1 8 0;0,1=19,2=2
P 4.65401998 0.54196998 0 P 1 8 0;0,1=19,2=2
P 4.68413002 4.33598002 0 P 1 8 0;0,1=19,2=2
P 4.69401998 0.54196998 0 P 1 8 0;0,1=19,2=2
P 4.72413002 4.33598002 0 P 1 8 0;0,1=19,2=2
P 4.73401998 0.54196998 0 P 1 8 0;0,1=19,2=2
P 4.76413002 4.33598002 0 P 1 8 0;0,1=19,2=2
P 4.77401998 0.54196998 0 P 1 8 0;0,1=19,2=2
P 0.04878002 0.21716998 0 P 1 8 0;0,1=19,2=2
P 4.80413002 4.33598002 0 P 1 8 0;0,1=19,2=2
P 4.81401998 0.54196998 0 P 1 8 0;0,1=19,2=2
P 0.48413002 4.33598002 0 P 1 8 0;0,1=19,2=2
P 4.84413002 4.33598002 0 P 1 8 0;0,1=19,2=2
P 4.85401998 0.54196998 0 P 1 8 0;0,1=19,2=2
P 0.48878002 0.21716998 0 P 1 8 0;0,1=19,2=2
P 4.88413002 4.33598002 0 P 1 8 0;0,1=19,2=2
P 4.89401998 0.54196998 0 P 1 8 0;0,1=19,2=2
P 4.92413002 4.33598002 0 P 1 8 0;0,1=19,2=2
P 4.93401998 0.54196998 0 P 1 8 0;0,1=19,2=2
P 4.96413002 4.33598002 0 P 1 8 0;0,1=19,2=2
P 4.97401998 0.54196998 0 P 1 8 0;0,1=19,2=2
P 5.00413002 4.33598002 0 P 1 8 0;0,1=19,2=2
P 5.01401998 0.54196998 0 P 1 8 0;0,1=19,2=2
P 5.04413002 4.33598002 0 P 1 8 0;0,1=19,2=2
P 5.05401998 0.54196998 0 P 1 8 0;0,1=19,2=2
P 5.08413002 4.33598002 0 P 1 8 0;0,1=19,2=2
P 5.09401998 0.54196998 0 P 1 8 0;0,1=19,2=2
P 5.12413002 4.33598002 0 P 1 8 0;0,1=19,2=2
P 5.13401998 0.54196998 0 P 1 8 0;0,1=19,2=2
P 5.16413002 4.33598002 0 P 1 8 0;0,1=19,2=2
P 5.17401998 0.54196998 0 P 1 8 0;0,1=19,2=2
P 5.20413002 4.33598002 0 P 1 8 0;0,1=19,2=2
P 5.21401998 0.54196998 0 P 1 8 0;0,1=19,2=2
P 0.52413002 4.33598002 0 P 1 8 0;0,1=19,2=2
P 5.24413002 4.33598002 0 P 1 8 0;0,1=19,2=2
P 5.25401998 0.54196998 0 P 1 8 0;0,1=19,2=2
P 0.52878002 0.21716998 0 P 1 8 0;0,1=19,2=2
P 5.28413002 4.33598002 0 P 1 8 0;0,1=19,2=2
P 5.29401998 0.54196998 0 P 1 8 0;0,1=19,2=2
P 5.32413002 4.33598002 0 P 1 8 0;0,1=19,2=2
P 5.33401998 0.54196998 0 P 1 8 0;0,1=19,2=2
P 5.36413002 4.33598002 0 P 1 8 0;0,1=19,2=2
P 5.37401998 0.54196998 0 P 1 8 0;0,1=19,2=2
P 5.40413002 4.33598002 0 P 1 8 0;0,1=19,2=2
P 5.41401998 0.54196998 0 P 1 8 0;0,1=19,2=2
P 5.44413002 4.33598002 0 P 1 8 0;0,1=19,2=2
P 5.45401998 0.54196998 0 P 1 8 0;0,1=19,2=2
P 5.48413002 4.33598002 0 P 1 8 0;0,1=19,2=2
P 5.49401998 0.54196998 0 P 1 8 0;0,1=19,2=2
P 0.55055 0.25073002 0 P 1 8 0;0,1=19,2=2
P 0.55055 0.29073002 0 P 1 8 0;0,1=19,2=2
P 0.55055 0.33073002 0 P 1 8 0;0,1=19,2=2
P 0.55055 0.37073002 0 P 1 8 0;0,1=19,2=2
P 0.55055 0.41073002 0 P 1 8 0;0,1=19,2=2
P 0.55055 0.45073002 0 P 1 8 0;0,1=19,2=2
P 5.52413002 4.33598002 0 P 1 8 0;0,1=19,2=2
P 5.53401998 0.54196998 0 P 1 8 0;0,1=19,2=2
P 0.55558002 0.49041004 0 P 1 8 0;0,1=19,2=2
P 5.56413002 4.33598002 0 P 1 8 0;0,1=19,2=2
P 5.57401998 0.54196998 0 P 1 8 0;0,1=19,2=2
P 5.60413002 4.33598002 0 P 1 8 0;0,1=19,2=2
P 5.61401998 0.54196998 0 P 1 8 0;0,1=19,2=2
P 0.56413002 4.33598002 0 P 1 8 0;0,1=19,2=2
P 5.64413002 4.33598002 0 P 1 8 0;0,1=19,2=2
P 5.65401998 0.54196998 0 P 1 8 0;0,1=19,2=2
P 5.666 2.129 0 P 1 8 0;0,1=19,2=2
P 5.68413002 4.33598002 0 P 1 8 0;0,1=19,2=2
P 5.69401998 0.54196998 0 P 1 8 0;0,1=19,2=2
P 5.72413002 4.33598002 0 P 1 8 0;0,1=19,2=2
P 5.73401998 0.54196998 0 P 1 8 0;0,1=19,2=2
P 5.76413002 4.33598002 0 P 1 8 0;0,1=19,2=2
P 5.77401998 0.54196998 0 P 1 8 0;0,1=19,2=2
P 0.57858996 0.52313002 0 P 1 8 0;0,1=19,2=2
P 5.80413002 4.33598002 0 P 1 8 0;0,1=19,2=2
P 5.81401998 0.54196998 0 P 1 8 0;0,1=19,2=2
P 5.84413002 4.33598002 0 P 1 8 0;0,1=19,2=2
P 5.85401998 0.54196998 0 P 1 8 0;0,1=19,2=2
P 5.88413002 4.33598002 0 P 1 8 0;0,1=19,2=2
P 5.89401998 0.54196998 0 P 1 8 0;0,1=19,2=2
P 5.92413002 4.33598002 0 P 1 8 0;0,1=19,2=2
P 5.93401998 0.54196998 0 P 1 8 0;0,1=19,2=2
P 5.96413002 4.33598002 0 P 1 8 0;0,1=19,2=2
P 5.97401998 0.54196998 0 P 1 8 0;0,1=19,2=2
P 6.00413002 4.33598002 0 P 1 8 0;0,1=19,2=2
P 6.01401998 0.54196998 0 P 1 8 0;0,1=19,2=2
P 0.60413002 4.33598002 0 P 1 8 0;0,1=19,2=2
P 6.04413002 4.33598002 0 P 1 8 0;0,1=19,2=2
P 6.05401998 0.54196998 0 P 1 8 0;0,1=19,2=2
P 6.08413002 4.33598002 0 P 1 8 0;0,1=19,2=2
P 6.09401998 0.54196998 0 P 1 8 0;0,1=19,2=2
P 6.12413002 4.33598002 0 P 1 8 0;0,1=19,2=2
P 6.13401998 0.54196998 0 P 1 8 0;0,1=19,2=2
P 0.61463002 0.54048002 0 P 1 8 0;0,1=19,2=2
P 6.16413002 4.33598002 0 P 1 8 0;0,1=19,2=2
P 6.17401998 0.54196998 0 P 1 8 0;0,1=19,2=2
P 6.19961004 2.21273996 0 P 1 8 0;0,1=19,2=2
P 6.19961004 2.30873996 0 P 1 8 0;0,1=19,2=2
P 6.20413002 4.33598002 0 P 1 8 0;0,1=19,2=2
P 6.21401998 0.54196998 0 P 1 8 0;0,1=19,2=2
P 6.24413002 4.33598002 0 P 1 8 0;0,1=19,2=2
P 6.25401998 0.54196998 0 P 1 8 0;0,1=19,2=2
P 6.28413002 4.33598002 0 P 1 8 0;0,1=19,2=2
P 6.29401998 0.54196998 0 P 1 8 0;0,1=19,2=2
P 6.32413002 4.33598002 0 P 1 8 0;0,1=19,2=2
P 6.36413002 4.33598002 0 P 1 8 0;0,1=19,2=2
P 6.40413002 4.33598002 0 P 1 8 0;0,1=19,2=2
P 0.64413002 4.33598002 0 P 1 8 0;0,1=19,2=2
P 6.44413002 4.33598002 0 P 1 8 0;0,1=19,2=2
P 6.48413002 4.33598002 0 P 1 8 0;0,1=19,2=2
P 6.49401998 0.54196998 0 P 1 8 0;0,1=19,2=2
P 6.52413002 4.33598002 0 P 1 8 0;0,1=19,2=2
P 6.53401998 0.54196998 0 P 1 8 0;0,1=19,2=2
P 0.6546 0.54196998 0 P 1 8 0;0,1=19,2=2
P 6.56038996 1.01205 0 P 1 8 0;0,1=19,2=2
P 6.56038996 1.05205 0 P 1 8 0;0,1=19,2=2
P 6.56038996 1.09205 0 P 1 8 0;0,1=19,2=2
P 6.56038996 1.13205 0 P 1 8 0;0,1=19,2=2
P 6.56038996 1.17205 0 P 1 8 0;0,1=19,2=2
P 6.56038996 1.21205 0 P 1 8 0;0,1=19,2=2
P 6.56038996 1.25205 0 P 1 8 0;0,1=19,2=2
P 6.56038996 1.29205 0 P 1 8 0;0,1=19,2=2
P 6.56038996 1.33205 0 P 1 8 0;0,1=19,2=2
P 6.56038996 1.37205 0 P 1 8 0;0,1=19,2=2
P 6.56038996 1.41205 0 P 1 8 0;0,1=19,2=2
P 6.56038996 1.45205 0 P 1 8 0;0,1=19,2=2
P 6.56038996 1.49205 0 P 1 8 0;0,1=19,2=2
P 6.56038996 1.53205 0 P 1 8 0;0,1=19,2=2
P 6.56038996 1.57205 0 P 1 8 0;0,1=19,2=2
P 6.56038996 1.61205 0 P 1 8 0;0,1=19,2=2
P 6.56038996 1.65205 0 P 1 8 0;0,1=19,2=2
P 6.56038996 1.69205 0 P 1 8 0;0,1=19,2=2
P 6.56038996 1.73205 0 P 1 8 0;0,1=19,2=2
P 6.56038996 1.77205 0 P 1 8 0;0,1=19,2=2
P 6.56038996 1.81205 0 P 1 8 0;0,1=19,2=2
P 6.56038996 2.35585 0 P 1 8 0;0,1=19,2=2
P 6.56038996 3.11908996 0 P 1 8 0;0,1=19,2=2
P 6.56038996 3.15908996 0 P 1 8 0;0,1=19,2=2
P 6.56038996 3.19908996 0 P 1 8 0;0,1=19,2=2
P 6.56038996 3.23908996 0 P 1 8 0;0,1=19,2=2
P 6.56038996 3.27908996 0 P 1 8 0;0,1=19,2=2
P 6.56038996 3.31908996 0 P 1 8 0;0,1=19,2=2
P 6.56038996 3.35908996 0 P 1 8 0;0,1=19,2=2
P 6.56038996 3.39908996 0 P 1 8 0;0,1=19,2=2
P 6.56038996 3.43908996 0 P 1 8 0;0,1=19,2=2
P 6.56038996 3.47908996 0 P 1 8 0;0,1=19,2=2
P 6.56038996 3.51908996 0 P 1 8 0;0,1=19,2=2
P 6.56038996 3.55908996 0 P 1 8 0;0,1=19,2=2
P 6.56038996 3.59908996 0 P 1 8 0;0,1=19,2=2
P 6.56038996 3.63908996 0 P 1 8 0;0,1=19,2=2
P 6.56038996 3.67908996 0 P 1 8 0;0,1=19,2=2
P 6.56038996 3.71908996 0 P 1 8 0;0,1=19,2=2
P 6.56038996 3.75908996 0 P 1 8 0;0,1=19,2=2
P 6.56038996 3.79908996 0 P 1 8 0;0,1=19,2=2
P 6.56038996 3.83908996 0 P 1 8 0;0,1=19,2=2
P 6.56038996 3.87908996 0 P 1 8 0;0,1=19,2=2
P 6.56038996 3.91908996 0 P 1 8 0;0,1=19,2=2
P 6.56038996 3.95908996 0 P 1 8 0;0,1=19,2=2
P 6.56038996 3.99908996 0 P 1 8 0;0,1=19,2=2
P 6.56038996 4.03908996 0 P 1 8 0;0,1=19,2=2
P 6.56038996 4.07908996 0 P 1 8 0;0,1=19,2=2
P 6.56038996 4.11908996 0 P 1 8 0;0,1=19,2=2
P 6.56038996 4.15908996 0 P 1 8 0;0,1=19,2=2
P 6.56038996 4.19908996 0 P 1 8 0;0,1=19,2=2
P 6.56038996 4.23908996 0 P 1 8 0;0,1=19,2=2
P 6.56038996 4.27908996 0 P 1 8 0;0,1=19,2=2
P 6.56038996 4.31908996 0 P 1 8 0;0,1=19,2=2
P 6.56038996 0.57205 0 P 1 8 0;0,1=19,2=2
P 6.56038996 0.61205 0 P 1 8 0;0,1=19,2=2
P 6.56038996 0.65205 0 P 1 8 0;0,1=19,2=2
P 6.56038996 0.69205 0 P 1 8 0;0,1=19,2=2
P 6.56038996 0.73205 0 P 1 8 0;0,1=19,2=2
P 6.56038996 0.77205 0 P 1 8 0;0,1=19,2=2
P 6.56038996 0.81205 0 P 1 8 0;0,1=19,2=2
P 6.56038996 0.85205 0 P 1 8 0;0,1=19,2=2
P 6.56038996 0.89205 0 P 1 8 0;0,1=19,2=2
P 6.56038996 0.93205 0 P 1 8 0;0,1=19,2=2
P 6.56038996 0.97205 0 P 1 8 0;0,1=19,2=2
P 0.67 2.831 0 P 1 8 0;0,1=19,2=2
P 0.671 3.575 0 P 1 8 0;0,1=19,2=2
P 0.68413002 4.33598002 0 P 1 8 0;0,1=19,2=2
P 0.6946 0.54196998 0 P 1 8 0;0,1=19,2=2
P 0.72413002 4.33598002 0 P 1 8 0;0,1=19,2=2
P 0.7346 0.54196998 0 P 1 8 0;0,1=19,2=2
P 0.76413002 4.33598002 0 P 1 8 0;0,1=19,2=2
P 0.767 3.575 0 P 1 8 0;0,1=19,2=2
P 0.7746 0.54196998 0 P 1 8 0;0,1=19,2=2
P 0.79248002 2.661 0 P 1 8 0;0,1=19,2=2
P 0.80413002 4.33598002 0 P 1 8 0;0,1=19,2=2
P 0.8146 0.54196998 0 P 1 8 0;0,1=19,2=2
P 0.08413002 4.33598002 0 P 1 8 0;0,1=19,2=2
P 0.84413002 4.33598002 0 P 1 8 0;0,1=19,2=2
P 0.8546 0.54196998 0 P 1 8 0;0,1=19,2=2
P 0.856 2.637 0 P 1 8 0;0,1=19,2=2
P 0.868 2.3 0 P 1 8 0;0,1=19,2=2
P 0.08878002 0.21716998 0 P 1 8 0;0,1=19,2=2
P 0.88413002 4.33598002 0 P 1 8 0;0,1=19,2=2
P 0.8946 0.54196998 0 P 1 8 0;0,1=19,2=2
P 0.92413002 4.33598002 0 P 1 8 0;0,1=19,2=2
P 0.9346 0.54196998 0 P 1 8 0;0,1=19,2=2
P 0.96413002 4.33598002 0 P 1 8 0;0,1=19,2=2
P 0.9746 0.54196998 0 P 1 8 0;0,1=19,2=2
P 4.14 4.19 0 P 1 8 0;0,1=19,2=2
P 0.98 4.2 0 P 1 8 0;0,1=19,2=2
P 4.22336998 4.24 0 P 1 8 0;0,1=19,2=2
P 0.9 4.205 0 P 1 8 0;0,1=19,2=2
P 4.168 4.24 0 P 1 8 0;0,1=19,2=2
P 0.855 4.205 0 P 1 8 0;0,1=19,2=2
P 3.93 4.185 0 P 1 8 0;0,1=19,2=2
P 4.03 4.185 0 P 1 8 0;0,1=19,2=2
P 3.98 4.185 0 P 1 8 0;0,1=19,2=2
P 3.985 4 0 P 1 8 0;0,1=19,2=2
P 3.885 4 0 P 1 8 0;0,1=19,2=2
P 3.935 4 0 P 1 8 0;0,1=19,2=2
P 2.54526998 0.339 0 P 1 8 0;0,1=19,2=2
P 5.52 3.67596998 0 P 1 8 0;0,1=19,2=2
P 5.52 3.71141004 0 P 1 8 0;0,1=19,2=2
P 5.52 3.74683996 0 P 1 8 0;0,1=19,2=2
P 5.52 3.78226998 0 P 1 8 0;0,1=19,2=2
P 5.552 3.67596998 0 P 1 8 0;0,1=19,2=2
P 5.552 3.71141004 0 P 1 8 0;0,1=19,2=2
P 5.552 3.74683996 0 P 1 8 0;0,1=19,2=2
P 5.552 3.78226998 0 P 1 8 0;0,1=19,2=2
P 1.86 0.33 0 P 1 8 0;0,1=19,2=2
P 1.87598002 0.289 0 P 1 8 0;0,1=19,2=2
P 1.87598002 0.369 0 P 1 8 0;0,1=19,2=2
P 1.895 0.33 0 P 1 8 0;0,1=19,2=2
P 0.686 2.74 0 P 1 8 0;0,1=19,2=2
P 0.736 2.525 0 P 1 8 0;1=19,2=2
P 3.804 0.816 0 P 1 8 0;0,1=19,2=2
P 2.128 2.895 0 P 1 8 0;0,1=19,2=2
P 2.245 3.02 0 P 1 8 0;0,1=19,2=2
P 3.106 3.35 0 P 1 8 0;1=19,2=2
P 3.222 3.205 0 P 1 8 0;0,1=19,2=2
P 3.222 3.385 0 P 1 8 0;0,1=19,2=2
P 3.548 2.856 0 P 1 8 0;0,1=19,2=2
P 3.55 3.28 0 P 1 8 0;1=19,2=2
P 4.32 3.965 0 P 1 8 0;0,1=19,2=2
P 4.43 3.865 0 P 1 8 0;0,1=19,2=2
P 0.883 1.639 0 P 1 8 0;0,1=19,2=2
P 2.105 0.305 0 P 1 8 0;0,1=19,2=2
P 6.258 2.15873996 0 P 1 8 0;0,1=19,2=2
P 3.9113 1.3513 0 P 1 8 0;0,1=20,2=2
P 3.95066998 1.3513 0 P 1 8 0;0,1=20,2=2
P 3.95066998 2.05996004 0 P 1 8 0;0,1=20,2=2
P 3.99 1.31188002 0 P 1 8 0;0,1=20,2=2
P 3.99 1.35125 0 P 1 8 0;0,1=20,2=2
P 3.99005 1.94185 0 P 1 8 0;0,1=20,2=2
P 4.02941998 1.39066998 0 P 1 8 0;0,1=20,2=2
P 4.02941998 1.86311004 0 P 1 8 0;0,1=20,2=2
P 4.02941998 1.94185 0 P 1 8 0;0,1=20,2=2
P 4.02941998 1.98121998 0 P 1 8 0;0,1=20,2=2
P 4.02941998 2.02058996 0 P 1 8 0;0,1=20,2=2
P 4.06873996 1.31188002 0 P 1 8 0;0,1=20,2=2
P 4.06878996 1.39066998 0 P 1 8 0;0,1=20,2=2
P 4.06878996 1.43005 0 P 1 8 0;0,1=20,2=2
P 4.06878996 1.90248002 0 P 1 8 0;0,1=20,2=2
P 4.06878996 2.05996004 0 P 1 8 0;0,1=20,2=2
P 4.06878996 2.1387 0 P 1 8 0;0,1=20,2=2
P 4.10811004 1.31188002 0 P 1 8 0;0,1=20,2=2
P 4.10816004 1.3513 0 P 1 8 0;0,1=20,2=2
P 4.10816004 1.39066998 0 P 1 8 0;0,1=20,2=2
P 4.10816004 1.43005 0 P 1 8 0;0,1=20,2=2
P 4.10816004 1.94185 0 P 1 8 0;0,1=20,2=2
P 4.10816004 1.98121998 0 P 1 8 0;0,1=20,2=2
P 4.10816004 2.02058996 0 P 1 8 0;0,1=20,2=2
P 4.14753002 1.3513 0 P 1 8 0;0,1=20,2=2
P 4.14753002 1.39066998 0 P 1 8 0;0,1=20,2=2
P 4.14753002 1.43005 0 P 1 8 0;0,1=20,2=2
P 4.14753002 1.46941998 0 P 1 8 0;0,1=20,2=2
P 4.14753002 1.98121998 0 P 1 8 0;0,1=20,2=2
P 4.14753002 2.02058996 0 P 1 8 0;0,1=20,2=2
P 4.1869 1.31193002 0 P 1 8 0;0,1=20,2=2
P 4.1869 1.3513 0 P 1 8 0;0,1=20,2=2
P 4.1869 1.43005 0 P 1 8 0;0,1=20,2=2
P 4.1869 1.46941998 0 P 1 8 0;0,1=20,2=2
P 4.1869 1.94185 0 P 1 8 0;0,1=20,2=2
P 4.1869 2.1387 0 P 1 8 0;0,1=20,2=2
P 4.22626998 1.31193002 0 P 1 8 0;0,1=20,2=2
P 4.22626998 1.3513 0 P 1 8 0;0,1=20,2=2
P 4.22626998 1.39066998 0 P 1 8 0;0,1=20,2=2
P 4.22626998 1.43005 0 P 1 8 0;0,1=20,2=2
P 4.22626998 1.98121998 0 P 1 8 0;0,1=20,2=2
P 4.22626998 2.02058996 0 P 1 8 0;0,1=20,2=2
P 4.22626998 2.05996004 0 P 1 8 0;0,1=20,2=2
P 4.26563996 1.31193002 0 P 1 8 0;0,1=20,2=2
P 4.26563996 1.39066998 0 P 1 8 0;0,1=20,2=2
P 4.26563996 1.50878996 0 P 1 8 0;0,1=20,2=2
P 4.26563996 1.94185 0 P 1 8 0;0,1=20,2=2
P 4.26563996 2.02058996 0 P 1 8 0;0,1=20,2=2
P 4.26563996 2.05996004 0 P 1 8 0;0,1=20,2=2
P 4.26563996 2.09933002 0 P 1 8 0;0,1=20,2=2
P 4.34436998 1.31193002 0 P 1 8 0;0,1=20,2=2
P 4.34436998 1.3513 0 P 1 8 0;0,1=20,2=2
P 4.34436998 1.39066998 0 P 1 8 0;0,1=20,2=2
P 4.34436998 1.98121998 0 P 1 8 0;0,1=20,2=2
P 4.34436998 2.09933002 0 P 1 8 0;0,1=20,2=2
P 4.38373996 1.82373996 0 P 1 8 0;0,1=20,2=2
P 4.38373996 1.86311004 0 P 1 8 0;0,1=20,2=2
P 4.42311004 1.98121998 0 P 1 8 0;0,1=20,2=2
P 4.42311004 2.05996004 0 P 1 8 0;0,1=20,2=2
P 4.45938996 1.35438996 0 P 1 8 0;0,1=20,2=2
P 4.46248002 1.39066998 0 P 1 8 0;0,1=20,2=2
P 4.46248002 1.50878996 0 P 1 8 0;0,1=20,2=2
P 4.46248002 1.94185 0 P 1 8 0;0,1=20,2=2
P 4.46248002 1.98121998 0 P 1 8 0;0,1=20,2=2
P 4.46248002 2.02058996 0 P 1 8 0;0,1=20,2=2
P 4.46248002 2.05996004 0 P 1 8 0;0,1=20,2=2
P 4.49876004 1.31501998 0 P 1 8 0;0,1=20,2=2
P 4.50185 1.39066998 0 P 1 8 0;0,1=20,2=2
P 4.50185 1.46941998 0 P 1 8 0;0,1=20,2=2
P 4.50185 1.86311004 0 P 1 8 0;0,1=20,2=2
P 4.50185 1.90248002 0 P 1 8 0;0,1=20,2=2
P 4.50185 2.02058996 0 P 1 8 0;0,1=20,2=2
P 4.50185 2.09933002 0 P 1 8 0;0,1=20,2=2
P 4.50185 2.1387 0 P 1 8 0;0,1=20,2=2
P 4.54121998 1.31193002 0 P 1 8 0;0,1=20,2=2
P 4.54121998 1.3513 0 P 1 8 0;0,1=20,2=2
P 4.54121998 1.39066998 0 P 1 8 0;0,1=20,2=2
P 4.54121998 1.46941998 0 P 1 8 0;0,1=20,2=2
P 4.54121998 1.50878996 0 P 1 8 0;0,1=20,2=2
P 4.54121998 1.54816004 0 P 1 8 0;0,1=20,2=2
P 4.54121998 1.90248002 0 P 1 8 0;0,1=20,2=2
P 4.54121998 1.98121998 0 P 1 8 0;0,1=20,2=2
P 4.54121998 2.02058996 0 P 1 8 0;0,1=20,2=2
P 4.54121998 2.09933002 0 P 1 8 0;0,1=20,2=2
P 4.54121998 2.1387 0 P 1 8 0;0,1=20,2=2
P 4.57843996 1.35345 0 P 1 8 0;0,1=20,2=2
P 4.58058996 1.39066998 0 P 1 8 0;0,1=20,2=2
P 4.58058996 1.43005 0 P 1 8 0;0,1=20,2=2
P 4.58058996 1.46941998 0 P 1 8 0;0,1=20,2=2
P 4.58058996 1.54816004 0 P 1 8 0;0,1=20,2=2
P 4.58058996 1.86311004 0 P 1 8 0;0,1=20,2=2
P 4.58058996 1.98121998 0 P 1 8 0;0,1=20,2=2
P 4.58058996 2.02058996 0 P 1 8 0;0,1=20,2=2
P 4.58058996 2.05996004 0 P 1 8 0;0,1=20,2=2
P 4.58058996 2.09933002 0 P 1 8 0;0,1=20,2=2
P 4.58058996 2.17806998 0 P 1 8 0;0,1=20,2=2
P 4.61996004 1.3513 0 P 1 8 0;0,1=20,2=2
P 4.61996004 1.43005 0 P 1 8 0;0,1=20,2=2
P 4.61996004 1.46941998 0 P 1 8 0;0,1=20,2=2
P 4.61996004 1.50878996 0 P 1 8 0;0,1=20,2=2
P 4.61996004 1.54816004 0 P 1 8 0;0,1=20,2=2
P 4.61996004 1.90248002 0 P 1 8 0;0,1=20,2=2
P 4.61996004 1.94185 0 P 1 8 0;0,1=20,2=2
P 4.61996004 1.98121998 0 P 1 8 0;0,1=20,2=2
P 4.61996004 2.1387 0 P 1 8 0;0,1=20,2=2
P 4.61996004 2.17806998 0 P 1 8 0;0,1=20,2=2
P 4.65933002 1.3513 0 P 1 8 0;0,1=20,2=2
P 4.65933002 1.39066998 0 P 1 8 0;0,1=20,2=2
P 4.65933002 1.43005 0 P 1 8 0;0,1=20,2=2
P 4.65933002 1.50878996 0 P 1 8 0;0,1=20,2=2
P 4.65933002 1.82373996 0 P 1 8 0;0,1=20,2=2
P 4.65933002 1.98121998 0 P 1 8 0;0,1=20,2=2
P 4.65933002 2.05996004 0 P 1 8 0;0,1=20,2=2
P 4.6987 1.31193002 0 P 1 8 0;0,1=20,2=2
P 4.6987 1.39066998 0 P 1 8 0;0,1=20,2=2
P 4.6987 1.43005 0 P 1 8 0;0,1=20,2=2
P 4.6987 1.50878996 0 P 1 8 0;0,1=20,2=2
P 4.6987 1.66626998 0 P 1 8 0;0,1=20,2=2
P 4.6987 1.70563996 0 P 1 8 0;0,1=20,2=2
P 4.6987 1.86311004 0 P 1 8 0;0,1=20,2=2
P 4.6987 1.94185 0 P 1 8 0;0,1=20,2=2
P 4.6987 2.05996004 0 P 1 8 0;0,1=20,2=2
P 4.73806998 1.31193002 0 P 1 8 0;0,1=20,2=2
P 4.73806998 1.70563996 0 P 1 8 0;0,1=20,2=2
P 4.73806998 1.78436998 0 P 1 8 0;0,1=20,2=2
P 4.73806998 1.90248002 0 P 1 8 0;0,1=20,2=2
P 4.73806998 2.09933002 0 P 1 8 0;0,1=20,2=2
P 4.73806998 2.1387 0 P 1 8 0;0,1=20,2=2
P 4.73806998 2.17806998 0 P 1 8 0;0,1=20,2=2
P 4.6987 2.1387 0 P 1 8 0;0,1=20,2=2
P 4.5806 1.70563996 0 P 1 8 0;0,1=20,2=2
P 4.26563996 1.78436998 0 P 1 8 0;0,1=20,2=2
P 4.50185 2.05996004 0 P 1 8 0;0,1=20,2=2
P 4.38373996 2.17806998 0 P 1 8 0;0,1=20,2=2
P 4.34436998 2.17806998 0 P 1 8 0;0,1=20,2=2
P 4.34436998 2.02058996 0 P 1 8 0;0,1=20,2=2
P 4.58058996 1.82373996 0 P 1 8 0;0,1=20,2=2
P 4.1869 2.09933002 0 P 1 8 0;0,1=20,2=2
P 4.1869 2.05996004 0 P 1 8 0;0,1=20,2=2
P 4.14753002 2.09933002 0 P 1 8 0;0,1=20,2=2
P 4.10816004 2.09933002 0 P 1 8 0;0,1=20,2=2
P 4.34436998 2.1387 0 P 1 8 0;0,1=20,2=2
P 4.6987 1.90248002 0 P 1 8 0;0,1=20,2=2
P 4.61996004 2.09933002 0 P 1 8 0;0,1=20,2=2
P 4.61996004 2.05996004 0 P 1 8 0;0,1=20,2=2
P 4.26563996 1.90248002 0 P 1 8 0;0,1=20,2=2
P 3.9113 2.09933002 0 P 1 8 0;0,1=20,2=2
P 4.14753002 1.82373996 0 P 1 8 0;0,1=20,2=2
P 4.10816004 1.82373996 0 P 1 8 0;0,1=20,2=2
P 4.73806998 1.82373996 0 P 1 8 0;0,1=20,2=2
P 4.14753002 2.05996004 0 P 1 8 0;0,1=20,2=2
P 4.06878996 1.82373996 0 P 1 8 0;0,1=20,2=2
P 4.06878996 1.86311004 0 P 1 8 0;0,1=20,2=2
P 4.06878996 1.94185 0 P 1 8 0;0,1=20,2=2
P 3.95066998 1.86311004 0 P 1 8 0;0,1=20,2=2
P 3.95066998 1.90248002 0 P 1 8 0;0,1=20,2=2
P 4.02941998 1.82373996 0 P 1 8 0;0,1=20,2=2
P 3.99005 1.98121998 0 P 1 8 0;0,1=20,2=2
P 3.95066998 1.98121998 0 P 1 8 0;0,1=20,2=2
P 3.95066998 2.02058996 0 P 1 8 0;0,1=20,2=2
P 4.02941998 2.05996004 0 P 1 8 0;0,1=20,2=2
P 3.99005 2.05996004 0 P 1 8 0;0,1=20,2=2
P 4.06878996 2.02058996 0 P 1 8 0;0,1=20,2=2
P 4.38373996 1.78436998 0 P 1 8 0;0,1=20,2=2
P 4.58058996 1.58753002 0 P 1 8 0;0,1=20,2=2
P 4.58058996 1.6269 0 P 1 8 0;0,1=20,2=2
P 4.65933002 1.54816004 0 P 1 8 0;0,1=20,2=2
P 4.65933002 1.58753002 0 P 1 8 0;0,1=20,2=2
P 4.26563996 2.17806998 0 P 1 8 0;0,1=20,2=2
P 4.54123002 1.70563996 0 P 1 8 0;0,1=20,2=2
P 4.73806998 1.66626998 0 P 1 8 0;0,1=20,2=2
P 4.26563996 1.82373996 0 P 1 8 0;0,1=20,2=2
P 4.34436998 1.82373996 0 P 1 8 0;0,1=20,2=2
P 3.95066998 1.70563996 0 P 1 8 0;0,1=21,2=2
P 0.46 0.82 0 P 1 8 0;0,1=22,2=2
P 0.51765 0.966 0 P 1 8 0;0,1=22,2=2
P 0.795 2.345 0 P 1 8 0;0,1=22,2=2
P 0.825 2.305 0 P 1 8 0;0,1=22,2=2
P 2.435 0.4865 0 P 1 8 0;0,1=22,2=2
P 3.415 3.335 0 P 1 8 0;0,1=22,2=2
P 3.5825 3.4005 0 P 1 8 0;0,1=22,2=2
P 4.44 4.115 0 P 1 8 0;0,1=22,2=2
P 4.44 4.065 0 P 1 8 0;0,1=22,2=2
P 3.61123996 3.49876004 0 P 1 8 0;0,1=22,2=2
P 4.70461998 3.69461998 0 P 1 8 0;0,1=22,2=2
P 4.935 3.59 0 P 1 8 0;0,1=22,2=2
P 5.03 3.546 0 P 1 8 0;0,1=22,2=2
P 0.796 2.489 0 P 1 8 0;0,1=22,2=2
P 0.846 2.489 0 P 1 8 0;0,1=22,2=2
P 3.36525 3.305 0 P 1 8 0;0,1=22,2=2
P 1.128 0.666 0 P 1 8 0;0,1=22,2=2
P 3.18 2.685 0 P 1 8 0;1=22,2=2
P 3.326 2.466 0 P 1 8 0;0,1=22,2=2
P 3.3435 2.82 0 P 1 8 0;0,1=22,2=2
P 3.44 2.95 0 P 1 8 0;0,1=22,2=2
P 3.275 2.32 0 P 1 8 0;0,1=22,2=2
P 0.758 2.743 0 P 1 8 0;0,1=22,2=2
P 3.365 2.95 0 P 1 8 0;0,1=22,2=2
P 0.858 2.87451998 0 P 1 8 0;0,1=22,2=2
P 3.415 3.385 0 P 1 8 0;0,1=22,2=2
P 3.83 3.285 0 P 1 8 0;0,1=22,2=2
P 3.415 3.285 0 P 1 8 0;0,1=22,2=2
P 3.83 3.335 0 P 1 8 0;0,1=22,2=2
P 4.319 3.922 0 P 1 8 0;0,1=22,2=2
P 4.31168996 4.01168996 0 P 1 8 0;0,1=22,2=2
P 2.527 0.44 0 P 1 8 0;0,1=22,2=2
P 4.415 2.975 0 P 1 8 0;0,1=22,2=2
P 3.36525 3.205 0 P 1 8 0;0,1=22,2=2
P 3.36525 3.255 0 P 1 8 0;0,1=22,2=2
P 2.977 3.351 0 P 1 8 0;0,1=22,2=2
P 0.825 2.732 0 P 1 8 0;0,1=22,2=2
P 0.72 2.714 0 P 1 8 0;0,1=22,2=2
P 0.77963996 2.601 0 P 1 8 0;0,1=22,2=2
P 0.896 2.489 0 P 1 8 0;0,1=22,2=2
P 3.285 2.38645 0 P 1 8 0;0,1=22,2=2
P 3.24 2.36 0 P 1 8 0;0,1=22,2=2
P 3.243 2.547 0 P 1 8 0;0,1=22,2=2
P 3.278 2.468 0 P 1 8 0;0,1=22,2=2
P 3.429 2.468 0 P 1 8 0;0,1=22,2=2
P 5.68 3.567 0 P 1 8 0;0,1=22,2=2
P 5.50643002 4.009 0 P 1 8 0;0,1=22,2=2
P 5.55568996 3.88051004 0 P 1 8 0;0,1=22,2=2
P 4.2136 3.5997 0 P 1 8 0;0,1=22,2=2
P 3.916 3.048 0 P 1 8 0;0,1=22,2=2
P 3.793 3.05 0 P 1 8 0;0,1=22,2=2
P 0.871 2.713 0 P 1 8 0;0,1=22,2=2
P 4.705 3.95 0 P 1 8 0;0,1=22,2=2
P 2.95835 0.449 0 P 1 8 0;0,1=23,2=2
P 2.95835 0.481 0 P 1 8 0;0,1=23,2=2
P 2.64338996 0.353 0 P 1 8 0;0,1=23,2=2
P 2.64338996 0.385 0 P 1 8 0;0,1=23,2=2
P 2.80086998 0.353 0 P 1 8 0;0,1=23,2=2
P 2.80086998 0.385 0 P 1 8 0;0,1=23,2=2
P 2.95835 0.353 0 P 1 8 0;0,1=23,2=2
P 2.95835 0.385 0 P 1 8 0;0,1=23,2=2
P 3.65101004 1.91558996 0 P 1 8 0;0,1=23,2=2
P 3.65101004 1.88358996 0 P 1 8 0;0,1=23,2=2
P 3.2591 1.90298996 0 P 1 8 0;0,1=23,2=2
P 3.45301004 1.93098996 0 P 1 8 0;0,1=23,2=2
P 3.2271 1.90298996 0 P 1 8 0;0,1=23,2=2
P 3.45301004 1.89898996 0 P 1 8 0;0,1=23,2=2
P 4.06878996 2.09933002 0 P 1 8 0;0,1=24,2=2
P 4.75 1.63 0 P 1 8 0;0,1=24,2=2
P 3.87193002 2.09933002 0 P 1 8 0;0,1=24,2=2
P 4.10816004 1.90248002 0 P 1 8 0;0,1=24,2=2
P 4.65933002 2.02058996 0 P 1 8 0;0,1=24,2=2
P 4.54121998 2.17806998 0 P 1 8 0;0,1=24,2=2
P 1.8317 0.5639 0 P 1 8 0;0,1=25,2=2
P 4.9097 1.335 0 P 1 8 0;0,1=25,2=2
P 5.91 2.615 0 P 1 8 0;0,1=25,2=2
P 1.485 0.625 0 P 1 8 0;0,1=25,2=2
P 1.395 0.625 0 P 1 8 0;0,1=25,2=2
P 1.26 0.67 0 P 1 8 0;0,1=25,2=2
P 1.26 0.62 0 P 1 8 0;0,1=25,2=2
P 3.83 3.466 0 P 1 8 0;0,1=25,2=2
P 5.905 3.015 0 P 1 8 0;0,1=25,2=2
P 4.9097 1.385 0 P 1 8 0;0,1=25,2=2
P 1.96496998 0.76501998 0 P 1 8 0;0,1=25,2=2
P 5.89953002 2.366 0 P 1 8 0;0,1=25,2=2
P 5.4525 2.563 0 P 1 8 0;0,1=25,2=2
P 5.375 2.96606998 0 P 1 8 0;0,1=25,2=2
P 5.39976998 2.75123996 0 P 1 8 0;0,1=25,2=2
P 6.33 2.67 0 P 1 8 0;0,1=25,2=2
P 5.814 2.621 0 P 1 8 0;0,1=25,2=2
P 5.815 3.021 0 P 1 8 0;0,1=25,2=2
P 5.814 2.721 0 P 1 8 0;0,1=25,2=2
P 5.814 2.821 0 P 1 8 0;0,1=25,2=2
P 4.885 3.59 0 P 1 8 0;0,1=25,2=2
P 4.15463002 3.83 0 P 1 8 0;0,1=25,2=2
P 4.05463002 3.83 0 P 1 8 0;0,1=25,2=2
P 4.10463002 3.83 0 P 1 8 0;0,1=25,2=2
P 1.8039 0.7072 0 P 1 8 0;0,1=25,2=2
P 2.0788 0.7874 0 P 1 8 0;0,1=25,2=2
P 2.03 0.75 0 P 1 8 0;0,1=25,2=2
P 2.1481 0.7881 0 P 1 8 0;0,1=25,2=2
P 1.8091 0.6339 0 P 1 8 0;0,1=25,2=2
P 1.4207 0.779 0 P 1 8 0;0,1=25,2=2
P 1.42 0.69535 0 P 1 8 0;0,1=25,2=2
P 3.4593 2.17 0 P 1 8 0;0,1=25,2=2
P 2.22 3.3 0 P 1 8 0;0,1=25,2=2
P 3.49 0.825 0 P 1 8 0;0,1=25,2=2
P 0.761 1.544 0 P 1 8 0;0,1=25,2=2
P 0.7595 1.642 0 P 1 8 0;0,1=25,2=2
P 6.01901998 2.001 0 P 1 8 0;0,1=25,2=2
P 6.06901998 2.004 0 P 1 8 0;0,1=25,2=2
P 5.91901998 2.003 0 P 1 8 0;0,1=25,2=2
P 5.94153002 2.205 0 P 1 8 0;0,1=25,2=2
P 3.795 0.725 0 P 1 8 0;0,1=25,2=2
P 3.964 1.005 0 P 1 8 0;0,1=25,2=2
P 5.97 1.999 0 P 1 8 0;0,1=25,2=2
P 0.705 4.19 0 P 1 8 0;0,1=25,2=2
P 0.7558 4.19003996 0 P 1 8 0;0,1=25,2=2
P 3.985 3.91 0 P 1 8 0;0,1=25,2=2
P 3.885 3.91 0 P 1 8 0;0,1=25,2=2
P 3.935 3.91 0 P 1 8 0;0,1=25,2=2
P 1.1288 0.7302 0 P 1 8 0;0,1=25,2=2
P 5.40318002 2.70436004 0 P 1 8 0;0,1=25,2=2
P 5.323 4.257 0 P 1 8 0;0,1=25,2=2
P 1.8062 0.7789 0 P 1 8 0;0,1=25,2=2
P 3.073 0.613 0 P 1 8 0;0,1=25,2=2
P 1.95 0.5455 0 P 1 8 0;0,1=25,2=2
P 5.7287 0.6757 0 P 1 8 0;0,1=25,2=2
P 5.686 0.76 0 P 1 8 0;0,1=25,2=2
P 5.725 0.60301004 0 P 1 8 0;0,1=25,2=2
P 5.495 0.694 0 P 1 8 0;0,1=25,2=2
P 5.53121998 2.27978996 0 P 1 8 0;0,1=25,2=2
P 3.584 1.827 0 P 1 8 0;0,1=25,2=2
P 2.185 3.017 0 P 1 8 0;0,1=25,2=2
P 2.135 3.017 0 P 1 8 0;0,1=25,2=2
P 2.085 3.017 0 P 1 8 0;0,1=25,2=2
P 3.817 0.924 0 P 1 8 0;0,1=25,2=2
P 1.606 4.174 0 P 1 8 0;0,1=25,2=2
P 1.633 3.829 0 P 1 8 0;0,1=25,2=2
P 1.485 3.76 0 P 1 8 0;0,1=25,2=2
P 5.762 3.425 0 P 1 8 0;0,1=25,2=2
P 5.771 2.279 0 P 1 8 0;0,1=25,2=2
P 5.595 2.28 0 P 1 8 0;0,1=25,2=2
P 5.667 2.275 0 P 1 8 0;0,1=25,2=2
P 5.48158002 2.28033002 0 P 1 8 0;0,1=25,2=2
P 5.005 2.711 0 P 1 8 0;0,1=25,2=2
P 5.224 2.707 0 P 1 8 0;0,1=25,2=2
P 1.385 3.875 0 P 1 8 0;0,1=25,2=2
P 5.226 2.762 0 P 1 8 0;0,1=25,2=2
P 5 2.78798996 0 P 1 8 0;0,1=25,2=2
P 1.522 4.163 0 P 1 8 0;0,1=25,2=2
P 1.521 3.993 0 P 1 8 0;0,1=25,2=2
P 1.5153 4.063 0 P 1 8 0;0,1=25,2=2
P 1.511 3.863 0 P 1 8 0;0,1=25,2=2
P 1.5315 3.9459 0 P 1 8 0;0,1=25,2=2
P 6.335 2.05906004 0 P 1 8 0;0,1=25,2=2
P 3.375 1.162 0 P 1 8 0;0,1=19,2=2
P 3.375 1.194 0 P 1 8 0;0,1=19,2=2
P 3.41798996 1.085 0 P 1 8 0;0,1=19,2=2
P 3.44998996 1.085 0 P 1 8 0;0,1=19,2=2
P 3.51463996 1.04706998 0 P 1 8 0;0,1=19,2=2
P 3.54663996 1.04706998 0 P 1 8 0;0,1=19,2=2
P 3.657 0.92 0 P 1 8 0;0,1=23,2=2
P 6.19961004 2.24473996 0 P 1 8 0;0,1=23,2=2
P 3.625 0.92 0 P 1 8 0;0,1=23,2=2
P 6.19961004 2.27673996 0 P 1 8 0;0,1=23,2=2
P 1.105 3.825 0 P 1 8 0;0,1=23,2=2
P 0.735 3.575 0 P 1 8 0;0,1=23,2=2
P 1.073 3.825 0 P 1 8 0;0,1=23,2=2
P 0.703 3.575 0 P 1 8 0;0,1=23,2=2
P 2.40508002 0.699 0 P 1 8 0;0,1=19,2=2
P 2.40508002 0.731 0 P 1 8 0;0,1=19,2=2
P 2.50221998 0.763 0 P 1 8 0;0,1=23,2=2
P 2.47021998 0.763 0 P 1 8 0;0,1=23,2=2
P 2.69906998 0.763 0 P 1 8 0;0,1=23,2=2
P 2.66706998 0.763 0 P 1 8 0;0,1=23,2=2
P 2.85055 0.763 0 P 1 8 0;0,1=23,2=2
P 2.81855 0.763 0 P 1 8 0;0,1=23,2=2
P 3.14763002 0.85236998 0 P 1 8 0;0,1=23,2=2
P 3.125 0.875 0 P 1 8 0;0,1=23,2=2
P 3.8865 2.9265 1 P 3 8 0;0,1=17,2=2
P 5.0895 2.7325 1 P 3 8 0;0,1=17,2=2
P 4.3305 2.914 1 P 3 8 0;0,1=17,2=2
P 4.3815 2.838 1 P 3 8 0;0,1=17,2=2
P 3.95066998 2.09933002 0 P 1 8 0;0,1=20,2=2
P 4.1869 1.50878996 0 P 1 8 0;0,1=20,2=2
P 4.22626998 1.50878996 0 P 1 8 0;0,1=20,2=2
P 4.26563996 1.46941998 0 P 1 8 0;0,1=20,2=2
P 4.38373996 1.39066998 0 P 1 8 0;0,1=20,2=2
P 4.38373996 1.43005 0 P 1 8 0;0,1=20,2=2
P 4.50185 1.50878996 0 P 1 8 0;0,1=20,2=2
P 4.6987 2.09933002 0 P 1 8 0;0,1=20,2=2
P 4.61996004 1.66626998 0 P 1 8 0;0,1=20,2=2
P 4.65933002 1.70563996 0 P 1 8 0;0,1=20,2=2
P 4.61996004 1.70563996 0 P 1 8 0;0,1=20,2=2
P 4.65933002 1.78436998 0 P 1 8 0;0,1=20,2=2
P 4.61996004 1.78436998 0 P 1 8 0;0,1=20,2=2
P 4.54121998 1.58753002 0 P 1 8 0;0,1=20,2=2
P 4.38373996 2.09933002 0 P 1 8 0;0,1=20,2=2
P 4.38373996 2.05996004 0 P 1 8 0;0,1=20,2=2
P 4.54121998 1.78436998 0 P 1 8 0;0,1=20,2=2
P 4.10816004 1.70563996 0 P 1 8 0;0,1=20,2=2
P 4.61996004 1.86311004 0 P 1 8 0;0,1=20,2=2
P 4.65933002 1.86311004 0 P 1 8 0;0,1=20,2=2
P 4.34436998 1.90248002 0 P 1 8 0;0,1=20,2=2
P 4.54121998 1.66626998 0 P 1 8 0;0,1=20,2=2
P 4.54121998 1.6269 0 P 1 8 0;0,1=20,2=2
P 3.9113 1.46941998 0 P 1 8 0;0,1=20,2=2
P 3.9113 1.54816004 0 P 1 8 0;0,1=20,2=2
P 3.9113 1.6269 0 P 1 8 0;0,1=20,2=2
P 3.9113 1.70563996 0 P 1 8 0;0,1=20,2=2
P 3.95066998 1.43005 0 P 1 8 0;0,1=20,2=2
P 3.95066998 1.58753002 0 P 1 8 0;0,1=20,2=2
P 4.06878996 1.58753002 0 P 1 8 0;0,1=20,2=2
P 4.1869 1.98121998 0 P 1 8 0;0,1=20,2=2
P 4.65933002 1.94185 0 P 1 8 0;0,1=20,2=2
P 4.22626998 1.94185 0 P 1 8 0;0,1=20,2=2
P 4.58058996 1.90248002 0 P 1 8 0;0,1=20,2=2
P 4.54121998 1.94185 0 P 1 8 0;0,1=20,2=2
P 4.6987 1.82373996 0 P 1 8 0;0,1=20,2=2
P 4.38373996 1.98121998 0 P 1 8 0;0,1=20,2=2
P 4.50185 1.94185 0 P 1 8 0;0,1=20,2=2
P 4.58058996 1.78436998 0 P 1 8 0;0,1=20,2=2
P 4.46248002 1.82373996 0 P 1 8 0;0,1=20,2=2
P 4.50185 1.82373996 0 P 1 8 0;0,1=20,2=2
P 3.87193002 1.86311004 0 P 1 8 0;0,1=20,2=2
P 4.42311004 1.43005 0 P 1 8 0;0,1=20,2=2
P 4.42311004 1.46941998 0 P 1 8 0;0,1=20,2=2
P 4.38373996 1.3513 0 P 1 8 0;0,1=20,2=2
P 4.34436998 1.46941998 0 P 1 8 0;0,1=20,2=2
P 4.34436998 1.50878996 0 P 1 8 0;0,1=20,2=2
P 4.38373996 1.46941998 0 P 1 8 0;0,1=20,2=2
P 4.42311004 1.50878996 0 P 1 8 0;0,1=20,2=2
P 3.9113 1.82373996 0 P 1 8 0;0,1=20,2=2
P 3.95066998 1.82373996 0 P 1 8 0;0,1=20,2=2
P 3.99005 1.86311004 0 P 1 8 0;0,1=20,2=2
P 3.99005 1.90248002 0 P 1 8 0;0,1=20,2=2
P 4.34436998 1.94185 0 P 1 8 0;0,1=20,2=2
P 4.54121998 1.82373996 0 P 1 8 0;0,1=20,2=2
P 3.87193002 1.3513 0 P 1 8 0;0,1=20,2=2
P 3.87193002 1.39066998 0 P 1 8 0;0,1=20,2=2
P 3.87193002 1.46941998 0 P 1 8 0;0,1=20,2=2
P 3.87193002 1.54816004 0 P 1 8 0;0,1=20,2=2
P 3.87193002 1.6269 0 P 1 8 0;0,1=20,2=2
P 3.87193002 1.70563996 0 P 1 8 0;0,1=20,2=2
P 3.87193002 1.78436998 0 P 1 8 0;0,1=20,2=2
P 3.87193002 2.17806998 0 P 1 8 0;0,1=20,2=2
P 3.9113 1.39066998 0 P 1 8 0;0,1=20,2=2
P 3.9113 1.78436998 0 P 1 8 0;0,1=20,2=2
P 3.9113 2.05996004 0 P 1 8 0;0,1=20,2=2
P 3.95066998 1.39066998 0 P 1 8 0;0,1=20,2=2
P 3.95066998 1.50878996 0 P 1 8 0;0,1=20,2=2
P 3.95066998 1.66626998 0 P 1 8 0;0,1=20,2=2
P 3.95066998 1.78436998 0 P 1 8 0;0,1=20,2=2
P 3.95066998 1.94185 0 P 1 8 0;0,1=20,2=2
P 3.99005 1.39066998 0 P 1 8 0;0,1=20,2=2
P 3.99005 1.43005 0 P 1 8 0;0,1=20,2=2
P 3.99005 1.58753002 0 P 1 8 0;0,1=20,2=2
P 3.99005 1.78436998 0 P 1 8 0;0,1=20,2=2
P 3.99005 1.82373996 0 P 1 8 0;0,1=20,2=2
P 4.02941998 1.43005 0 P 1 8 0;0,1=20,2=2
P 4.02941998 1.46941998 0 P 1 8 0;0,1=20,2=2
P 4.02941998 1.54816004 0 P 1 8 0;0,1=20,2=2
P 4.02941998 1.6269 0 P 1 8 0;0,1=20,2=2
P 4.02941998 1.70563996 0 P 1 8 0;0,1=20,2=2
P 4.02941998 2.09933002 0 P 1 8 0;0,1=20,2=2
P 4.06878996 1.46941998 0 P 1 8 0;0,1=20,2=2
P 4.06878996 1.70563996 0 P 1 8 0;0,1=20,2=2
P 4.06878996 1.98121998 0 P 1 8 0;0,1=20,2=2
P 4.10816004 1.46941998 0 P 1 8 0;0,1=20,2=2
P 4.10816004 1.50878996 0 P 1 8 0;0,1=20,2=2
P 4.10816004 1.54816004 0 P 1 8 0;0,1=20,2=2
P 4.10816004 1.58753002 0 P 1 8 0;0,1=20,2=2
P 4.10816004 1.6269 0 P 1 8 0;0,1=20,2=2
P 4.10816004 1.66626998 0 P 1 8 0;0,1=20,2=2
P 4.10816004 1.78436998 0 P 1 8 0;0,1=20,2=2
P 4.10816004 1.86311004 0 P 1 8 0;0,1=20,2=2
P 4.14753002 1.31193002 0 P 1 8 0;0,1=20,2=2
P 4.14753002 1.54816004 0 P 1 8 0;0,1=20,2=2
P 4.14753002 1.6269 0 P 1 8 0;0,1=20,2=2
P 4.14753002 1.70563996 0 P 1 8 0;0,1=20,2=2
P 4.14753002 2.1387 0 P 1 8 0;0,1=20,2=2
P 4.1869 1.58753002 0 P 1 8 0;0,1=20,2=2
P 4.1869 1.66626998 0 P 1 8 0;0,1=20,2=2
P 4.1869 1.78436998 0 P 1 8 0;0,1=20,2=2
P 4.1869 2.02058996 0 P 1 8 0;0,1=20,2=2
P 4.22626998 1.46941998 0 P 1 8 0;0,1=20,2=2
P 4.22626998 1.54816004 0 P 1 8 0;0,1=20,2=2
P 4.22626998 1.6269 0 P 1 8 0;0,1=20,2=2
P 4.22626998 1.70563996 0 P 1 8 0;0,1=20,2=2
P 4.22626998 1.90248002 0 P 1 8 0;0,1=20,2=2
P 4.26563996 1.3513 0 P 1 8 0;0,1=20,2=2
P 4.26563996 1.58753002 0 P 1 8 0;0,1=20,2=2
P 4.26563996 1.6269 0 P 1 8 0;0,1=20,2=2
P 4.26563996 1.66626998 0 P 1 8 0;0,1=20,2=2
P 4.34436998 1.54816004 0 P 1 8 0;0,1=20,2=2
P 4.34436998 1.6269 0 P 1 8 0;0,1=20,2=2
P 4.34436998 1.66626998 0 P 1 8 0;0,1=20,2=2
P 4.34436998 1.70563996 0 P 1 8 0;0,1=20,2=2
P 4.34436998 2.05996004 0 P 1 8 0;0,1=20,2=2
P 4.38373996 1.50878996 0 P 1 8 0;0,1=20,2=2
P 4.38373996 1.58753002 0 P 1 8 0;0,1=20,2=2
P 4.38373996 1.6269 0 P 1 8 0;0,1=20,2=2
P 4.38373996 1.66626998 0 P 1 8 0;0,1=20,2=2
P 4.38373996 1.94185 0 P 1 8 0;0,1=20,2=2
P 4.42311004 1.39066998 0 P 1 8 0;0,1=20,2=2
P 4.42311004 1.54816004 0 P 1 8 0;0,1=20,2=2
P 4.42311004 1.6269 0 P 1 8 0;0,1=20,2=2
P 4.42311004 1.70563996 0 P 1 8 0;0,1=20,2=2
P 4.42311004 1.82373996 0 P 1 8 0;0,1=20,2=2
P 4.46248002 1.58753002 0 P 1 8 0;0,1=20,2=2
P 4.46248002 1.66626998 0 P 1 8 0;0,1=20,2=2
P 4.46248002 1.78436998 0 P 1 8 0;0,1=20,2=2
P 4.46248002 2.09933002 0 P 1 8 0;0,1=20,2=2
P 4.50185 1.54816004 0 P 1 8 0;0,1=20,2=2
P 4.50185 1.6269 0 P 1 8 0;0,1=20,2=2
P 4.50185 1.70563996 0 P 1 8 0;0,1=20,2=2
P 4.50185 1.98121998 0 P 1 8 0;0,1=20,2=2
P 4.54121998 1.43005 0 P 1 8 0;0,1=20,2=2
P 4.54121998 1.86311004 0 P 1 8 0;0,1=20,2=2
P 4.57843996 1.31408002 0 P 1 8 0;0,1=20,2=2
P 4.58058996 1.66626998 0 P 1 8 0;0,1=20,2=2
P 4.58058996 2.1387 0 P 1 8 0;0,1=20,2=2
P 4.61996004 1.58753002 0 P 1 8 0;0,1=20,2=2
P 4.61996004 2.02058996 0 P 1 8 0;0,1=20,2=2
P 4.65933002 1.46941998 0 P 1 8 0;0,1=20,2=2
P 4.65933002 1.90248002 0 P 1 8 0;0,1=20,2=2
P 4.6987 1.3513 0 P 1 8 0;0,1=20,2=2
P 4.6987 1.78436998 0 P 1 8 0;0,1=20,2=2
P 4.6987 2.17806998 0 P 1 8 0;0,1=20,2=2
P 4.73806998 2.05996004 0 P 1 8 0;0,1=20,2=2
P 4.22626998 1.86311004 0 P 1 8 0;0,1=20,2=2
P 4.22626998 1.82373996 0 P 1 8 0;0,1=20,2=2
P 4.14753002 1.90248002 0 P 1 8 0;0,1=20,2=2
P 4.1869 1.90248002 0 P 1 8 0;0,1=20,2=2
P 4.1869 1.86311004 0 P 1 8 0;0,1=20,2=2
P 4.14753002 1.86311004 0 P 1 8 0;0,1=20,2=2
P 4.42311004 1.90248002 0 P 1 8 0;0,1=20,2=2
P 4.42311004 1.94185 0 P 1 8 0;0,1=20,2=2
P 4.38373996 1.90248002 0 P 1 8 0;0,1=20,2=2
P 3.99005 1.50878996 0 P 1 8 0;0,1=20,2=2
P 3.99005 1.66626998 0 P 1 8 0;0,1=20,2=2
P 4.02941998 1.58753002 0 P 1 8 0;0,1=20,2=2
P 4.06878996 1.54816004 0 P 1 8 0;0,1=20,2=2
P 4.06878996 1.6269 0 P 1 8 0;0,1=20,2=2
P 4.14753002 1.58753002 0 P 1 8 0;0,1=20,2=2
P 4.14753002 1.66626998 0 P 1 8 0;0,1=20,2=2
P 4.1869 1.54816004 0 P 1 8 0;0,1=20,2=2
P 4.1869 1.6269 0 P 1 8 0;0,1=20,2=2
P 4.1869 1.70563996 0 P 1 8 0;0,1=20,2=2
P 4.22626998 1.58753002 0 P 1 8 0;0,1=20,2=2
P 4.26563996 1.54816004 0 P 1 8 0;0,1=20,2=2
P 4.26563996 1.70563996 0 P 1 8 0;0,1=20,2=2
P 4.34436998 1.58753002 0 P 1 8 0;0,1=20,2=2
P 4.38373996 1.54816004 0 P 1 8 0;0,1=20,2=2
P 4.38373996 1.70563996 0 P 1 8 0;0,1=20,2=2
P 4.42311004 1.58753002 0 P 1 8 0;0,1=20,2=2
P 4.42311004 1.66626998 0 P 1 8 0;0,1=20,2=2
P 4.46248002 1.54816004 0 P 1 8 0;0,1=20,2=2
P 4.46248002 1.6269 0 P 1 8 0;0,1=20,2=2
P 4.50185 1.58753002 0 P 1 8 0;0,1=20,2=2
P 4.50185 1.66626998 0 P 1 8 0;0,1=20,2=2
P 4.02941998 1.78436998 0 P 1 8 0;0,1=20,2=2
P 4.14753002 1.78436998 0 P 1 8 0;0,1=20,2=2
P 4.22626998 1.66626998 0 P 1 8 0;0,1=20,2=2
P 4.22626998 1.78436998 0 P 1 8 0;0,1=20,2=2
P 4.34436998 1.78436998 0 P 1 8 0;0,1=20,2=2
P 4.42311004 1.78436998 0 P 1 8 0;0,1=20,2=2
P 4.46248002 1.70563996 0 P 1 8 0;0,1=20,2=2
P 3.95066998 1.31193002 0 P 1 8 0;0,1=20,2=2
P 4.06878996 1.3513 0 P 1 8 0;0,1=20,2=2
P 4.14753002 1.50878996 0 P 1 8 0;0,1=20,2=2
P 4.1869 1.39066998 0 P 1 8 0;0,1=20,2=2
P 4.34436998 1.43005 0 P 1 8 0;0,1=20,2=2
P 4.38373996 1.31193002 0 P 1 8 0;0,1=20,2=2
P 4.46248002 1.46941998 0 P 1 8 0;0,1=20,2=2
P 4.50185 1.3513 0 P 1 8 0;0,1=20,2=2
P 4.58058996 1.50878996 0 P 1 8 0;0,1=20,2=2
P 4.61996004 1.39066998 0 P 1 8 0;0,1=20,2=2
P 4.6987 1.54816004 0 P 1 8 0;0,1=20,2=2
P 4.73806998 1.43005 0 P 1 8 0;0,1=20,2=2
P 3.855 1.96153996 0 P 1 8 0;0,1=20,2=2
P 3.9113 1.86311004 0 P 1 8 0;0,1=20,2=2
P 3.95066998 2.1387 0 P 1 8 0;0,1=20,2=2
P 3.99005 2.02058996 0 P 1 8 0;0,1=20,2=2
P 4.02941998 1.90248002 0 P 1 8 0;0,1=20,2=2
P 4.06878996 1.78436998 0 P 1 8 0;0,1=20,2=2
P 4.06878996 2.17806998 0 P 1 8 0;0,1=20,2=2
P 4.10816004 2.05996004 0 P 1 8 0;0,1=20,2=2
P 4.14753002 1.94185 0 P 1 8 0;0,1=20,2=2
P 4.1869 1.82373996 0 P 1 8 0;0,1=20,2=2
P 4.22626998 2.09933002 0 P 1 8 0;0,1=20,2=2
P 4.26563996 1.98121998 0 P 1 8 0;0,1=20,2=2
P 4.34436998 1.86311004 0 P 1 8 0;0,1=20,2=2
P 4.38373996 2.1387 0 P 1 8 0;0,1=20,2=2
P 4.42311004 2.02058996 0 P 1 8 0;0,1=20,2=2
P 4.46248002 1.90248002 0 P 1 8 0;0,1=20,2=2
P 4.50185 1.78436998 0 P 1 8 0;0,1=20,2=2
P 4.50185 2.17806998 0 P 1 8 0;0,1=20,2=2
P 4.54121998 2.05996004 0 P 1 8 0;0,1=20,2=2
P 4.58058996 1.94185 0 P 1 8 0;0,1=20,2=2
P 4.61996004 1.82373996 0 P 1 8 0;0,1=20,2=2
P 4.65933002 1.66626998 0 P 1 8 0;0,1=20,2=2
P 4.65933002 2.09933002 0 P 1 8 0;0,1=20,2=2
P 4.6987 1.98121998 0 P 1 8 0;0,1=20,2=2
P 4.73806998 1.86311004 0 P 1 8 0;0,1=20,2=2
P 3.87193002 1.58753002 0 P 1 8 0;0,1=21,2=2
P 3.9113 1.58753002 0 P 1 8 0;0,1=21,2=2
P 3.99005 1.70563996 0 P 1 8 0;0,1=21,2=2
P 3.87193002 1.66626998 0 P 1 8 0;0,1=21,2=2
P 3.9113 1.66626998 0 P 1 8 0;0,1=21,2=2
P 3.95066998 1.6269 0 P 1 8 0;0,1=21,2=2
P 3.99005 1.6269 0 P 1 8 0;0,1=21,2=2
P 4.65933002 1.31193002 0 P 1 8 0;0,1=21,2=2
P 4.61996004 1.31193002 0 P 1 8 0;0,1=21,2=2
P 4.46248002 1.86311004 0 P 1 8 0;0,1=21,2=2
P 4.42311004 1.86311004 0 P 1 8 0;0,1=21,2=2
P 4.02941998 1.50878996 0 P 1 8 0;0,1=21,2=2
P 4.06878996 1.50878996 0 P 1 8 0;0,1=21,2=2
P 4.50185 1.43005 0 P 1 8 0;0,1=21,2=2
P 4.46248002 1.43005 0 P 1 8 0;0,1=21,2=2
P 4.02941998 1.66626998 0 P 1 8 0;0,1=21,2=2
P 4.06878996 1.66626998 0 P 1 8 0;0,1=21,2=2
P 3.99005 2.09933002 0 P 1 8 0;0,1=24,2=2
P 4.26563996 1.43005 0 P 1 8 0;0,1=24,2=2
P 4.38373996 2.02058996 0 P 1 8 0;0,1=24,2=2
P 4.26563996 1.86311004 0 P 1 8 0;0,1=24,2=2
P 4.42311004 2.09933002 0 P 1 8 0;0,1=24,2=2
P 3.87193002 1.43005 0 P 1 8 0;0,1=21,2=2
P 3.9113 1.43005 0 P 1 8 0;0,1=21,2=2
P 3.95066998 1.46941998 0 P 1 8 0;0,1=21,2=2
P 3.99005 1.46941998 0 P 1 8 0;0,1=21,2=2
P 3.87193002 1.50878996 0 P 1 8 0;0,1=21,2=2
P 3.9113 1.50878996 0 P 1 8 0;0,1=21,2=2
P 3.95066998 1.54816004 0 P 1 8 0;0,1=21,2=2
P 3.99005 1.54816004 0 P 1 8 0;0,1=21,2=2
P 4.73806998 1.3513 0 P 1 8 0;0,1=21,2=2
P 4.73806998 1.39066998 0 P 1 8 0;0,1=21,2=2
P 4.73806998 1.46941998 0 P 1 8 0;0,1=21,2=2
P 4.6987 1.46941998 0 P 1 8 0;0,1=21,2=2
P 5.6065 0.7045 1 P 3 8 0;0,1=17,2=2
P 1.6615 3.0405 1 P 3 8 0;0,1=17,2=2

### steps/pcb/layers/l02_gnd1/features
#
#Num Features
#
F 2385

#
#Units
#
U INCH

#
#Feature symbol names
#
$0 r5
$1 r6
$2 r10
$3 r26
$4 r28
$5 r30
$6 r32
$7 r39
$8 r82
$9 r99
$10 r102
$11 r125
$12 r143
$13 r150
$14 024x051ob071x075p_l
$15 024x051ob071x075p_r
$16 024x063ob035x075p
$17 ths102x92.01x45x4x14 I
$18 ths105x95x45x4x14 I
$19 ths191.99x182x45x4x27 I
$20 ths42.01x31.99x45x4x10 I
$21 ths58.99x49x45x4x10 I
$22 ths89x79x45x4x11.99 I

#
#Feature attribute names
#
@0 .nomenclature
@1 .geometry
@2 .sip

#
#Feature attribute text strings
#
&0 V010C020P_TP030B
&1 V008C018P-ANTI28-NSM
&2 V010C020P
&3 TPV010CT020B030
&4 V008C018P_ANTI026_TP030B
&5 V008C018P_NATI28_TP030B_NSMT
&6 016C024P
&7 V008C018P_TP030B
&8 V008C018P
&9 V008C018P_ANTI28
&10 059C086P
&11 V008C018P_ANTI026_NSM
&12 076S104P
&13 076C104P
&14 079C100P
&15 V010C020P_SM014-NTH
&16 024X063OB035X075P
&17 166CT244CB198P
&18 024X051OB071X075P_R
&19 024X051OB071X075P_L
&20 033C057P
&21 063C090P
&22 MTH100C090N
&23 MTH125C115N
&24 MTH118C108N

#
#Layer features
#
S P 0;0,2=1
OB -24.76435 -17.98935 I
OS -24.76435 16.38535
OS 21.05735 16.38535
OS 21.05735 -17.98935
OS -24.76435 -17.98935
OE
OB -0.00110019685 0.21653976378 H
OC 0.039369783465 0.176069783465 0.039369783465 0.21653976378 N
OS 0.551194094488 0.176069980315
OC 0.59165 0.216525885827 0.551180019685 0.21653996063 N
OS 0.59165019685 0.46260019685
OC 0.629906200787 0.500870177165 0.629920177165 0.46260019685 Y
OS 1.273619980315 0.500869980315
OC 1.31188996063 0.462613779528 1.273619980315 0.4626 Y
OS 1.31188976378 0.21653976378
OC 1.35235984252 0.176069783465 1.352359744094 0.21653976378 N
OS 1.588594094488 0.176069980315
OC 1.62905 0.216525885827 1.588580019685 0.21653996063 N
OS 1.62905019685 0.430120177165
OC 1.77055019685 0.430134055118 1.69980019685 0.430120177165 Y
OS 1.770550098425 0.019702952756
OC 1.770872244094 0.018912204724 1.77165 0.019690059055 N
OS 1.790547933071 -0.000763484252
OC 1.791339862205 -0.001100098425 1.79133996063 -0.000000098425 N
OS 2.192896850394 -0.001100098425
OC 2.193511712598 -0.000920767717 2.192909645669 -0.00000019685 N
OC 2.193677066929 -0.000788484252 2.192910728346 -0.000000098425 N
OS 2.213388188976 0.018922637795
OC 2.213699901575 0.019689862205 2.212599901575 0.019689862205 N
OS 2.2137 0.29331003937
OC 2.2863 0.29331003937 2.25 0.29331003937 Y
OS 2.286300098425 0.019690059055
OC 2.286636712598 0.018898129921 2.287400098425 0.01969015748 N
OS 2.306298129921 -0.000763287402
OC 2.307090059055 -0.001099901575 2.30709015748 0.000000098425 N
OS 3.102347047244 -0.001099901575
OC 3.102961909449 -0.000920570866 3.10235984252 0 N
OC 3.10312726378 -0.000788287402 3.102360925197 0.000000098425 N
OS 3.122837893701 0.01892234252
OC 3.122970570866 0.019087992126 3.122049901575 0.019689468504 N
OC 3.123149901575 0.019702952756 3.12205 0.019690059055 N
OS 3.12314980315 0.462613779528
OC 3.161419783465 0.500869783465 3.161419783465 0.46259980315 Y
OS 6.561034055118 0.500869980315
OC 6.60148996063 0.541325885827 6.561019980315 0.54133996063 N
OS 6.60149015748 2.374999901575
OC 6.580710531496 2.39579015748 6.580705216535 2.375005216535 N
OS 6.572096555118 2.39578996063
OC 6.553530019685 2.414369980315 6.57211003937 2.414369980315 Y
OS 6.553529822835 2.826783759843
OC 6.572110137795 2.84535984252 6.57211476378 2.826774901575 Y
OS 6.572111122047 2.84535984252
OS 6.580724409449 2.84536003937
OC 6.60148996063 2.866125590551 6.58071003937 2.86613996063 N
OS 6.60149015748 4.33661023622
OC 6.561020177165 4.377080216535 6.561020177165 4.33661023622 N
OS 0.039355905512 4.377080019685
OC -0.0011 4.336624114173 0.039369980315 4.33661003937 N
OS -0.00110019685 0.21653976378
OE
SE
S P 0
OB -0.00110019685 0.21653976378 I
OS -0.0011 4.336624114173
OC 0.039355905512 4.377080019685 0.039369980315 4.33661003937 Y
OS 6.561020177165 4.377080216535
OC 6.60149015748 4.33661023622 6.561020177165 4.33661023622 Y
OS 6.60148996063 2.866125590551
OC 6.580724409449 2.84536003937 6.58071003937 2.86613996063 Y
OS 6.580725 2.84536003937
OS 6.580710629921 2.845359940945
OS 6.572123917323 2.845359940945
OS 6.572111122047 2.84535984252
OS 6.572110137795 2.84535984252
OC 6.553529822835 2.826783759843 6.57211476378 2.826774901575 N
OS 6.553530019685 2.414369980315
OC 6.572096555118 2.39578996063 6.57211003937 2.414369980315 N
OS 6.580710531496 2.39579015748
OC 6.60149015748 2.374999901575 6.580705216535 2.375005216535 Y
OS 6.60148996063 0.541325885827
OC 6.561034055118 0.500869980315 6.561019980315 0.54133996063 Y
OS 6.561034744094 0.500869980315
OS 6.561020570866 0.50086988189
OS 3.161433858268 0.50086988189
OS 3.161419783465 0.500869783465
OC 3.12314980315 0.462613779528 3.161419783465 0.46259980315 N
OS 3.123149901575 0.019702952756
OC 3.122970570866 0.019087992126 3.12205 0.019690059055 Y
OC 3.122837893701 0.01892234252 3.122049901575 0.019689468504 Y
OS 3.10312726378 -0.000788287402
OC 3.102961909449 -0.000920570866 3.102360925197 0.000000098425 Y
OC 3.102347047244 -0.001099901575 3.10235984252 0 Y
OS 2.307090059055 -0.001099901575
OC 2.306298129921 -0.000763287402 2.30709015748 0.000000098425 Y
OS 2.286636712598 0.018898129921
OC 2.286300098425 0.019690059055 2.287400098425 0.01969015748 Y
OS 2.2863 0.29331003937
OC 2.2137 0.29331003937 2.25 0.29331003937 N
OS 2.213699901575 0.019689862205
OC 2.213388188976 0.018922637795 2.212599901575 0.019689862205 Y
OS 2.193677066929 -0.000788484252
OC 2.193511712598 -0.000920767717 2.192910728346 -0.000000098425 Y
OC 2.192896850394 -0.001100098425 2.192909645669 -0.00000019685 Y
OS 1.791339862205 -0.001100098425
OC 1.790547933071 -0.000763484252 1.79133996063 -0.000000098425 Y
OS 1.770872244094 0.018912204724
OC 1.770550098425 0.019702952756 1.77165 0.019690059055 Y
OS 1.77055019685 0.430134055118
OC 1.62905019685 0.430120177165 1.69980019685 0.430120177165 N
OS 1.62905 0.216525885827
OC 1.588594094488 0.176069980315 1.588580019685 0.21653996063 Y
OS 1.588594783465 0.176069980315
OS 1.588580610236 0.17606988189
OS 1.352373917323 0.17606988189
OS 1.35235984252 0.176069783465
OC 1.31188976378 0.21653976378 1.352359744094 0.21653976378 Y
OS 1.31188996063 0.462613779528
OC 1.273619980315 0.500869980315 1.273619980315 0.4626 N
OS 0.629906200787 0.500870177165
OC 0.59165019685 0.46260019685 0.629920177165 0.46260019685 N
OS 0.59165 0.216525885827
OC 0.551194094488 0.176069980315 0.551180019685 0.21653996063 Y
OS 0.551194783465 0.176069980315
OS 0.551180610236 0.17606988189
OS 0.039383858268 0.17606988189
OS 0.039369783465 0.176069783465
OC -0.00110019685 0.21653976378 0.039369783465 0.21653976378 Y
OE
OB 0.03003996063 0.21653996063 H
OC 0.039369980315 0.20721003937 0.03936988189 0.21653996063 N
OS 0.551180019685 0.20721003937
OC 0.56051003937 0.21653996063 0.55118011811 0.21653996063 N
OS 0.56051003937 0.4626
OC 0.629919980315 0.53201003937 0.629919980315 0.462600098425 Y
OS 1.273619980315 0.53201003937
OC 1.343030019685 0.4626 1.273619980315 0.4626 Y
OS 1.343030019685 0.21653996063
OC 1.35236003937 0.20721003937 1.352359940945 0.21653996063 N
OS 1.588580019685 0.20721003937
OC 1.59791003937 0.21653996063 1.58858011811 0.21653996063 N
OS 1.59791003937 0.430119980315
OC 1.80168996063 0.430119980315 1.6998 0.430119980315 Y
OS 1.80168996063 0.262
OS 2.18256003937 0.262
OS 2.18256003937 0.29331003937
OC 2.31743996063 0.29331003937 2.25 0.29331003937 Y
OS 2.31743996063 0.262
OS 3.09201003937 0.262
OS 3.09201003937 0.4626
OC 3.161419980315 0.53201003937 3.161419980315 0.462600098425 Y
OS 6.561019980315 0.53201003937
OC 6.57035 0.54133996063 6.56102007874 0.54133996063 N
OS 6.57035 2.364680019685
OC 6.52238996063 2.414369980315 6.572111220472 2.41437007874 Y
OS 6.52238996063 2.826780019685
OC 6.57035 2.876469980315 6.572115452756 2.826775885827 Y
OS 6.57035 4.33661003937
OC 6.561019980315 4.34593996063 6.56102007874 4.33661003937 N
OS 0.039369980315 4.34593996063
OC 0.03003996063 4.33661003937 0.03936988189 4.33661003937 N
OS 0.03003996063 0.21653996063
OE
OB 0.36981003937 0.36811003937 I
OC 0.36981003937 0.36811003937 0.295280019685 0.36811003937 Y
OE
OB 0.36981003937 3.73031003937 I
OC 0.36981003937 3.73031003937 0.295280019685 3.73031003937 Y
OE
OB 0.672580019685 3.482980019685 I
OS 0.672580019685 3.530019980315
OS 0.692619980315 3.530019980315
OS 0.692619980315 3.482980019685
OS 0.672580019685 3.482980019685
OE
OB 0.688980019685 3.560980019685 I
OS 0.688980019685 3.589019980315
OS 0.749019980315 3.589019980315
OS 0.749019980315 3.560980019685
OS 0.688980019685 3.560980019685
OE
OB 0.747380019685 3.482980019685 I
OS 0.747380019685 3.530019980315
OS 0.767419980315 3.530019980315
OS 0.767419980315 3.482980019685
OS 0.747380019685 3.482980019685
OE
OB 1.058980019685 3.810980019685 I
OS 1.058980019685 3.839019980315
OS 1.119019980315 3.839019980315
OS 1.119019980315 3.810980019685
OS 1.058980019685 3.810980019685
OE
OB 1.092980019685 3.674980019685 I
OS 1.092980019685 3.703019980315
OS 1.117019980315 3.703019980315
OS 1.117019980315 3.674980019685
OS 1.092980019685 3.674980019685
OE
OB 1.092980019685 3.716980019685 I
OS 1.092980019685 3.745019980315
OS 1.117019980315 3.745019980315
OS 1.117019980315 3.716980019685
OS 1.092980019685 3.716980019685
OE
OB 1.126819980315 3.545980019685 I
OS 1.126819980315 3.610019980315
OS 1.13886003937 3.610019980315
OS 1.13886003937 3.545980019685
OS 1.126819980315 3.545980019685
OE
OB 1.142980019685 3.674980019685 I
OS 1.142980019685 3.703019980315
OS 1.167019980315 3.703019980315
OS 1.167019980315 3.674980019685
OS 1.142980019685 3.674980019685
OE
OB 1.142980019685 3.716980019685 I
OS 1.142980019685 3.745019980315
OS 1.167019980315 3.745019980315
OS 1.167019980315 3.716980019685
OS 1.142980019685 3.716980019685
OE
OB 1.1465 3.545980019685 I
OS 1.1465 3.610019980315
OS 1.15856003937 3.610019980315
OS 1.15856003937 3.545980019685
OS 1.1465 3.545980019685
OE
OB 1.4977 1.060430019685 I
OC 1.4977 1.060430019685 1.435669980315 1.060430019685 Y
OE
OB 1.5227 2.680430019685 I
OC 1.5227 2.680430019685 1.460669980315 2.680430019685 Y
OE
OB 2.39006003937 0.679980019685 I
OS 2.39006003937 0.750019980315
OS 2.4201 0.750019980315
OS 2.4201 0.679980019685
OS 2.39006003937 0.679980019685
OE
OB 2.4562 0.748980019685 I
OS 2.4562 0.777019980315
OS 2.51623996063 0.777019980315
OS 2.51623996063 0.748980019685
OS 2.4562 0.748980019685
OE
OB 2.7477 1.121430019685 I
OC 2.7477 1.121430019685 2.685669980315 1.121430019685 Y
OE
OB 2.7477 2.559430019685 I
OC 2.7477 2.559430019685 2.685669980315 2.559430019685 Y
OE
OB 2.629380019685 0.338980019685 I
OS 2.629380019685 0.399019980315
OS 2.6574 0.399019980315
OS 2.6574 0.338980019685
OS 2.629380019685 0.338980019685
OE
OB 2.65306003937 0.748980019685 I
OS 2.65306003937 0.777019980315
OS 2.713080019685 0.777019980315
OS 2.713080019685 0.748980019685
OS 2.65306003937 0.748980019685
OE
OB 2.73433996063 1.746819980315 I
OS 2.73433996063 1.75686003937
OS 2.805380019685 1.75686003937
OS 2.805380019685 1.746819980315
OS 2.73433996063 1.746819980315
OE
OB 2.73433996063 1.7665 I
OS 2.73433996063 1.77653996063
OS 2.805380019685 1.77653996063
OS 2.805380019685 1.7665
OS 2.73433996063 1.7665
OE
OB 2.73433996063 1.86493996063 I
OS 2.73433996063 1.87496003937
OS 2.805380019685 1.87496003937
OS 2.805380019685 1.86493996063
OS 2.73433996063 1.86493996063
OE
OB 2.73433996063 1.884619980315 I
OS 2.73433996063 1.89463996063
OS 2.805380019685 1.89463996063
OS 2.805380019685 1.884619980315
OS 2.73433996063 1.884619980315
OE
OB 2.73433996063 1.9043 I
OS 2.73433996063 1.91433996063
OS 2.805380019685 1.91433996063
OS 2.805380019685 1.9043
OS 2.73433996063 1.9043
OE
OB 2.73433996063 1.923980019685 I
OS 2.73433996063 1.934019980315
OS 2.805380019685 1.934019980315
OS 2.805380019685 1.923980019685
OS 2.73433996063 1.923980019685
OE
OB 2.783 1.971980019685 I
OS 2.783 2.002019980315
OS 2.853019980315 2.002019980315
OS 2.853019980315 1.971980019685
OS 2.783 1.971980019685
OE
OB 2.78686003937 0.338980019685 I
OS 2.78686003937 0.399019980315
OS 2.814880019685 0.399019980315
OS 2.814880019685 0.338980019685
OS 2.78686003937 0.338980019685
OE
OB 2.80453996063 0.748980019685 I
OS 2.80453996063 0.777019980315
OS 2.86456003937 0.777019980315
OS 2.86456003937 0.748980019685
OS 2.80453996063 0.748980019685
OE
OB 2.829980019685 1.823980019685 I
OS 2.829980019685 1.894019980315
OS 2.860019980315 1.894019980315
OS 2.860019980315 1.823980019685
OS 2.829980019685 1.823980019685
OE
OB 2.891819980315 1.9043 I
OS 2.891819980315 1.91433996063
OS 2.96286003937 1.91433996063
OS 2.96286003937 1.9043
OS 2.891819980315 1.9043
OE
OB 2.891819980315 1.923980019685 I
OS 2.891819980315 1.934019980315
OS 2.96286003937 1.934019980315
OS 2.96286003937 1.923980019685
OS 2.891819980315 1.923980019685
OE
OB 2.94433996063 0.338980019685 I
OS 2.94433996063 0.399019980315
OS 2.97236003937 0.399019980315
OS 2.97236003937 0.338980019685
OS 2.94433996063 0.338980019685
OE
OB 2.94433996063 0.434980019685 I
OS 2.94433996063 0.495019980315
OS 2.97236003937 0.495019980315
OS 2.97236003937 0.434980019685
OS 2.94433996063 0.434980019685
OE
OB 3.104980019685 1.837980019685 I
OS 3.104980019685 1.862019980315
OS 3.133019980315 1.862019980315
OS 3.133019980315 1.837980019685
OS 3.104980019685 1.837980019685
OE
OB 3.104980019685 1.882980019685 I
OS 3.104980019685 1.907019980315
OS 3.133019980315 1.907019980315
OS 3.133019980315 1.882980019685
OS 3.104980019685 1.882980019685
OE
OB 3.10516003937 0.875 I
OS 3.125 0.89483996063
OS 3.167469980315 0.852369980315
OS 3.147630019685 0.832530019685
OS 3.10516003937 0.875
OE
OB 3.108980019685 1.737980019685 I
OS 3.108980019685 1.762019980315
OS 3.137019980315 1.762019980315
OS 3.137019980315 1.737980019685
OS 3.108980019685 1.737980019685
OE
OB 3.108980019685 1.787980019685 I
OS 3.108980019685 1.812019980315
OS 3.137019980315 1.812019980315
OS 3.137019980315 1.787980019685
OS 3.108980019685 1.787980019685
OE
OB 3.146980019685 1.837980019685 I
OS 3.146980019685 1.862019980315
OS 3.175019980315 1.862019980315
OS 3.175019980315 1.837980019685
OS 3.146980019685 1.837980019685
OE
OB 3.146980019685 1.882980019685 I
OS 3.146980019685 1.907019980315
OS 3.175019980315 1.907019980315
OS 3.175019980315 1.882980019685
OS 3.146980019685 1.882980019685
OE
OB 3.150980019685 1.737980019685 I
OS 3.150980019685 1.762019980315
OS 3.179019980315 1.762019980315
OS 3.179019980315 1.737980019685
OS 3.150980019685 1.737980019685
OE
OB 3.150980019685 1.787980019685 I
OS 3.150980019685 1.812019980315
OS 3.179019980315 1.812019980315
OS 3.179019980315 1.787980019685
OS 3.150980019685 1.787980019685
OE
OB 3.153980019685 1.952980019685 I
OS 3.153980019685 1.977019980315
OS 3.182019980315 1.977019980315
OS 3.182019980315 1.952980019685
OS 3.153980019685 1.952980019685
OE
OB 3.153980019685 2.002980019685 I
OS 3.153980019685 2.027019980315
OS 3.182019980315 2.027019980315
OS 3.182019980315 2.002980019685
OS 3.153980019685 2.002980019685
OE
OB 3.153980019685 2.047980019685 I
OS 3.153980019685 2.072019980315
OS 3.182019980315 2.072019980315
OS 3.182019980315 2.047980019685
OS 3.153980019685 2.047980019685
OE
OB 3.153980019685 2.097980019685 I
OS 3.153980019685 2.122019980315
OS 3.182019980315 2.122019980315
OS 3.182019980315 2.097980019685
OS 3.153980019685 2.097980019685
OE
OB 3.195980019685 1.952980019685 I
OS 3.195980019685 1.977019980315
OS 3.224019980315 1.977019980315
OS 3.224019980315 1.952980019685
OS 3.195980019685 1.952980019685
OE
OB 3.195980019685 2.002980019685 I
OS 3.195980019685 2.027019980315
OS 3.224019980315 2.027019980315
OS 3.224019980315 2.002980019685
OS 3.195980019685 2.002980019685
OE
OB 3.195980019685 2.047980019685 I
OS 3.195980019685 2.072019980315
OS 3.224019980315 2.072019980315
OS 3.224019980315 2.047980019685
OS 3.195980019685 2.047980019685
OE
OB 3.195980019685 2.097980019685 I
OS 3.195980019685 2.122019980315
OS 3.224019980315 2.122019980315
OS 3.224019980315 2.097980019685
OS 3.195980019685 2.097980019685
OE
OB 3.213080019685 1.888980019685 I
OS 3.213080019685 1.917
OS 3.273119980315 1.917
OS 3.273119980315 1.888980019685
OS 3.213080019685 1.888980019685
OE
OB 3.246980019685 1.954980019685 I
OS 3.246980019685 1.983019980315
OS 3.271019980315 1.983019980315
OS 3.271019980315 1.954980019685
OS 3.246980019685 1.954980019685
OE
OB 3.246980019685 1.996980019685 I
OS 3.246980019685 2.025019980315
OS 3.271019980315 2.025019980315
OS 3.271019980315 1.996980019685
OS 3.246980019685 1.996980019685
OE
OB 3.246980019685 2.049980019685 I
OS 3.246980019685 2.078019980315
OS 3.271019980315 2.078019980315
OS 3.271019980315 2.049980019685
OS 3.246980019685 2.049980019685
OE
OB 3.246980019685 2.091980019685 I
OS 3.246980019685 2.120019980315
OS 3.271019980315 2.120019980315
OS 3.271019980315 2.091980019685
OS 3.246980019685 2.091980019685
OE
OB 3.359980019685 1.142980019685 I
OS 3.359980019685 1.213019980315
OS 3.390019980315 1.213019980315
OS 3.390019980315 1.142980019685
OS 3.359980019685 1.142980019685
OE
OB 3.398980019685 1.069980019685 I
OS 3.398980019685 1.100019980315
OS 3.469019980315 1.100019980315
OS 3.469019980315 1.069980019685
OS 3.398980019685 1.069980019685
OE
OB 3.439 1.884980019685 I
OS 3.439 1.945
OS 3.467019980315 1.945
OS 3.467019980315 1.884980019685
OS 3.439 1.884980019685
OE
OB 3.48743996063 1.9036 I
OS 3.48743996063 1.91163996063
OS 3.52446003937 1.91163996063
OS 3.52446003937 1.9036
OS 3.48743996063 1.9036
OE
OB 3.48743996063 1.91933996063 I
OS 3.48743996063 1.927380019685
OS 3.52446003937 1.927380019685
OS 3.52446003937 1.91933996063
OS 3.48743996063 1.91933996063
OE
OB 3.49563996063 1.03206003937 I
OS 3.49563996063 1.062080019685
OS 3.56566003937 1.062080019685
OS 3.56566003937 1.03206003937
OS 3.49563996063 1.03206003937
OE
OB 3.56356003937 1.88786003937 I
OS 3.56356003937 1.895880019685
OS 3.600580019685 1.895880019685
OS 3.600580019685 1.88786003937
OS 3.56356003937 1.88786003937
OE
OB 3.56356003937 1.9036 I
OS 3.56356003937 1.91163996063
OS 3.600580019685 1.91163996063
OS 3.600580019685 1.9036
OS 3.56356003937 1.9036
OE
OB 3.56356003937 1.91933996063 I
OS 3.56356003937 1.927380019685
OS 3.600580019685 1.927380019685
OS 3.600580019685 1.91933996063
OS 3.56356003937 1.91933996063
OE
OB 3.56356003937 1.9351 I
OS 3.56356003937 1.943119980315
OS 3.600580019685 1.943119980315
OS 3.600580019685 1.9351
OS 3.56356003937 1.9351
OE
OB 3.610980019685 0.905980019685 I
OS 3.610980019685 0.934019980315
OS 3.671019980315 0.934019980315
OS 3.671019980315 0.905980019685
OS 3.610980019685 0.905980019685
OE
OB 3.637 1.869580019685 I
OS 3.637 1.9296
OS 3.665019980315 1.9296
OS 3.665019980315 1.869580019685
OS 3.637 1.869580019685
OE
OB 3.871930019685 1.417019980315 I
OC 3.871930019685 1.443080019685 3.871930019685 1.43005 Y
OS 3.87798996063 1.443080019685
OC 3.881919980315 1.44783996063 3.877994291339 1.447078838583 N
OC 3.88173996063 1.449730019685 3.891611318898 1.449716633858 Y
OC 3.901480019685 1.449730019685 3.89161003937 1.449730019685 Y
OC 3.9013 1.44783996063 3.891608759843 1.449716633858 Y
OC 3.905230019685 1.443080019685 3.905225688976 1.447078838583 N
OS 3.9113 1.443080019685
OC 3.9113 1.417019980315 3.9113 1.43005 Y
OS 3.871930019685 1.417019980315
OE
OB 3.871930019685 1.49576003937 I
OC 3.871930019685 1.521819980315 3.871930019685 1.508790059055 Y
OS 3.87798996063 1.521819980315
OC 3.881919980315 1.526580019685 3.877994291339 1.525818799213 N
OC 3.88173996063 1.528469980315 3.891611318898 1.528456692913 Y
OC 3.901480019685 1.528469980315 3.89161003937 1.528469980315 Y
OC 3.9013 1.526580019685 3.891608759843 1.528456692913 Y
OC 3.905230019685 1.521819980315 3.905225688976 1.525818799213 N
OS 3.9113 1.521819980315
OC 3.9113 1.49576003937 3.9113 1.508790059055 Y
OS 3.871930019685 1.49576003937
OE
OB 3.871930019685 1.5745 I
OC 3.871930019685 1.60056003937 3.871930019685 1.587530019685 Y
OS 3.878 1.60056003937
OC 3.881919980315 1.605319980315 3.877994291339 1.604558858268 N
OC 3.88173996063 1.607180019685 3.891611318898 1.607196653543 Y
OS 3.88173996063 1.60721003937
OC 3.901480019685 1.60721003937 3.89161003937 1.60721003937 Y
OS 3.901480019685 1.607180019685
OC 3.9013 1.605319980315 3.891608759843 1.607196653543 Y
OC 3.905219980315 1.60056003937 3.905225688976 1.604558858268 N
OS 3.9113 1.60056003937
OC 3.9113 1.5745 3.9113 1.587530019685 Y
OS 3.871930019685 1.5745
OE
OB 3.871930019685 1.65323996063 I
OC 3.871930019685 1.6793 3.871930019685 1.666269980315 Y
OS 3.878 1.6793
OC 3.881919980315 1.68406003937 3.877994291339 1.683298818898 N
OC 3.88173996063 1.685919980315 3.891611318898 1.685936712598 Y
OS 3.88173996063 1.68595
OC 3.901480019685 1.68595 3.89161003937 1.68595 Y
OS 3.901480019685 1.685919980315
OC 3.9013 1.68406003937 3.891608759843 1.685936712598 Y
OC 3.905219980315 1.6793 3.905225688976 1.683298818898 N
OS 3.9113 1.6793
OC 3.9113 1.65323996063 3.9113 1.666269980315 Y
OS 3.871930019685 1.65323996063
OE
OB 3.94086003937 1.449730019685 I
OC 3.94086003937 1.449730019685 3.930980019685 1.449730019685 Y
OE
OB 3.94086003937 1.528469980315 I
OC 3.94086003937 1.528469980315 3.930980019685 1.528469980315 Y
OE
OB 3.94086003937 1.60721003937 I
OC 3.94086003937 1.60721003937 3.930980019685 1.60721003937 Y
OE
OB 3.94086003937 1.68595 I
OC 3.94086003937 1.68595 3.930980019685 1.68595 Y
OE
OB 3.950669980315 1.53513996063 I
OC 3.950669980315 1.561180019685 3.950669980315 1.54816003937 Y
OS 3.956730019685 1.561180019685
OC 3.96066003937 1.56595 3.956732185039 1.565182185039 N
OC 3.960480019685 1.56783996063 3.970351279528 1.567826673228 Y
OC 3.980219980315 1.56783996063 3.97035 1.56783996063 Y
OC 3.98003996063 1.56595 3.970348720472 1.567826673228 Y
OC 3.983969980315 1.561180019685 3.983967814961 1.565182185039 N
OS 3.99003996063 1.561180019685
OC 3.99003996063 1.53513996063 3.99003996063 1.54816003937 Y
OS 3.950669980315 1.53513996063
OE
OB 3.950669980315 1.692619980315 I
OC 3.950669980315 1.71866003937 3.950669980315 1.705640059055 Y
OS 3.956730019685 1.71866003937
OC 3.96066003937 1.723430019685 3.956732185039 1.722662204724 N
OC 3.960480019685 1.72528996063 3.970351279528 1.725306692913 Y
OS 3.960480019685 1.725319980315
OC 3.980219980315 1.725319980315 3.97035 1.725319980315 Y
OS 3.980219980315 1.72528996063
OC 3.98003996063 1.723430019685 3.970348720472 1.725306692913 Y
OC 3.983969980315 1.71866003937 3.983967814961 1.722662204724 N
OS 3.99003996063 1.71866003937
OC 3.99003996063 1.692619980315 3.99003996063 1.705640059055 Y
OS 3.950669980315 1.692619980315
OE
OB 3.950669980315 1.4564 I
OC 3.950669980315 1.48243996063 3.950669980315 1.469419980315 Y
OS 3.956730019685 1.48243996063
OC 3.96066003937 1.48721003937 3.956732185039 1.486442125984 N
OC 3.960480019685 1.4891 3.970351279528 1.489086712598 Y
OC 3.980219980315 1.4891 3.97035 1.4891 Y
OC 3.98003996063 1.48721003937 3.970348720472 1.489086712598 Y
OC 3.983969980315 1.48243996063 3.983967814961 1.486442125984 N
OS 3.99003996063 1.48243996063
OC 3.99003996063 1.4564 3.99003996063 1.469419980315 Y
OS 3.950669980315 1.4564
OE
OB 3.950669980315 1.613880019685 I
OC 3.950669980315 1.639919980315 3.950669980315 1.6269 Y
OS 3.956730019685 1.639919980315
OC 3.96066003937 1.64468996063 3.956732185039 1.643922145669 N
OC 3.960480019685 1.64655 3.970351279528 1.646566633858 Y
OS 3.960480019685 1.646580019685
OC 3.980219980315 1.646580019685 3.97035 1.646580019685 Y
OS 3.980219980315 1.64655
OC 3.98003996063 1.64468996063 3.970348720472 1.646566633858 Y
OC 3.983969980315 1.639919980315 3.983967814961 1.643922145669 N
OS 3.99003996063 1.639919980315
OC 3.99003996063 1.613880019685 3.99003996063 1.6269 Y
OS 3.950669980315 1.613880019685
OE
OB 3.997480019685 1.145980019685 I
OS 3.997480019685 1.176
OS 4.067519980315 1.176
OS 4.067519980315 1.145980019685
OS 3.997480019685 1.145980019685
OE
OB 4.01961003937 1.4891 I
OC 4.01961003937 1.4891 4.009730019685 1.4891 Y
OE
OB 4.01961003937 1.56783996063 I
OC 4.01961003937 1.56783996063 4.009730019685 1.56783996063 Y
OE
OB 4.01961003937 1.646580019685 I
OC 4.01961003937 1.646580019685 4.009730019685 1.646580019685 Y
OE
OB 4.01961003937 1.725319980315 I
OC 4.01961003937 1.725319980315 4.009730019685 1.725319980315 Y
OE
OB 4.029419980315 1.49576003937 I
OC 4.029419980315 1.521819980315 4.029419980315 1.508790059055 Y
OS 4.035480019685 1.521819980315
OC 4.03941003937 1.526580019685 4.035482283465 1.525820472441 N
OC 4.039219980315 1.528469980315 4.049096161417 1.528508661417 Y
OC 4.058980019685 1.528469980315 4.0491 1.528469980315 Y
OC 4.05878996063 1.526580019685 4.049103838583 1.528508661417 Y
OC 4.062719980315 1.521819980315 4.062717716535 1.525820472441 N
OS 4.06878996063 1.521819980315
OC 4.06878996063 1.49576003937 4.06878996063 1.508790059055 Y
OS 4.029419980315 1.49576003937
OE
OB 4.029419980315 1.65323996063 I
OC 4.029419980315 1.6793 4.029419980315 1.666269980315 Y
OS 4.03548996063 1.6793
OC 4.03941003937 1.68406003937 4.035484251969 1.683298917323 N
OC 4.039219980315 1.68595 4.049096161417 1.685988681102 Y
OC 4.058980019685 1.68595 4.0491 1.68595 Y
OC 4.05878996063 1.68406003937 4.049103838583 1.685988681102 Y
OC 4.06271003937 1.6793 4.062715748031 1.683298917323 N
OS 4.06878996063 1.6793
OC 4.06878996063 1.65323996063 4.06878996063 1.666269980315 Y
OS 4.029419980315 1.65323996063
OE
OB 4.09835 1.528469980315 I
OC 4.09835 1.528469980315 4.088469980315 1.528469980315 Y
OE
OB 4.09835 1.68595 I
OC 4.09835 1.68595 4.088469980315 1.68595 Y
OE
OB 4.3575 1.150980019685 I
OS 4.3575 1.181
OS 4.427519980315 1.181
OS 4.427519980315 1.150980019685
OS 4.3575 1.150980019685
OE
OB 4.41331003937 1.843430019685 I
OC 4.41331003937 1.843430019685 4.403430019685 1.843430019685 Y
OE
OB 4.42311003937 1.850080019685 I
OC 4.42311003937 1.87613996063 4.42311003937 1.86311003937 Y
OS 4.462480019685 1.87613996063
OC 4.462480019685 1.850080019685 4.462480019685 1.86311003937 Y
OS 4.45641003937 1.850080019685
OC 4.45248996063 1.845319980315 4.456415748031 1.846081102362 N
OC 4.452680019685 1.843430019685 4.442803838583 1.843391338583 Y
OC 4.432919980315 1.843430019685 4.4428 1.843430019685 Y
OC 4.43311003937 1.845319980315 4.442796161417 1.843391338583 Y
OC 4.42918996063 1.850080019685 4.429184251969 1.846081102362 N
OS 4.42311003937 1.850080019685
OE
OB 4.452680019685 1.449730019685 I
OC 4.452680019685 1.449730019685 4.4428 1.449730019685 Y
OE
OB 4.462480019685 1.417019980315 I
OC 4.462480019685 1.443080019685 4.462480019685 1.43005 Y
OS 4.46855 1.443080019685
OC 4.472480019685 1.44783996063 4.46855226378 1.447080511811 N
OC 4.4723 1.4497 4.482171259843 1.449716633858 Y
OS 4.4723 1.449730019685
OC 4.49203996063 1.449730019685 4.482169980315 1.449730019685 Y
OS 4.49203996063 1.4497
OC 4.49186003937 1.44783996063 4.482168700787 1.449716141732 Y
OC 4.49578996063 1.443080019685 4.49578769685 1.447080413386 N
OS 4.50185 1.443080019685
OC 4.50185 1.417019980315 4.50185 1.43005 Y
OS 4.462480019685 1.417019980315
OE
OB 4.5223 1.20666003937 I
OS 4.5223 1.236680019685
OS 4.592319980315 1.236680019685
OS 4.592319980315 1.20666003937
OS 4.5223 1.20666003937
OE
OB 4.61016003937 1.33161003937 I
OC 4.61016003937 1.33161003937 4.600280019685 1.33161003937 Y
OE
OB 4.61996003937 1.2989 I
OC 4.61996003937 1.32496003937 4.61996003937 1.311930019685 Y
OS 4.62603996063 1.32496003937
OC 4.62996003937 1.329719980315 4.626034251969 1.328958956693 N
OC 4.629780019685 1.331580019685 4.639651279528 1.331596653543 Y
OS 4.629780019685 1.33161003937
OC 4.649519980315 1.33161003937 4.63965 1.33161003937 Y
OS 4.649519980315 1.331580019685
OC 4.64933996063 1.329719980315 4.639648720472 1.331596653543 Y
OC 4.65326003937 1.32496003937 4.653265748031 1.328958956693 N
OS 4.659330019685 1.32496003937
OC 4.659330019685 1.2989 4.659330019685 1.311930019685 Y
OS 4.61996003937 1.2989
OE
OB 4.6889 1.4891 I
OC 4.6889 1.4891 4.679019980315 1.4891 Y
OE
OB 4.6987 1.4564 I
OC 4.6987 1.48243996063 4.6987 1.469419980315 Y
OS 4.704769980315 1.48243996063
OC 4.7087 1.48721003937 4.704772145669 1.486442125984 N
OC 4.708519980315 1.4891 4.718391240157 1.489086712598 Y
OC 4.72826003937 1.4891 4.718390059055 1.4891 Y
OC 4.728080019685 1.48721003937 4.718388681102 1.489086712598 Y
OC 4.73201003937 1.48243996063 4.732007775591 1.486442125984 N
OS 4.738069980315 1.48243996063
OC 4.738069980315 1.4564 4.738069980315 1.469419980315 Y
OS 4.6987 1.4564
OE
OB 4.71838996063 1.3611 I
OC 4.71838996063 1.38086003937 4.71838996063 1.370980019685 Y
OC 4.720280019685 1.380669980315 4.718351377953 1.370983858268 Y
OC 4.72503996063 1.3846 4.721041141732 1.384595669291 N
OS 4.72503996063 1.390669980315
OC 4.7511 1.390669980315 4.738069980315 1.390669980315 Y
OS 4.7511 1.3513
OC 4.72503996063 1.3513 4.738069980315 1.3513 Y
OS 4.72503996063 1.35736003937
OC 4.720280019685 1.36128996063 4.721041141732 1.357364271654 N
OC 4.71838996063 1.3611 4.718351968504 1.370976181102 Y
OE
OB 4.728269980315 1.41035 I
OC 4.728269980315 1.41035 4.71838996063 1.41035 Y
OE
OB 6.190030019685 2.094 I
OC 6.190030019685 2.094 5.99 2.094 Y
OE
OB 5.974969980315 1.045 I
OC 5.984369980315 1.1056 6.174999507874 1.045001377953 Y
OC 5.97846003937 1.12348996063 6.008502165354 1.123493208661 Y
OS 5.97846003937 1.1235
OC 6.00696003937 1.1535 6.008499507874 1.1235 Y
OC 6.175 1.245030019685 6.175000098425 1.045012598425 Y
OC 6.375030019685 1.045 6.175 1.045 Y
OC 6.362830019685 0.97621003937 6.174992913386 1.045 Y
OC 6.365 0.96501003937 6.334998523622 0.965007480315 Y
OS 6.365 0.965
OC 6.342730019685 0.93601003937 6.334996161417 0.965 Y
OC 6.175 0.844969980315 6.174999901575 1.045000984252 Y
OC 5.974969980315 1.045 6.175 1.045 Y
OE
OB 6.1856 2.230719980315 I
OS 6.1856 2.29076003937
OS 6.213619980315 2.29076003937
OS 6.213619980315 2.230719980315
OS 6.1856 2.230719980315
OE
OB 6.222480019685 2.178319980315 I
OS 6.222480019685 2.22536003937
OS 6.2425 2.22536003937
OS 6.2425 2.178319980315
OS 6.222480019685 2.178319980315
OE
OB 6.424580019685 3.34448996063 I
OC 6.424580019685 3.34448996063 6.34055 3.34448996063 Y
OE
OB 6.424580019685 3.67518996063 I
OC 6.424580019685 3.67518996063 6.34055 3.67518996063 Y
OE
OB 6.297280019685 2.178319980315 I
OS 6.297280019685 2.22536003937
OS 6.3173 2.22536003937
OS 6.3173 2.178319980315
OS 6.297280019685 2.178319980315
OE
OB 6.474919980315 0.65353996063 I
OC 6.474919980315 0.65353996063 6.40038996063 0.65353996063 Y
OE
OB 6.474919980315 4.17835 I
OC 6.474919980315 4.17835 6.40038996063 4.17835 Y
OE
OB 6.383980019685 2.07663996063 I
OS 6.383980019685 2.09266003937
OS 6.437019980315 2.09266003937
OS 6.437019980315 2.07663996063
OS 6.383980019685 2.07663996063
OE
OB 6.383980019685 2.102219980315 I
OS 6.383980019685 2.11826003937
OS 6.437019980315 2.11826003937
OS 6.437019980315 2.102219980315
OS 6.383980019685 2.102219980315
OE
SE
P 4.31 4.065 6 P 0 8 0;1=0
P 4.31 4.115 6 P 0 8 0;1=0
P 4.61 2.3 6 P 0 8 0;1=0
P 4.50185 2.05996004 4 P 0 8 0;1=1
P 4.49 2.275 6 P 0 8 0;1=0
P 4.435 2.315 6 P 0 8 0;1=0
P 4.49 2.325 6 P 0 8 0;1=0
P 4.435 2.365 6 P 0 8 0;1=0
P 3.655 2.465 6 P 0 8 0;1=0
P 3.125 1.605 6 P 0 8 0;1=0
P 3.65 2.68 6 P 0 8 0;1=2
P 3.12 2.645 6 P 0 8 0;1=2
P 4.1869 2.09933002 4 P 0 8 0;1=1
P 3.765 2.69 6 P 0 8 0;1=0
P 4.50185 1.50878996 4 P 0 8 0;1=1
P 4.3 3.865 4 P 0 8 0;1=3
P 3.36525 3.305 3 P 0 8 0;1=4
P 3.37 3.44 4 P 0 8 0;1=3
P 4.795 0.925 4 P 0 8 0;1=3
P 4.08 3.27 4 P 0 8 0;1=3
P 3.95 3.82 4 P 0 8 0;1=3
P 3.746 1.782 4 P 0 8 0;1=3
P 4.06878996 1.58753002 4 P 0 8 0;1=1
P 4.205 0.82 4 P 0 8 0;1=3
P 3.82286004 0.86213996 6 P 0 8 0;1=0
P 3.705 0.84 4 P 0 8 0;1=3
P 0.496 2.13455 6 P 0 8 0;1=0
P 0.528 2.72 6 P 0 8 0;1=0
P 0.575 1.015 6 P 0 8 0;1=0
P 0.48956998 1.53618996 6 P 0 8 0;1=0
P 4.65933002 1.98121998 4 P 0 8 0;1=1
P 4.06878996 1.90248002 4 P 0 8 0;1=1
P 4.50185 1.39066998 4 P 0 8 0;1=1
P 4.06878996 2.1387 4 P 0 8 0;1=1
P 4.22626998 2.05996004 4 P 0 8 0;1=1
P 3.95066998 2.05996004 4 P 0 8 0;1=1
P 4.22626998 2.02058996 4 P 0 8 0;1=1
P 4.26563996 2.09933002 4 P 0 8 0;1=1
P 4.26563996 2.05996004 4 P 0 8 0;1=1
P 4.50185 1.90248002 4 P 0 8 0;1=1
P 4.73806998 2.09933002 4 P 0 8 0;1=1
P 4.02941998 2.02058996 4 P 0 8 0;1=1
P 4.50185 1.86311004 4 P 0 8 0;1=1
P 4.6987 2.05996004 4 P 0 8 0;1=1
P 4.61996004 1.94185 4 P 0 8 0;1=1
P 4.61996004 1.98121998 4 P 0 8 0;1=1
P 4.26563996 2.02058996 4 P 0 8 0;1=1
P 4.61996004 1.90248002 4 P 0 8 0;1=1
P 4.58058996 1.98121998 4 P 0 8 0;1=1
P 4.54121998 2.02058996 4 P 0 8 0;1=1
P 4.34436998 2.09933002 4 P 0 8 0;1=1
P 4.06878996 2.09933002 4 P 0 8 0;1=5
P 4.6987 1.50878996 4 P 0 8 0;1=1
P 4.54121998 1.98121998 4 P 0 8 0;1=1
P 4.06878996 2.05996004 4 P 0 8 0;1=1
P 4.65933002 1.50878996 4 P 0 8 0;1=1
P 3.95066998 2.09933002 4 P 0 8 0;1=1
P 4.61996004 1.54816004 4 P 0 8 0;1=1
P 3.99005 2.09933002 4 P 0 8 0;1=5
P 4.58058996 1.54816004 4 P 0 8 0;1=1
P 4.6987 1.94185 4 P 0 8 0;1=1
P 4.50185 2.02058996 4 P 0 8 0;1=1
P 4.46248002 2.02058996 4 P 0 8 0;1=1
P 4.42311004 1.98121998 4 P 0 8 0;1=1
P 4.46248002 1.94185 4 P 0 8 0;1=1
P 4.38373996 1.86311004 4 P 0 8 0;1=1
P 4.38373996 1.82373996 4 P 0 8 0;1=1
P 4.46248002 1.98121998 4 P 0 8 0;1=1
P 4.10816004 1.94185 4 P 0 8 0;1=1
P 4.02941998 1.98121998 4 P 0 8 0;1=1
P 4.58058996 2.17806998 4 P 0 8 0;1=1
P 4.73806998 1.90248002 4 P 0 8 0;1=1
P 4.54121998 2.1387 4 P 0 8 0;1=1
P 4.10816004 2.02058996 4 P 0 8 0;1=1
P 4.50185 2.1387 4 P 0 8 0;1=1
P 3.99005 1.94185 4 P 0 8 0;1=1
P 4.02941998 1.94185 4 P 0 8 0;1=1
P 4.50185 2.09933002 4 P 0 8 0;1=1
P 4.14753002 2.02058996 4 P 0 8 0;1=1
P 4.61996004 2.17806998 4 P 0 8 0;1=1
P 4.02941998 1.86311004 4 P 0 8 0;1=1
P 4.06878996 1.43005 4 P 0 8 0;1=1
P 4.54121998 1.54816004 4 P 0 8 0;1=1
P 4.26563996 1.50878996 4 P 0 8 0;1=1
P 4.1869 1.94185 4 P 0 8 0;1=1
P 4.14753002 1.46941998 4 P 0 8 0;1=1
P 4.1869 1.46941998 4 P 0 8 0;1=1
P 4.1869 2.1387 4 P 0 8 0;1=1
P 4.6987 1.43005 4 P 0 8 0;1=1
P 4.10816004 1.39066998 4 P 0 8 0;1=1
P 4.65933002 1.43005 4 P 0 8 0;1=1
P 4.14753002 1.39066998 4 P 0 8 0;1=1
P 4.61996004 1.43005 4 P 0 8 0;1=1
P 4.10816004 1.43005 4 P 0 8 0;1=1
P 4.58058996 1.43005 4 P 0 8 0;1=1
P 4.14753002 1.43005 4 P 0 8 0;1=1
P 4.1869 1.43005 4 P 0 8 0;1=1
P 4.22626998 1.43005 4 P 0 8 0;1=1
P 4.54121998 1.46941998 4 P 0 8 0;1=1
P 4.22626998 1.39066998 4 P 0 8 0;1=1
P 4.50185 1.46941998 4 P 0 8 0;1=1
P 4.26563996 1.39066998 4 P 0 8 0;1=1
P 4.61996004 1.46941998 4 P 0 8 0;1=1
P 4.26563996 1.31193002 4 P 0 8 0;1=1
P 4.61996004 1.50878996 4 P 0 8 0;1=1
P 4.34436998 1.31193002 4 P 0 8 0;1=1
P 4.58058996 1.46941998 4 P 0 8 0;1=1
P 4.34436998 1.3513 4 P 0 8 0;1=1
P 4.54121998 1.50878996 4 P 0 8 0;1=1
P 4.34436998 1.39066998 4 P 0 8 0;1=1
P 4.1869 1.50878996 4 P 0 8 0;1=1
P 4.46248002 1.50878996 4 P 0 8 0;1=1
P 4.22626998 1.50878996 4 P 0 8 0;1=1
P 4.26563996 1.43005 4 P 0 8 0;1=5
P 4.26563996 1.46941998 4 P 0 8 0;1=1
P 4.38373996 1.39066998 4 P 0 8 0;1=1
P 4.38373996 1.43005 4 P 0 8 0;1=1
P 4.54121998 1.31193002 4 P 0 8 0;1=1
P 4.49876004 1.31501998 4 P 0 8 0;1=1
P 4.34436998 1.98121998 4 P 0 8 0;1=1
P 4.57843996 1.35345 4 P 0 8 0;1=1
P 3.9113 1.3513 4 P 0 8 0;1=1
P 4.54121998 1.3513 4 P 0 8 0;1=1
P 3.95066998 1.3513 4 P 0 8 0;1=1
P 4.45938996 1.35438996 4 P 0 8 0;1=1
P 3.99 1.31188002 4 P 0 8 0;1=1
P 4.46248002 1.39066998 4 P 0 8 0;1=1
P 4.65933002 1.3513 4 P 0 8 0;1=1
P 3.99 1.35125 4 P 0 8 0;1=1
P 4.61996004 1.3513 4 P 0 8 0;1=1
P 4.6987 1.86311004 4 P 0 8 0;1=1
P 4.46248002 2.05996004 4 P 0 8 0;1=1
P 4.06873996 1.31188002 4 P 0 8 0;1=1
P 4.65933002 1.82373996 4 P 0 8 0;1=1
P 4.42311004 2.05996004 4 P 0 8 0;1=1
P 4.10811004 1.31188002 4 P 0 8 0;1=1
P 4.58058996 1.39066998 4 P 0 8 0;1=1
P 4.02941998 1.39066998 4 P 0 8 0;1=1
P 4.54121998 1.39066998 4 P 0 8 0;1=1
P 4.06878996 1.39066998 4 P 0 8 0;1=1
P 4.73806998 1.78436998 4 P 0 8 0;1=1
P 4.73806998 1.31193002 4 P 0 8 0;1=1
P 4.1869 1.31193002 4 P 0 8 0;1=1
P 4.73806998 1.70563996 4 P 0 8 0;1=1
P 4.6987 1.31193002 4 P 0 8 0;1=1
P 4.22626998 1.31193002 4 P 0 8 0;1=1
P 4.10816004 1.3513 4 P 0 8 0;1=1
P 4.14753002 1.3513 4 P 0 8 0;1=1
P 4.6987 1.39066998 4 P 0 8 0;1=1
P 4.1869 1.3513 4 P 0 8 0;1=1
P 4.65933002 1.39066998 4 P 0 8 0;1=1
P 4.22626998 1.3513 4 P 0 8 0;1=1
P 4.73806998 2.17806998 4 P 0 8 0;1=1
P 4.73806998 2.1387 4 P 0 8 0;1=1
P 4.58058996 2.09933002 4 P 0 8 0;1=1
P 4.54121998 2.09933002 4 P 0 8 0;1=1
P 4.58058996 1.86311004 4 P 0 8 0;1=1
P 4.65933002 2.05996004 4 P 0 8 0;1=1
P 4.58058996 2.05996004 4 P 0 8 0;1=1
P 4.54121998 1.90248002 4 P 0 8 0;1=1
P 4.58058996 2.02058996 4 P 0 8 0;1=1
P 4.22626998 1.98121998 4 P 0 8 0;1=1
P 4.26563996 1.94185 4 P 0 8 0;1=1
P 4.10816004 1.98121998 4 P 0 8 0;1=1
P 4.14753002 1.98121998 4 P 0 8 0;1=1
P 4.61996004 2.1387 4 P 0 8 0;1=1
P 4.6987 1.70563996 4 P 0 8 0;1=1
P 4.6987 1.66626998 4 P 0 8 0;1=1
P 1.45 3.59 6 P 0 8 0;1=0
P 1.56 3.165 6 P 0 8 0;1=2
P 1.56 3.205 6 P 0 8 0;1=0
P 0.72 3.463 6 P 0 8 0;1=2
P 0.42326004 3.4315 7 P 0 8 0;1=6
P 0.40553996 3.4008 7 P 0 8 0;1=6
P 0.2815 3.4315 7 P 0 8 0;1=6
P 0.26378002 3.4008 7 P 0 8 0;1=6
P 0.71 3.305 4 P 0 8 0;1=3
P 1.14 3.52 6 P 0 8 0;1=0
P 1.245 3.52 6 P 0 8 0;1=0
P 4.705 3.95 3 P 0 8 0;1=4
P 4.705 3.91 6 P 0 8 0;1=2
P 1.566 2.95 6 P 0 8 0;1=0
P 1.045 3.77 6 P 0 8 0;1=2
P 1.515 3.58 6 P 0 8 0;1=2
P 6.145 4.035 6 P 0 8 0;1=0
P 1.37 3.64 6 P 0 8 0;1=2
P 1.667 3.438 6 P 0 8 0;1=2
P 1.591 3.546 6 P 0 8 0;1=2
P 1.13 3.445 6 P 0 8 0;1=2
P 0.95 3.445 6 P 0 8 0;1=2
P 2.19 3.488 6 P 0 8 0;1=2
P 2.192 3.388 6 P 0 8 0;1=2
P 1.41916004 3.33916004 6 P 0 8 0;1=2
P 1.407 3.2 6 P 0 8 0;1=2
P 1.495 3.11033996 6 P 0 8 0;1=2
P 1.535 3.105 4 P 0 8 0;1=3
P 1.15253002 3.06246998 6 P 0 8 0;1=2
P 0.95 3.215 6 P 0 8 0;1=2
P 0.945 3.125 6 P 0 8 0;1=2
P 1.175 2.9 6 P 0 8 0;1=2
P 1.025 3.02 6 P 0 8 0;1=2
P 5.275 3.891 6 P 0 8 0;1=0
P 5.275 3.931 6 P 0 8 0;1=2
P 5.275 3.971 6 P 0 8 0;1=0
P 5.321 3.99 6 P 0 8 0;1=2
P 5.762 3.425 5 P 0 8 0;1=7
P 5.567 3.203 6 P 0 8 0;1=2
P 5.617 3.203 6 P 0 8 0;1=0
P 5.62 3.316 6 P 0 8 0;1=2
P 5.625 3.261 6 P 0 8 0;1=0
P 5.625 3.361 6 P 0 8 0;1=2
P 5.6 3.421 6 P 0 8 0;1=0
P 5.552 3.71141004 5 P 0 8 0;1=8
P 5.552 3.74683996 5 P 0 8 0;1=8
P 5.552 3.78226998 5 P 0 8 0;1=8
P 5.552 3.67596998 5 P 0 8 0;1=8
P 5.52 3.78226998 5 P 0 8 0;1=8
P 5.52 3.74683996 5 P 0 8 0;1=8
P 5.52 3.71141004 5 P 0 8 0;1=8
P 5.52 3.67596998 5 P 0 8 0;1=8
P 0.978 3.918 4 P 0 8 0;1=3
P 0.928 3.961 6 P 0 8 0;1=2
P 0.968 3.961 6 P 0 8 0;1=2
P 0.968 4.021 6 P 0 8 0;1=2
P 0.928 4.021 6 P 0 8 0;1=0
P 0.928 4.081 6 P 0 8 0;1=2
P 0.968 4.081 6 P 0 8 0;1=0
P 0.928 4.141 6 P 0 8 0;1=0
P 0.968 4.141 6 P 0 8 0;1=2
P 0.603 3.951 6 P 0 8 0;1=0
P 0.643 3.956 6 P 0 8 0;1=2
P 0.603 4.011 6 P 0 8 0;1=2
P 0.643 4.016 6 P 0 8 0;1=0
P 0.603 4.071 6 P 0 8 0;1=0
P 0.643 4.076 6 P 0 8 0;1=2
P 0.603 4.131 6 P 0 8 0;1=2
P 0.643 4.136 6 P 0 8 0;1=0
P 0.854 3.942 6 P 0 8 0;1=2
P 0.807 3.942 6 P 0 8 0;1=2
P 0.76 3.942 6 P 0 8 0;1=2
P 0.713 3.942 6 P 0 8 0;1=2
P 0.76 4.042 6 P 0 8 0;1=2
P 0.76 3.992 6 P 0 8 0;1=2
P 0.713 3.992 6 P 0 8 0;1=2
P 0.713 4.042 6 P 0 8 0;1=2
P 0.713 4.092 6 P 0 8 0;1=2
P 0.76 4.092 6 P 0 8 0;1=2
P 0.807 4.092 6 P 0 8 0;1=2
P 0.807 4.042 6 P 0 8 0;1=2
P 0.807 3.992 6 P 0 8 0;1=2
P 0.854 3.992 6 P 0 8 0;1=2
P 0.854 4.042 6 P 0 8 0;1=2
P 0.854 4.092 6 P 0 8 0;1=2
P 0.74 1.005 6 P 0 8 0;1=0
P 0.79 1.005 6 P 0 8 0;1=0
P 0.84 1.005 6 P 0 8 0;1=0
P 1.568 3.011 6 P 0 8 0;1=0
P 1.738 3.241 6 P 0 8 0;1=0
P 1.765 2.9 6 P 0 8 0;1=0
P 1.78 3.095 6 P 0 8 0;1=0
P 1.795 2.946 6 P 0 8 0;1=0
P 5.2 0.87 6 P 0 8 0;1=0
P 4.47 3.21998002 6 P 0 8 0;1=0
P 4.385 3.645 6 P 0 8 0;1=0
P 0.78 3.305 4 P 0 8 0;1=3
P 1.03 3.515 6 P 0 8 0;1=0
P 1.19 3.52 6 P 0 8 0;1=0
P 0.95 2.915 4 P 0 8 0;1=3
P 0.945 2.99 4 P 0 8 0;1=3
P 0.885 3.03 4 P 0 8 0;1=3
P 0.875 2.955 4 P 0 8 0;1=3
P 0.795 3.085 4 P 0 8 0;1=3
P 0.55 3.36 6 P 0 8 0;1=0
P 0.3701 3.4008 7 P 0 8 0;1=6
P 0.55 3.554 6 P 0 8 0;1=0
P 0.31693996 3.4315 7 P 0 8 0;1=6
P 5.92 1.57063002 6 P 0 8 0;1=0
P 6.22 1.57 6 P 0 8 0;1=0
P 5.92 1.46 6 P 0 8 0;1=0
P 6.22 1.465 6 P 0 8 0;1=0
P 5.92 1.68 6 P 0 8 0;1=0
P 6.22035 1.67063002 6 P 0 8 0;1=0
P 5.92 1.78 6 P 0 8 0;1=0
P 6.22 1.755 6 P 0 8 0;1=0
P 6.09423996 4.13778996 6 P 0 8 0;1=0
P 3.51 3.08 6 P 0 8 0;1=0
P 1.025 2.9 6 P 0 8 0;1=2
P 4.42311004 1.94185 4 P 0 8 0;1=1
P 3.46 3.065 6 P 0 8 0;1=0
P 1.125 2.9 6 P 0 8 0;1=2
P 4.42311004 1.90248002 4 P 0 8 0;1=1
P 3.035 1.64 6 P 0 8 0;1=2
P 3.445 2.65 4 P 0 8 0;1=3
P 1.1288 0.7302 5 P 0 8 0;1=7
P 3.075 1.605 6 P 0 8 0;1=2
P 3.365 2.95 3 P 0 8 0;1=4
P 0.755 0.62 4 P 0 8 0;1=3
P 0.715 0.77 6 P 0 8 0;1=0
P 0.83 3.445 6 P 0 8 0;1=0
P 0.795 3.485 6 P 0 8 0;1=0
P 0.83 3.525 6 P 0 8 0;1=0
P 0.951 3.519 6 P 0 8 0;1=0
P 0.82951004 3.2794 6 P 0 8 0;1=0
P 0.79 3.155 6 P 0 8 0;1=0
P 0.78635 3.24491998 6 P 0 8 0;1=0
P 1.26 3.18 6 P 0 8 0;1=0
P 1.295 3.28 6 P 0 8 0;1=0
P 1.075 3.02 6 P 0 8 0;1=0
P 1.125 3.02 6 P 0 8 0;1=0
P 1.073 3.825 4 P 0 8 0;1=9
P 0.703 3.575 4 P 0 8 0;1=9
P 0.35238002 3.4315 7 P 0 8 0;1=6
P 0.33466004 3.4008 7 P 0 8 0;1=6
P 0.735 3.575 4 P 0 8 0;1=9
P 1.105 3.825 4 P 0 8 0;1=9
P 0.38781998 3.4315 7 P 0 8 0;1=6
P 0.29921998 3.4008 7 P 0 8 0;1=6
P 0.995 3.7 4 P 0 8 0;1=3
P 4.285 3.46 6 P 0 8 0;1=2
P 2.15 3.438 6 P 0 8 0;1=0
P 2.05 3.538 6 P 0 8 0;1=0
P 2.05 3.488 6 P 0 8 0;1=0
P 1.29 3.215 6 P 0 8 0;1=2
P 1.0541 3.185 6 P 0 8 0;1=0
P 1.3 3.49663996 6 P 0 8 0;1=2
P 1.04018996 3.47425 6 P 0 8 0;1=2
P 4.205 3.66 6 P 0 8 0;1=0
P 0.975 3.41 6 P 0 8 0;1=2
P 4.225 3.545 6 P 0 8 0;1=0
P 1.015 3.41 6 P 0 8 0;1=2
P 3.95 3.6 6 P 0 8 0;1=0
P 0.835 3.6 6 P 0 8 0;1=2
P 3.95 3.7 6 P 0 8 0;1=0
P 0.915 3.595 6 P 0 8 0;1=2
P 4.1184 3.5362 6 P 0 8 0;1=2
P 4.085 3.11 6 P 0 8 0;1=0
P 4.51 3.065 6 P 0 8 0;1=2
P 4.33381998 3.60466004 6 P 0 8 0;1=0
P 4.34 3.28 6 P 0 8 0;1=2
P 4.335 3.665 6 P 0 8 0;1=0
P 4.09 3.71338996 6 P 0 8 0;1=0
P 3.38 1.025 6 P 0 8 0;1=2
P 4.585 0.865 6 P 0 8 0;1=0
P 0.62 3.235 6 P 0 8 0;1=2
P 3.925 3.239 6 P 0 8 0;1=0
P 0.825 3.39 6 P 0 8 0;1=2
P 0.795 3.4179 6 P 0 8 0;1=2
P 3.795 3.758 6 P 0 8 0;1=0
P 3.62 1.28 6 P 0 8 0;1=2
P 5.195 0.755 6 P 0 8 0;1=0
P 4.96 0.85 6 P 0 8 0;1=2
P 0.66 3.185 6 P 0 8 0;1=2
P 3.62 1.235 6 P 0 8 0;1=2
P 5.195 0.815 6 P 0 8 0;1=0
P 4.937 0.79161004 6 P 0 8 0;1=2
P 0.66 3.235 6 P 0 8 0;1=2
P 4.205 3.81 6 P 0 8 0;1=2
P 5.814 2.821 5 P 0 8 0;1=7
P 4.19 3.735 6 P 0 8 0;1=2
P 5.814 2.721 5 P 0 8 0;1=7
P 3.895 3.7 6 P 0 8 0;1=2
P 5.815 3.021 5 P 0 8 0;1=7
P 4.135 3.735 6 P 0 8 0;1=2
P 5.814 2.621 5 P 0 8 0;1=7
P 2.3 3.475 6 P 0 8 0;1=2
P 5.045 3.405 6 P 0 8 0;1=2
P 6.33 2.67 5 P 0 8 0;1=7
P 1.35 3.12 6 P 0 8 0;1=2
P 2.255 3.475 6 P 0 8 0;1=2
P 5.09 3.405 6 P 0 8 0;1=2
P 6.33 2.865 6 P 0 8 0;1=0
P 1.46 3.34 6 P 0 8 0;1=2
P 4.575 2.235 6 P 0 8 0;1=2
P 4.50185 1.94185 4 P 0 8 0;1=1
P 4.705 0.825 6 P 0 8 0;1=0
P 4.575 2.275 6 P 0 8 0;1=2
P 4.38373996 1.98121998 4 P 0 8 0;1=1
P 4.755 0.825 6 P 0 8 0;1=0
P 1.26 0.72 6 P 0 8 0;1=0
P 4.6987 1.82373996 4 P 0 8 0;1=1
P 0.842 0.75 6 P 0 8 0;1=0
P 4.73806998 1.82373996 4 P 0 8 0;1=1
P 4.10816004 1.90248002 4 P 0 8 0;1=5
P 3.73648996 1.85735 6 P 0 8 0;1=2
P 4.10816004 1.82373996 4 P 0 8 0;1=1
P 4.345 3.02 6 P 0 8 0;1=2
P 4.075 3.005 6 P 0 8 0;1=2
P 3.925 3.291 6 P 0 8 0;1=0
P 4.14753002 1.82373996 4 P 0 8 0;1=1
P 4.39 3.02 6 P 0 8 0;1=2
P 4.13 3.005 6 P 0 8 0;1=2
P 3.795 3.81 6 P 0 8 0;1=0
P 4.615 3.11 6 P 0 8 0;1=2
P 4.6987 1.90248002 4 P 0 8 0;1=1
P 4.4 3.325 6 P 0 8 0;1=0
P 4.615 2.68408996 6 P 0 8 0;1=2
P 4.15 2.468 6 P 0 8 0;1=2
P 6.22 1.415 6 P 0 8 0;1=0
P 4.685 2.7 6 P 0 8 0;1=2
P 4.209 2.468 6 P 0 8 0;1=2
P 4.34436998 2.1387 4 P 0 8 0;1=1
P 6.22 1.516 6 P 0 8 0;1=0
P 4.975 2.26 6 P 0 8 0;1=2
P 4.093 2.468 6 P 0 8 0;1=2
P 6.22 1.62 6 P 0 8 0;1=0
P 4.925 2.26 6 P 0 8 0;1=0
P 4.037 2.468 6 P 0 8 0;1=2
P 6.22 1.815 6 P 0 8 0;1=0
P 5.92 1.41 6 P 0 8 0;1=0
P 5.09 2.155 6 P 0 8 0;1=2
P 3.801 2.468 6 P 0 8 0;1=2
P 4.10816004 2.09933002 4 P 0 8 0;1=1
P 5.92 1.515 6 P 0 8 0;1=0
P 5.135 2.155 6 P 0 8 0;1=2
P 3.86 2.468 6 P 0 8 0;1=2
P 4.14753002 2.09933002 4 P 0 8 0;1=1
P 5.92 1.63 6 P 0 8 0;1=0
P 5.115 2.065 6 P 0 8 0;1=2
P 3.919 2.468 6 P 0 8 0;1=2
P 5.92 1.73 6 P 0 8 0;1=0
P 5.13 2.105 6 P 0 8 0;1=2
P 3.978 2.468 6 P 0 8 0;1=2
P 4.685 2.645 6 P 0 8 0;1=2
P 4.1 3.38 6 P 0 8 0;1=0
P 4.53 2.5 6 P 0 8 0;1=2
P 3.9 3.385 6 P 0 8 0;1=0
P 4.485 3.115 6 P 0 8 0;1=0
P 4.575 2.374 6 P 0 8 0;1=2
P 4.485 2.5 6 P 0 8 0;1=2
P 4.29441998 3.10075 6 P 0 8 0;1=0
P 4.61 2.345 6 P 0 8 0;1=2
P 4.54 3.125 6 P 0 8 0;1=0
P 4.085 3.21998002 6 P 0 8 0;1=0
P 4.35 2.505 6 P 0 8 0;1=2
P 5.365 0.79 6 P 0 8 0;1=0
P 5.365 0.845 6 P 0 8 0;1=0
P 4.0661 3.5341 6 P 0 8 0;1=0
P 3.83 3.466 5 P 0 8 0;1=7
P 4.35143002 3.06643002 6 P 0 8 0;1=2
P 3.7 3.325 6 P 0 8 0;1=0
P 3.5825 3.4005 3 P 0 8 0;1=4
P 4.33 3.1432 6 P 0 8 0;1=2
P 3.83 3.235 6 P 0 8 0;1=0
P 4.085 3.165 6 P 0 8 0;1=2
P 3.415 3.335 3 P 0 8 0;1=4
P 0.74 1.3 6 P 0 8 0;1=2
P 1.26 0.62 5 P 0 8 0;1=7
P 0.785 0.8225 6 P 0 8 0;1=2
P 0.695 1.3 6 P 0 8 0;1=2
P 1.26 0.67 5 P 0 8 0;1=7
P 0.76321004 0.783 6 P 0 8 0;1=2
P 3.32 3.015 4 P 0 8 0;1=3
P 3.24 3.01 4 P 0 8 0;1=3
P 0.606 1.57 6 P 0 8 0;1=0
P 0.835 1.73 6 P 0 8 0;1=0
P 0.355 3.27 6 P 0 8 0;1=0
P 0.28 3.27 6 P 0 8 0;1=0
P 0.13 3.187 6 P 0 8 0;1=0
P 0.69023002 1.98523996 6 P 0 8 0;1=2
P 0.125 2.195 6 P 0 8 0;1=0
P 0.69 1.93 6 P 0 8 0;1=2
P 0.125 2.145 6 P 0 8 0;1=0
P 0.69 1.875 6 P 0 8 0;1=2
P 0.125 2.045 6 P 0 8 0;1=0
P 0.13 2.73326998 6 P 0 8 0;1=0
P 0.287 2.743 6 P 0 8 0;1=0
P 0.125 2.615 6 P 0 8 0;1=0
P 0.735 1.19 6 P 0 8 0;1=2
P 0.125 1.06 6 P 0 8 0;1=0
P 0.68 1.19 6 P 0 8 0;1=2
P 0.125 1.01 6 P 0 8 0;1=0
P 0.675 1.145 6 P 0 8 0;1=2
P 0.125 0.91 6 P 0 8 0;1=0
P 0.125 1.62 6 P 0 8 0;1=0
P 0.13 1.57 6 P 0 8 0;1=0
P 0.1362 1.4872 6 P 0 8 0;1=0
P 2.937 3.173 6 P 0 8 0;1=0
P 3.01 3.17 6 P 0 8 0;1=2
P 0.896 2.489 3 P 0 8 0;1=4
P 4.31168996 4.01168996 3 P 0 8 0;1=4
P 4.319 3.922 3 P 0 8 0;1=4
P 4.5 4.115 6 P 0 8 0;1=0
P 1.315 2.905 5 P 0 8 0;1=8
P 2.932 3.295 5 P 0 8 0;1=8
P 0.915 1.4 6 P 0 8 0;1=2
P 1.42 0.69535 5 P 0 8 0;1=7
P 4.5 4.165 6 P 0 8 0;1=0
P 1.36 2.905 5 P 0 8 0;1=8
P 2.896 3.301 5 P 0 8 0;1=8
P 0.965 1.4 6 P 0 8 0;1=2
P 1.4207 0.779 5 P 0 8 0;1=7
P 4.65933002 2.02058996 4 P 0 8 0;1=5
P 4.33 3.535 6 P 0 8 0;1=2
P 4.44 4.065 3 P 0 8 0;1=4
P 4.61996004 2.05996004 4 P 0 8 0;1=1
P 4.395 3.415 5 P 0 8 0;1=8
P 4.44 4.115 3 P 0 8 0;1=4
P 4.61996004 2.09933002 4 P 0 8 0;1=1
P 4.425 3.36088996 5 P 0 8 0;1=8
P 0.638 2.74 5 P 0 8 0;1=8
P 0.825 2.305 3 P 0 8 0;1=4
P 0.755 2.825 5 P 0 8 0;1=8
P 0.795 2.345 3 P 0 8 0;1=4
P 5.97613002 4.13778996 6 P 0 8 0;1=0
P 5.90748002 4.18725 6 P 0 8 0;1=0
P 4.06878996 2.02058996 4 P 0 8 0;1=1
P 0.905 1.935 6 P 0 8 0;1=0
P 3.99005 2.05996004 4 P 0 8 0;1=1
P 0.945 1.97 6 P 0 8 0;1=0
P 4.02941998 2.05996004 4 P 0 8 0;1=1
P 0.905 1.885 6 P 0 8 0;1=0
P 0.63 2.15 6 P 0 8 0;1=2
P 3.95066998 2.02058996 4 P 0 8 0;1=1
P 0.985 2.185 6 P 0 8 0;1=0
P 0.287 2.62508002 6 P 0 8 0;1=2
P 0.43 2.555 6 P 0 8 0;1=0
P 3.95066998 1.98121998 4 P 0 8 0;1=1
P 0.63 2.105 6 P 0 8 0;1=2
P 0.99 2.015 6 P 0 8 0;1=2
P 0.242 2.62508002 6 P 0 8 0;1=0
P 3.99005 1.98121998 4 P 0 8 0;1=1
P 0.63 2.06 6 P 0 8 0;1=2
P 0.99 1.975 6 P 0 8 0;1=2
P 4.02941998 1.82373996 4 P 0 8 0;1=1
P 0.935 1.3 6 P 0 8 0;1=0
P 3.95066998 1.90248002 4 P 0 8 0;1=1
P 0.87 1.255 6 P 0 8 0;1=0
P 3.95066998 1.86311004 4 P 0 8 0;1=1
P 0.935 1.25 6 P 0 8 0;1=0
P 4.06878996 1.94185 4 P 0 8 0;1=1
P 0.92 1.73 6 P 0 8 0;1=0
P 0.281 1.48798002 6 P 0 8 0;1=2
P 4.06878996 1.86311004 4 P 0 8 0;1=1
P 0.985 1.655 6 P 0 8 0;1=0
P 0.371 1.48798002 6 P 0 8 0;1=2
P 4.06878996 1.82373996 4 P 0 8 0;1=1
P 0.985 1.59 6 P 0 8 0;1=0
P 0.236 1.48798002 6 P 0 8 0;1=2
P 0.345 3.09 6 P 0 8 0;1=2
P 3.84091004 2.00091004 6 P 0 8 0;1=0
P 0.99 1.885 6 P 0 8 0;1=2
P 0.395 3.09 6 P 0 8 0;1=2
P 3.87193002 2.09933002 4 P 0 8 0;1=5
P 0.99 2.065 6 P 0 8 0;1=2
P 0.445 3.09 6 P 0 8 0;1=0
P 3.9113 2.09933002 4 P 0 8 0;1=1
P 0.975 2.14 6 P 0 8 0;1=2
P 0.53 2.005 6 P 0 8 0;1=0
P 0.552 2.535 6 P 0 8 0;1=0
P 0.455 1.825 6 P 0 8 0;1=0
P 0.16038996 1.85433002 8 P 0 8 0;1=10
P 0.46 2.195 6 P 0 8 0;1=0
P 0.16038996 2.4252 8 P 0 8 0;1=10
P 0.445 0.735 6 P 0 8 0;1=0
P 0.16038996 0.7126 8 P 0 8 0;1=10
P 0.455 1.0439 6 P 0 8 0;1=0
P 0.16038996 1.28346004 8 P 0 8 0;1=10
P 0.535 1.835 6 P 0 8 0;1=0
P 0.532 2.40186998 6 P 0 8 0;1=0
P 0.505 0.60228002 6 P 0 8 0;1=0
P 0.5374 1.26 6 P 0 8 0;1=0
P 0.48 2.005 6 P 0 8 0;1=0
P 0.485 2.525 6 P 0 8 0;1=0
P 0.515 0.835 6 P 0 8 0;1=0
P 0.475 1.405 6 P 0 8 0;1=0
P 6.335 0.965 6 P 0 8 0;1=0
P 6.335 1.02 6 P 0 8 0;1=0
P 6.335 1.08 6 P 0 8 0;1=0
P 2.085 3.017 5 P 0 8 0;1=7
P 2.135 3.017 5 P 0 8 0;1=7
P 2.185 3.017 5 P 0 8 0;1=7
P 6.0085 1.1235 6 P 0 8 0;1=0
P 2.22 3.3 5 P 0 8 0;1=7
P 5.8 1.048 4 P 0 8 0;1=3
P 4.34436998 2.02058996 4 P 0 8 0;1=1
P 5.285 2.99 5 P 0 8 0;1=8
P 3.125 3.075 6 P 0 8 0;1=2
P 4.34436998 2.17806998 4 P 0 8 0;1=1
P 2.017 3.279 4 P 0 8 0;1=3
P 0.636 2.915 4 P 0 8 0;1=3
P 4.38373996 2.17806998 4 P 0 8 0;1=1
P 2.97 3.105 6 P 0 8 0;1=0
P 5.91 2.785 6 P 0 8 0;1=0
P 5.91 2.615 5 P 0 8 0;1=7
P 5.91 2.915 6 P 0 8 0;1=0
P 5.91 2.715 6 P 0 8 0;1=0
P 0.54 2.135 6 P 0 8 0;1=2
P 0.67 1.09 6 P 0 8 0;1=0
P 4.61996004 1.66626998 4 P 0 8 0;1=1
P 0.45 2.13 6 P 0 8 0;1=2
P 4.6987 2.09933002 4 P 0 8 0;1=1
P 0.965 2.355 6 P 0 8 0;1=0
P 4.5806 1.70563996 4 P 0 8 0;1=1
P 0.735 1.125 6 P 0 8 0;1=0
P 0.48231998 2.6453 6 P 0 8 0;1=2
P 3.755 3.505 5 P 0 8 0;1=8
P 4.6987 2.1387 4 P 0 8 0;1=1
P 0.525 2.78 6 P 0 8 0;1=2
P 4.6 0.76 6 P 0 8 0;1=2
P 4.61996004 1.78436998 4 P 0 8 0;1=1
P 0.905 1.05 6 P 0 8 0;1=2
P 4.175 0.75 6 P 0 8 0;1=2
P 0.51765 0.966 3 P 0 8 0;1=4
P 2.078 0.8301 6 P 0 8 0;1=2
P 0.46 0.82 3 P 0 8 0;1=4
P 4.65933002 1.78436998 4 P 0 8 0;1=1
P 0.5413 1.525 6 P 0 8 0;1=0
P 4.61996004 1.70563996 4 P 0 8 0;1=1
P 0.625 1.005 6 P 0 8 0;1=2
P 4.65933002 1.70563996 4 P 0 8 0;1=1
P 0.935 1.105 6 P 0 8 0;1=0
P 0.4839 1.28311998 6 P 0 8 0;1=2
P 1.128 0.666 3 P 0 8 0;1=4
P 5.97613002 4.27558002 6 P 0 8 0;1=0
P 4.14753002 1.86311004 4 P 0 8 0;1=1
P 0.945 1.63 6 P 0 8 0;1=2
P 0.635 0.845 4 P 0 8 0;1=3
P 4.1869 1.86311004 4 P 0 8 0;1=1
P 0.975 1.72 6 P 0 8 0;1=2
P 0.644 0.7 4 P 0 8 0;1=3
P 0.555 0.59 6 P 0 8 0;1=0
P 3.935 3.91 5 P 0 8 0;1=7
P 0.835 1.885 6 P 0 8 0;1=2
P 3.885 3.91 5 P 0 8 0;1=7
P 0.835 1.93 6 P 0 8 0;1=2
P 3.985 3.91 5 P 0 8 0;1=7
P 0.835 1.78 6 P 0 8 0;1=2
P 0.645 1.295 4 P 0 8 0;1=3
P 4.1869 1.90248002 4 P 0 8 0;1=1
P 0.955 1.92 6 P 0 8 0;1=2
P 0.565 1.13 4 P 0 8 0;1=3
P 4.14753002 1.90248002 4 P 0 8 0;1=1
P 0.885 1.49 6 P 0 8 0;1=0
P 0.99 1.755 6 P 0 8 0;1=2
P 3.935 4 5 P 0 8 0;1=8
P 0.332 2.62508002 6 P 0 8 0;1=0
P 3.885 4 5 P 0 8 0;1=8
P 0.405 2.62 6 P 0 8 0;1=0
P 3.985 4 5 P 0 8 0;1=8
P 0.19 2.625 6 P 0 8 0;1=0
P 0.62 1.995 4 P 0 8 0;1=3
P 4.34436998 1.82373996 4 P 0 8 0;1=1
P 0.75 1.417 6 P 0 8 0;1=2
P 4.26563996 1.82373996 4 P 0 8 0;1=1
P 0.952 1.51 6 P 0 8 0;1=0
P 0.545 1.71 4 P 0 8 0;1=3
P 0.415 1.275 6 P 0 8 0;1=2
P 0.87 1.2 6 P 0 8 0;1=2
P 0.7558 4.19003996 5 P 0 8 0;1=7
P 3.98 4.185 5 P 0 8 0;1=8
P 0.465 1.33 6 P 0 8 0;1=2
P 0.87 1.3 6 P 0 8 0;1=2
P 0.705 4.19 5 P 0 8 0;1=7
P 4.03 4.185 5 P 0 8 0;1=8
P 0.41408996 1.32591004 6 P 0 8 0;1=2
P 0.89 1.105 6 P 0 8 0;1=2
P 0.805 4.205 6 P 0 8 0;1=0
P 3.93 4.185 5 P 0 8 0;1=8
P 0.647 2.517 4 P 0 8 0;1=3
P 4.22626998 1.82373996 4 P 0 8 0;1=1
P 0.939 1.552 6 P 0 8 0;1=2
P 0.575 2.265 4 P 0 8 0;1=3
P 4.22626998 1.86311004 4 P 0 8 0;1=1
P 0.957 2.275 6 P 0 8 0;1=0
P 4.168 4.24 5 P 0 8 0;1=8
P 0.855 4.205 5 P 0 8 0;1=8
P 0.15 2.79 6 P 0 8 0;1=0
P 0.326 1.487 6 P 0 8 0;1=2
P 0.09 2.86 6 P 0 8 0;1=0
P 0.9 4.205 5 P 0 8 0;1=8
P 4.22336998 4.24 5 P 0 8 0;1=8
P 0.416 1.48798002 6 P 0 8 0;1=2
P 0.09 2.79 6 P 0 8 0;1=0
P 0.98 4.2 5 P 0 8 0;1=8
P 4.14 4.19 5 P 0 8 0;1=8
P 0.191 1.48798002 6 P 0 8 0;1=2
P 4.10463002 3.83 5 P 0 8 0;1=7
P 0.33 3.145 6 P 0 8 0;1=2
P 4.05463002 3.83 5 P 0 8 0;1=7
P 0.43 3.145 6 P 0 8 0;1=2
P 4.15463002 3.83 5 P 0 8 0;1=7
P 0.18 3.145 6 P 0 8 0;1=2
P 0.869 2.672 6 P 0 8 0;1=2
P 0.871 2.713 3 P 0 8 0;1=4
P 0.686 2.74 5 P 0 8 0;1=8
P 0.64248002 2.58 6 P 0 8 0;1=2
P 0.736 2.525 5 P 0 8 0;1=8
P 0.714 2.329 6 P 0 8 0;1=2
P 3.429 2.468 3 P 0 8 0;1=4
P 3.51 2.33243002 6 P 0 8 0;1=2
P 3.278 2.468 3 P 0 8 0;1=4
P 3.243 2.547 3 P 0 8 0;1=4
P 3.385 2.135 4 P 0 8 0;1=3
P 3.24 2.36 3 P 0 8 0;1=4
P 3.285 2.38645 3 P 0 8 0;1=4
P 0.832 2.603 6 P 0 8 0;1=0
P 0.77963996 2.601 3 P 0 8 0;1=4
P 0.695 2.578 6 P 0 8 0;1=0
P 0.72 2.714 3 P 0 8 0;1=4
P 0.825 2.732 3 P 0 8 0;1=4
P 6.01953002 2.18853002 6 P 0 8 0;1=0
P 4.415 2.975 3 P 0 8 0;1=4
P 6.09423996 4.27558002 6 P 0 8 0;1=0
P 0.959 2.789 6 P 0 8 0;1=2
P 0.845 2.18 6 P 0 8 0;1=0
P 5.955 2.39 4 P 0 8 0;1=3
P 5.94153002 2.205 5 P 0 8 0;1=7
P 6.01901998 2.001 5 P 0 8 0;1=7
P 5.87 1.84 4 P 0 8 0;1=3
P 3.4593 2.17 5 P 0 8 0;1=7
P 3.44 2.12 6 P 0 8 0;1=0
P 4.34436998 1.94185 4 P 0 8 0;1=1
P 3.18 2.685 3 P 0 8 0;1=4
P 3.523 1.75 5 P 0 8 0;1=8
P 4.712 1.157 4 P 0 8 0;1=3
P 4.42311004 1.50878996 4 P 0 8 0;1=1
P 4.61996004 1.6269 4 P 0 8 0;1=3
P 4.29 1.235 4 P 0 8 0;1=3
P 4.38373996 1.46941998 4 P 0 8 0;1=1
P 4.15 1.235 4 P 0 8 0;1=3
P 4.34436998 1.50878996 4 P 0 8 0;1=1
P 5.035 1.49 4 P 0 8 0;1=3
P 4.65933002 1.58753002 4 P 0 8 0;1=1
P 4.185 1.17 4 P 0 8 0;1=3
P 4.34436998 1.46941998 4 P 0 8 0;1=1
P 4.816 1.258 4 P 0 8 0;1=3
P 4.665 1.104 4 P 0 8 0;1=3
P 4.38373996 1.3513 4 P 0 8 0;1=1
P 4.91 1.54 4 P 0 8 0;1=3
P 4.768 1.207 4 P 0 8 0;1=3
P 4.42311004 1.46941998 4 P 0 8 0;1=1
P 5.03 1.55 4 P 0 8 0;1=3
P 4.58058996 1.6269 4 P 0 8 0;1=1
P 4.828 1.103 4 P 0 8 0;1=3
P 4.42311004 1.43005 4 P 0 8 0;1=1
P 4.83 1.33 4 P 0 8 0;1=3
P 4.22 1.235 4 P 0 8 0;1=3
P 3.83128002 1.78371998 5 P 0 8 0;1=8
P 6.02558996 4.175 6 P 0 8 0;1=0
P 6.1437 4.175 6 P 0 8 0;1=0
P 3.87193002 1.86311004 4 P 0 8 0;1=1
P 4.14753002 2.05996004 4 P 0 8 0;1=1
P 5.83 2.97 6 P 0 8 0;1=2
P 5.89953002 2.366 5 P 0 8 0;1=7
P 3.61123996 3.49876004 3 P 0 8 0;1=4
P 4.54121998 1.94185 4 P 0 8 0;1=1
P 4.22626998 1.94185 4 P 0 8 0;1=1
P 1.96496998 0.76501998 5 P 0 8 0;1=7
P 4.1869 1.98121998 4 P 0 8 0;1=1
P 3.12 2.565 6 P 0 8 0;1=2
P 3.119 2.299 6 P 0 8 0;1=0
P 4.26563996 1.90248002 4 P 0 8 0;1=1
P 3.385 2.59 6 P 0 8 0;1=0
P 5.155 2.01 6 P 0 8 0;1=2
P 6.025 1.83 6 P 0 8 0;1=0
P 4.1869 2.05996004 4 P 0 8 0;1=1
P 4.34436998 1.90248002 4 P 0 8 0;1=1
P 2.554 2.901 6 P 0 8 0;1=0
P 4.75 1.63 4 P 0 8 0;1=5
P 3.205 1.7 6 P 0 8 0;1=0
P 4.775 1.705 6 P 0 8 0;1=2
P 4.84 1.855 6 P 0 8 0;1=0
P 4.58058996 1.82373996 4 P 0 8 0;1=1
P 4.65933002 1.86311004 4 P 0 8 0;1=1
P 4.815 1.93 6 P 0 8 0;1=0
P 4.885 3.46 6 P 0 8 0;1=2
P 4.61996004 1.86311004 4 P 0 8 0;1=1
P 4.83501004 3.46 6 P 0 8 0;1=0
P 3.125 2.254 6 P 0 8 0;1=2
P 4.26563996 1.86311004 4 P 0 8 0;1=5
P 3.12 2.69 6 P 0 8 0;1=2
P 4.565 3.055 6 P 0 8 0;1=2
P 4.3 3.81 6 P 0 8 0;1=0
P 1.3825 3.7225 5 P 0 8 0;1=8
P 5.905 3.015 5 P 0 8 0;1=7
P 5.41 0.96 4 P 0 8 0;1=3
P 4.85033002 1.74933996 6 P 0 8 0;1=2
P 4.54121998 1.78436998 4 P 0 8 0;1=1
P 5.26 2.955 6 P 0 8 0;1=2
P 3.625 0.92 4 P 0 8 0;1=9
P 6.19961004 2.27673996 4 P 0 8 0;1=9
P 3.657 0.92 4 P 0 8 0;1=9
P 6.19961004 2.24473996 4 P 0 8 0;1=9
P 3.3255 2.1355 6 P 0 8 0;1=0
P 3.35153002 2.17875 6 P 0 8 0;1=2
P 3.44 2.95 3 P 0 8 0;1=4
P 3.27923002 2.21576998 6 P 0 8 0;1=2
P 3.3435 2.82 3 P 0 8 0;1=4
P 4.46 2.94 6 P 0 8 0;1=0
P 4.47 2.83 6 P 0 8 0;1=0
P 5.995 1.165 6 P 0 8 0;1=2
P 3.106 3.26 6 P 0 8 0;1=2
P 3.222 3.385 5 P 0 8 0;1=8
P 3.106 3.35 5 P 0 8 0;1=8
P 1.959 3.325 6 P 0 8 0;1=2
P 3.222 3.205 5 P 0 8 0;1=8
P 3.49 2.955 6 P 0 8 0;1=2
P 3.98 3.365 6 P 0 8 0;1=2
P 3.7 3.37 6 P 0 8 0;1=2
P 3.55 3.37 6 P 0 8 0;1=2
P 4.175 3.37 6 P 0 8 0;1=2
P 3.71 3.26 6 P 0 8 0;1=2
P 3.55 3.28 5 P 0 8 0;1=8
P 3.414 3.235 6 P 0 8 0;1=2
P 3.41 3.04 6 P 0 8 0;1=2
P 3.548 2.856 5 P 0 8 0;1=8
P 3.5768 2.7178 6 P 0 8 0;1=2
P 3.395 2.82 6 P 0 8 0;1=2
P 3.58 2.615 4 P 0 8 0;1=3
P 3.485 2.6 6 P 0 8 0;1=2
P 3.525 2.6 6 P 0 8 0;1=2
P 3.335 2.589 6 P 0 8 0;1=2
P 3.24 2.2075 6 P 0 8 0;1=2
P 4.905 2.1675 6 P 0 8 0;1=2
P 4.85 2.02738996 6 P 0 8 0;1=2
P 4.965 1.975 6 P 0 8 0;1=2
P 3.49128002 1.86628002 6 P 0 8 0;1=2
P 4.65933002 1.66626998 4 P 0 8 0;1=1
P 3.795 2.375 6 P 0 8 0;1=2
P 3.99005 2.02058996 4 P 0 8 0;1=1
P 4.34436998 1.86311004 4 P 0 8 0;1=1
P 4.02941998 1.90248002 4 P 0 8 0;1=1
P 3.855 1.96153996 4 P 0 8 0;1=1
P 3.9113 1.86311004 4 P 0 8 0;1=1
P 4.06878996 1.78436998 4 P 0 8 0;1=1
P 4.1869 1.82373996 4 P 0 8 0;1=1
P 3.86 2.5925 6 P 0 8 0;1=2
P 3.758 2.552 6 P 0 8 0;1=2
P 4.209 2.59 6 P 0 8 0;1=2
P 4.65933002 2.09933002 4 P 0 8 0;1=1
P 4.54121998 2.05996004 4 P 0 8 0;1=1
P 4.50185 2.17806998 4 P 0 8 0;1=1
P 4.46248002 1.90248002 4 P 0 8 0;1=1
P 4.42311004 2.02058996 4 P 0 8 0;1=1
P 4.38373996 2.1387 4 P 0 8 0;1=1
P 4.26563996 1.98121998 4 P 0 8 0;1=1
P 4.22626998 2.09933002 4 P 0 8 0;1=1
P 4.14753002 1.94185 4 P 0 8 0;1=1
P 4.10816004 2.05996004 4 P 0 8 0;1=1
P 4.06878996 2.17806998 4 P 0 8 0;1=1
P 3.95066998 2.1387 4 P 0 8 0;1=1
P 4.6987 1.98121998 4 P 0 8 0;1=1
P 4.58058996 1.94185 4 P 0 8 0;1=1
P 4.73806998 1.86311004 4 P 0 8 0;1=1
P 4.61996004 1.82373996 4 P 0 8 0;1=1
P 4.50185 1.78436998 4 P 0 8 0;1=1
P 4.249 2.929 6 P 0 8 0;1=0
P 4.239 2.785 6 P 0 8 0;1=0
P 4.249 2.843 6 P 0 8 0;1=0
P 4.575 2.5 6 P 0 8 0;1=2
P 4.395 2.5 6 P 0 8 0;1=2
P 4.77 2.39 6 P 0 8 0;1=2
P 4.71 2.39 6 P 0 8 0;1=2
P 4.075 2.25 6 P 0 8 0;1=2
P 3.735 2.47 6 P 0 8 0;1=2
P 5.0395 1.335 6 P 0 8 0;1=2
P 4.97 1.75 6 P 0 8 0;1=0
P 4.96 1.63 6 P 0 8 0;1=2
P 6.22 1.27063002 6 P 0 8 0;1=2
P 3.839 3.846 6 P 0 8 0;1=2
P 4.384 3.824 6 P 0 8 0;1=2
P 4.95 3.46 6 P 0 8 0;1=2
P 5.94003002 1.87 6 P 0 8 0;1=2
P 6.379 1.169 6 P 0 8 0;1=2
P 6.105 1.905 6 P 0 8 0;1=2
P 5.92 1.27063002 6 P 0 8 0;1=2
P 5.88 0.965 6 P 0 8 0;1=2
P 6.47 1.08 6 P 0 8 0;1=2
P 5.19 3.075 6 P 0 8 0;1=2
P 5.375 3.04 6 P 0 8 0;1=2
P 5.41 2.815 6 P 0 8 0;1=2
P 5.544 2.675 6 P 0 8 0;1=2
P 6.1865 2.493 6 P 0 8 0;1=2
P 6.141 2.364 6 P 0 8 0;1=2
P 5.85 2.265 6 P 0 8 0;1=2
P 5.62 2.5487 6 P 0 8 0;1=2
P 5.42 2.9645 6 P 0 8 0;1=2
P 4.645 2.985 6 P 0 8 0;1=2
P 4.61 3.025 6 P 0 8 0;1=2
P 4.43 3.865 5 P 0 8 0;1=8
P 5.221 4.165 6 P 0 8 0;1=2
P 4.32 3.965 5 P 0 8 0;1=8
P 4.535 3.815 6 P 0 8 0;1=2
P 4.509 3.309 6 P 0 8 0;1=2
P 4.235 4.155 6 P 0 8 0;1=2
P 4.505 3.685 6 P 0 8 0;1=2
P 5.975 4.219 6 P 0 8 0;1=2
P 5.84 4.219 6 P 0 8 0;1=2
P 6.145 3.98 6 P 0 8 0;1=2
P 4.655 0.785 6 P 0 8 0;1=2
P 4.635 0.92 6 P 0 8 0;1=2
P 5.249 0.99 6 P 0 8 0;1=2
P 5.53 1.085 6 P 0 8 0;1=2
P 5.33 0.82 6 P 0 8 0;1=2
P 5.265 0.675 6 P 0 8 0;1=2
P 2.964 0.702 6 P 0 8 0;1=2
P 5.515 0.59596998 6 P 0 8 0;1=2
P 2.0477 0.6778 6 P 0 8 0;1=2
P 2.285 0.79 6 P 0 8 0;1=2
P 2.285 0.755 6 P 0 8 0;1=2
P 3.09 1.645 6 P 0 8 0;1=2
P 1.605 0.715 6 P 0 8 0;1=2
P 1.605 0.755 6 P 0 8 0;1=2
P 1.826 2.895 6 P 0 8 0;1=2
P 1.401 3.069 6 P 0 8 0;1=2
P 3.119 2.434 6 P 0 8 0;1=2
P 2.245 3.02 5 P 0 8 0;1=8
P 2.49 2.903 6 P 0 8 0;1=2
P 2.128 2.895 5 P 0 8 0;1=8
P 0.11976004 3.23523996 6 P 0 8 0;1=2
P 0.78 2.915 6 P 0 8 0;1=2
P 0.241 3.109 6 P 0 8 0;1=2
P 0.16 2.975 6 P 0 8 0;1=2
P 0.374 2.829 6 P 0 8 0;1=2
P 0.5459 2.6687 6 P 0 8 0;1=2
P 0.674 2.271 6 P 0 8 0;1=2
P 0.857 2.365 6 P 0 8 0;1=2
P 0.677 2.402 6 P 0 8 0;1=2
P 0.11963002 2.66436998 6 P 0 8 0;1=2
P 0.51451998 2.199 6 P 0 8 0;1=2
P 0.58 2.135 6 P 0 8 0;1=2
P 0.125 2.095 6 P 0 8 0;1=2
P 0.64445 1.68945 6 P 0 8 0;1=2
P 0.884 1.549 6 P 0 8 0;1=2
P 0.883 1.639 5 P 0 8 0;1=8
P 0.514 1.616 6 P 0 8 0;1=2
P 0.605 1.52 6 P 0 8 0;1=2
P 0.11263996 1.52263996 6 P 0 8 0;1=2
P 0.625 1.17 6 P 0 8 0;1=2
P 0.59 0.965 6 P 0 8 0;1=0
P 0.505 1.048 6 P 0 8 0;1=2
P 0.125 0.96 6 P 0 8 0;1=2
P 0.821 0.793 6 P 0 8 0;1=2
P 0.764 0.872 6 P 0 8 0;1=2
P 1.25 0.765 6 P 0 8 0;1=2
P 1.1133 0.5981 6 P 0 8 0;1=2
P 0.86 0.631 6 P 0 8 0;1=2
P 0.601 0.73 6 P 0 8 0;1=2
P 0.596 0.602 6 P 0 8 0;1=2
P 1.5327 0.584 6 P 0 8 0;1=2
P 4.6987 1.54816004 4 P 0 8 0;1=1
P 4.58058996 1.50878996 4 P 0 8 0;1=1
P 4.14753002 1.50878996 4 P 0 8 0;1=1
P 4.73806998 1.43005 4 P 0 8 0;1=1
P 4.61996004 1.39066998 4 P 0 8 0;1=1
P 4.50185 1.3513 4 P 0 8 0;1=1
P 4.46248002 1.46941998 4 P 0 8 0;1=1
P 4.38373996 1.31193002 4 P 0 8 0;1=1
P 4.34436998 1.43005 4 P 0 8 0;1=1
P 4.1869 1.39066998 4 P 0 8 0;1=1
P 4.06878996 1.3513 4 P 0 8 0;1=1
P 3.95066998 1.31193002 4 P 0 8 0;1=1
P 5.039 1.2869 6 P 0 8 0;1=2
P 5.0386 1.2415 6 P 0 8 0;1=2
P 4.625 1.17 6 P 0 8 0;1=2
P 4.485 1.005 6 P 0 8 0;1=2
P 3.69171998 1.02828002 6 P 0 8 0;1=2
P 3.6931 1.095 6 P 0 8 0;1=2
P 6.04 3.98 6 P 0 8 0;1=2
P 5.445 0.795 4 P 0 8 0;1=3
P 5.494 0.816 6 P 0 8 0;1=2
P 5.443 0.871 6 P 0 8 0;1=2
P 5.49 0.78223002 6 P 0 8 0;1=2
P 3.795 4.175 6 P 0 8 0;1=2
P 3.66 3.5085 6 P 0 8 0;1=2
P 3.105 3.21 6 P 0 8 0;1=2
P 5.55 4.02 6 P 0 8 0;1=2
P 5.01 2.635 6 P 0 8 0;1=0
P 5 2.78798996 5 P 0 8 0;1=7
P 5.226 2.762 5 P 0 8 0;1=7
P 3.775 2.235 6 P 0 8 0;1=2
P 3.775 2.265 6 P 0 8 0;1=0
P 3.775 2.21 6 P 0 8 0;1=2
P 3.775 2.185 6 P 0 8 0;1=2
P 4.42311004 1.78436998 4 P 0 8 0;1=1
P 4.46248002 1.70563996 4 P 0 8 0;1=1
P 4.34436998 1.78436998 4 P 0 8 0;1=1
P 4.22626998 1.78436998 4 P 0 8 0;1=1
P 4.22626998 1.66626998 4 P 0 8 0;1=1
P 4.14753002 1.78436998 4 P 0 8 0;1=1
P 4.02941998 1.78436998 4 P 0 8 0;1=1
P 5.765 0.98 4 P 0 8 0;1=3
P 1.385 3.875 5 P 0 8 0;1=7
P 5.31 2.855 6 P 0 8 0;1=2
P 4.608 2.942 6 P 0 8 0;1=2
P 4.25 3.81 6 P 0 8 0;1=2
P 0.99 2.60025 6 P 0 8 0;1=2
P 0.985 2.56661004 6 P 0 8 0;1=2
P 3.555 2.23 6 P 0 8 0;1=2
P 3.555 2.255 6 P 0 8 0;1=2
P 3.555 2.205 6 P 0 8 0;1=2
P 3.555 2.18 6 P 0 8 0;1=2
P 5.345 2.536 4 P 0 8 0;1=3
P 5.22 2.47 6 P 0 8 0;1=2
P 5.254 2.47 6 P 0 8 0;1=2
P 5.239 2.571 6 P 0 8 0;1=2
P 5.243 2.617 6 P 0 8 0;1=2
P 5.224 2.707 5 P 0 8 0;1=7
P 5.005 2.711 5 P 0 8 0;1=7
P 3.793 3.05 3 P 0 8 0;1=4
P 3.96981004 3.04481998 6 P 0 8 0;1=0
P 3.948 2.813 6 P 0 8 0;1=0
P 4.831 2.728 4 P 0 8 0;1=3
P 3.55 1.415 6 P 0 8 0;1=2
P 3.525 1.415 6 P 0 8 0;1=2
P 3.5 1.415 6 P 0 8 0;1=2
P 3.475 1.415 6 P 0 8 0;1=2
P 3.655 2.795 4 P 0 8 0;1=3
P 3.745 2.76 6 P 0 8 0;1=2
P 3.7 2.76 6 P 0 8 0;1=2
P 3.822 2.81 6 P 0 8 0;1=2
P 3.78 2.81 6 P 0 8 0;1=2
P 3.894 2.811 6 P 0 8 0;1=0
P 3.916 3.048 3 P 0 8 0;1=4
P 5.589 2.025 6 P 0 8 0;1=0
P 5.546 2.024 6 P 0 8 0;1=2
P 5.69943002 2.233 6 P 0 8 0;1=0
P 5.48158002 2.28033002 5 P 0 8 0;1=7
P 4.50185 1.66626998 4 P 0 8 0;1=1
P 4.42311004 1.66626998 4 P 0 8 0;1=1
P 4.38373996 1.70563996 4 P 0 8 0;1=1
P 4.26563996 1.70563996 4 P 0 8 0;1=1
P 4.14753002 1.66626998 4 P 0 8 0;1=1
P 4.1869 1.70563996 4 P 0 8 0;1=1
P 4.50185 1.58753002 4 P 0 8 0;1=1
P 4.46248002 1.6269 4 P 0 8 0;1=1
P 4.46248002 1.54816004 4 P 0 8 0;1=1
P 4.38373996 1.54816004 4 P 0 8 0;1=1
P 4.42311004 1.58753002 4 P 0 8 0;1=1
P 4.34436998 1.58753002 4 P 0 8 0;1=1
P 4.26563996 1.54816004 4 P 0 8 0;1=1
P 4.22626998 1.58753002 4 P 0 8 0;1=1
P 4.14753002 1.58753002 4 P 0 8 0;1=1
P 4.1869 1.6269 4 P 0 8 0;1=1
P 4.1869 1.54816004 4 P 0 8 0;1=1
P 5.145 1.57 6 P 0 8 0;1=2
P 5.145 1.54 6 P 0 8 0;1=2
P 5.145 1.44 6 P 0 8 0;1=0
P 5.145 1.48 6 P 0 8 0;1=2
P 5.145 1.51 6 P 0 8 0;1=2
P 5.76 2.465 4 P 0 8 0;1=3
P 4.2136 3.5997 3 P 0 8 0;1=4
P 3.755 3.092 6 P 0 8 0;1=2
P 3.99005 1.66626998 4 P 0 8 0;1=1
P 4.06878996 1.54816004 4 P 0 8 0;1=1
P 4.06878996 1.6269 4 P 0 8 0;1=1
P 4.02941998 1.58753002 4 P 0 8 0;1=1
P 3.99005 1.50878996 4 P 0 8 0;1=1
P 3.679 1.54228002 6 P 0 8 0;1=2
P 3.714 1.543 6 P 0 8 0;1=2
P 3.784 1.543 6 P 0 8 0;1=2
P 3.749 1.54228002 6 P 0 8 0;1=2
P 3.605 1.545 6 P 0 8 0;1=2
P 3.50085 1.543 6 P 0 8 0;1=2
P 3.53481998 1.54156998 6 P 0 8 0;1=2
P 3.57 1.542 6 P 0 8 0;1=2
P 5.4227 1.724 6 P 0 8 0;1=2
P 5.3977 1.724 6 P 0 8 0;1=2
P 5.58 1.615 4 P 0 8 0;1=3
P 5.3977 1.699 6 P 0 8 0;1=2
P 5.3977 1.749 6 P 0 8 0;1=2
P 5.4227 1.699 6 P 0 8 0;1=2
P 5.4352 1.7497 6 P 0 8 0;1=2
P 5.654 2.447 6 P 0 8 0;1=2
P 5.667 2.275 5 P 0 8 0;1=7
P 5.595 2.28 5 P 0 8 0;1=7
P 5.483 2.226 6 P 0 8 0;1=0
P 5.6695 2.2 6 P 0 8 0;1=2
P 5.771 2.279 5 P 0 8 0;1=7
P 5.789 2.366 6 P 0 8 0;1=2
P 5.6 2.4 6 P 0 8 0;1=2
P 5.6 4.01 4 P 0 8 0;1=3
P 5.55568996 3.88051004 3 P 0 8 0;1=4
P 5.765 2.197 6 P 0 8 0;1=0
P 5.71 2.179 6 P 0 8 0;1=2
P 5.41 2.164 6 P 0 8 0;1=0
P 5.458 2.165 6 P 0 8 0;1=2
P 5.465 2.405 6 P 0 8 0;1=2
P 5.53121998 2.27978996 5 P 0 8 0;1=7
P 3.817 0.924 5 P 0 8 0;1=7
P 4.25 0.877 6 P 0 8 0;1=0
P 5.495 0.694 5 P 0 8 0;1=7
P 5.49 0.635 6 P 0 8 0;1=0
P 5.725 0.60301004 5 P 0 8 0;1=7
P 5.686 0.76 5 P 0 8 0;1=7
P 5.7287 0.6757 5 P 0 8 0;1=7
P 5.38558002 4.13778996 6 P 0 8 0;1=0
P 5.485 4.11 6 P 0 8 0;1=0
P 5.725 4.135 6 P 0 8 0;1=0
P 5.6218 4.13778996 6 P 0 8 0;1=0
P 5.323 4.257 5 P 0 8 0;1=7
P 3.83 3.335 3 P 0 8 0;1=4
P 3.415 3.285 3 P 0 8 0;1=4
P 3.83 3.285 3 P 0 8 0;1=4
P 3.415 3.385 3 P 0 8 0;1=4
P 4.83871004 1.98241004 6 P 0 8 0;1=0
P 4.80288002 2.03788002 6 P 0 8 0;1=0
P 4.97 3.41 6 P 0 8 0;1=0
P 4.38373996 1.90248002 4 P 0 8 0;1=1
P 4.81 3.41 6 P 0 8 0;1=2
P 4.42311004 2.09933002 4 P 0 8 0;1=5
P 3.48863002 4.105 6 P 0 8 0;1=0
P 2.987 3.235 5 P 0 8 0;1=8
P 0.7595 1.642 5 P 0 8 0;1=7
P 2.987 3.27 5 P 0 8 0;1=8
P 0.761 1.544 5 P 0 8 0;1=7
P 4.54121998 1.82373996 4 P 0 8 0;1=1
P 4.79246004 1.78463996 6 P 0 8 0;1=0
P 4.54121998 2.17806998 4 P 0 8 0;1=5
P 0.955 1.455 6 P 0 8 0;1=0
P 1.512 0.75191004 6 P 0 8 0;1=2
P 1.8091 0.6339 5 P 0 8 0;1=7
P 1.459 0.752 5 P 0 8 0;1=8
P 0.905 1.445 6 P 0 8 0;1=2
P 2.40508002 0.731 5 P 0 8 0;1=8
P 4.06878996 1.66626998 3 P 0 8 0;1=11
P 2.40508002 0.699 5 P 0 8 0;1=8
P 4.02941998 1.66626998 3 P 0 8 0;1=11
P 4.4085 1.16598996 5 P 0 8 0;1=8
P 4.46248002 1.43005 3 P 0 8 0;1=11
P 4.3765 1.16598996 5 P 0 8 0;1=8
P 4.50185 1.43005 3 P 0 8 0;1=11
P 4.0485 1.16098996 5 P 0 8 0;1=8
P 4.06878996 1.50878996 3 P 0 8 0;1=11
P 4.0165 1.16098996 5 P 0 8 0;1=8
P 4.02941998 1.50878996 3 P 0 8 0;1=11
P 4.82 2.125 4 P 0 8 0;1=3
P 4.38373996 1.78436998 4 P 0 8 0;1=1
P 3.54663996 1.04706998 5 P 0 8 0;1=8
P 4.6987 1.46941998 3 P 0 8 0;1=11
P 3.51463996 1.04706998 5 P 0 8 0;1=8
P 4.73806998 1.46941998 3 P 0 8 0;1=11
P 3.44998996 1.085 5 P 0 8 0;1=8
P 4.73806998 1.39066998 3 P 0 8 0;1=11
P 3.41798996 1.085 5 P 0 8 0;1=8
P 4.73806998 1.3513 3 P 0 8 0;1=11
P 3.445 1.815 6 P 0 8 0;1=2
P 4.58058996 1.90248002 4 P 0 8 0;1=1
P 4.65933002 1.94185 4 P 0 8 0;1=1
P 4.785 3.46 6 P 0 8 0;1=0
P 3.9113 1.70563996 4 P 0 8 0;1=1
P 3.674 1.744 6 P 0 8 0;1=2
P 3.95066998 1.58753002 4 P 0 8 0;1=1
P 3.9113 1.54816004 4 P 0 8 0;1=1
P 3.9113 1.6269 4 P 0 8 0;1=1
P 3.95066998 1.43005 4 P 0 8 0;1=1
P 3.9113 1.46941998 4 P 0 8 0;1=1
P 3.82 1.42 6 P 0 8 0;1=0
P 3.79 1.41 6 P 0 8 0;1=2
P 3.74 1.41 6 P 0 8 0;1=2
P 3.765 1.41 6 P 0 8 0;1=2
P 4.54121998 1.6269 4 P 0 8 0;1=1
P 4.9097 1.385 5 P 0 8 0;1=7
P 4.54121998 1.66626998 4 P 0 8 0;1=1
P 4.84 1.66 6 P 0 8 0;1=0
P 4.81 1.725 6 P 0 8 0;1=0
P 3.375 1.194 5 P 0 8 0;1=8
P 4.5413 1.22166998 5 P 0 8 0;1=8
P 4.61996004 1.31193002 3 P 0 8 0;1=11
P 3.375 1.162 5 P 0 8 0;1=8
P 4.5733 1.22166998 5 P 0 8 0;1=8
P 4.65933002 1.31193002 3 P 0 8 0;1=11
P 5.3 4.065 4 P 0 8 0;1=3
P 4.10816004 1.70563996 4 P 0 8 0;1=1
P 4.365 2.33 6 P 0 8 0;1=2
P 4.38373996 2.02058996 4 P 0 8 0;1=5
P 4.38373996 2.05996004 4 P 0 8 0;1=1
P 4.485 2.375 6 P 0 8 0;1=0
P 4.38373996 2.09933002 4 P 0 8 0;1=1
P 4.54121998 1.58753002 4 P 0 8 0;1=1
P 4.9097 1.335 5 P 0 8 0;1=7
P 4.26563996 1.78436998 4 P 0 8 0;1=1
P 4.365 2.375 6 P 0 8 0;1=0
P 3.465 1.74 6 P 0 8 0;1=2
P 3.44 1.03 6 P 0 8 0;1=0
P 6.285 1.895 6 P 0 8 0;1=2
P 6.258 2.15873996 5 P 0 8 0;1=8
P 6.275 2.05373996 6 P 0 8 0;1=2
P 6.335 2.05906004 5 P 0 8 0;1=7
P 1.77 3.98 6 P 0 8 0;1=0
P 1.75 3.945 6 P 0 8 0;1=2
P 1.5315 3.9459 5 P 0 8 0;1=7
P 1.517 4.113 6 P 0 8 0;1=0
P 1.511 3.863 5 P 0 8 0;1=7
P 1.5153 4.063 5 P 0 8 0;1=7
P 1.521 3.993 5 P 0 8 0;1=7
P 1.579 3.874 6 P 0 8 0;1=0
P 1.585 4.052 6 P 0 8 0;1=2
P 1.435 4.18 6 P 0 8 0;1=2
P 1.522 4.163 5 P 0 8 0;1=7
P 1.4 4.01 6 P 0 8 0;1=2
P 5.14 3.74 6 P 0 8 0;1=2
P 5.175 3.74 6 P 0 8 0;1=2
P 5.18 3.825 6 P 0 8 0;1=2
P 5.675 4.03 6 P 0 8 0;1=2
P 1.56 3.29 6 P 0 8 0;1=2
P 1.56 3.25 6 P 0 8 0;1=2
P 3.245 2.955 6 P 0 8 0;1=2
P 3.21 2.955 6 P 0 8 0;1=2
P 3.175 2.955 6 P 0 8 0;1=2
P 2.59 3.445 6 P 0 8 0;1=2
P 2.55 3.445 6 P 0 8 0;1=2
P 2.51 3.445 6 P 0 8 0;1=2
P 2.47 3.445 6 P 0 8 0;1=2
P 2.2 3.96 6 P 0 8 0;1=2
P 2.25 3.96 4 P 0 8 0;1=3
P 1.351 4.126 6 P 0 8 0;1=2
P 2.165 3.96 6 P 0 8 0;1=2
P 2.155 3.925 6 P 0 8 0;1=2
P 2.19 3.925 6 P 0 8 0;1=2
P 3.23 4.015 6 P 0 8 0;1=0
P 3.2 3.985 6 P 0 8 0;1=2
P 5.9065 2.4568 6 P 0 8 0;1=2
P 3.745 4.185 4 P 0 8 0;1=3
P 3.47 3.912 6 P 0 8 0;1=0
P 3.69 4.135 4 P 0 8 0;1=3
P 3.48278996 4.05678002 6 P 0 8 0;1=2
P 3.476 3.988 6 P 0 8 0;1=0
P 3.437 4.099 6 P 0 8 0;1=0
P 3.598 3.977 6 P 0 8 0;1=2
P 3.477 3.816 6 P 0 8 0;1=0
P 3.405 3.916 6 P 0 8 0;1=2
P 5.68326004 3.712 6 P 0 8 0;1=0
P 5.686 3.807 6 P 0 8 0;1=0
P 5.50643002 4.009 3 P 0 8 0;1=4
P 5.686 3.76 6 P 0 8 0;1=0
P 5.675 3.865 6 P 0 8 0;1=0
P 5.718 3.965 4 P 0 8 0;1=3
P 6.05315 3.67518996 9 P 0 8 0;1=12
P 6.05315 3.50983996 9 P 0 8 0;1=13
P 6.05315 3.34448996 9 P 0 8 0;1=13
P 0.865 3.645 6 P 0 8 0;1=2
P 0.905 3.645 6 P 0 8 0;1=2
P 0.945 3.645 6 P 0 8 0;1=2
P 0.945 3.69 6 P 0 8 0;1=2
P 0.945 3.73 6 P 0 8 0;1=2
P 0.945 3.765 6 P 0 8 0;1=2
P 0.865 3.845 6 P 0 8 0;1=2
P 0.905 3.845 6 P 0 8 0;1=2
P 0.94 3.845 6 P 0 8 0;1=2
P 0.945 3.805 6 P 0 8 0;1=0
P 0.828 3.846 6 P 0 8 0;1=2
P 0.828 3.646 6 P 0 8 0;1=2
P 5.66 3.47 4 P 0 8 0;1=3
P 5.68 3.567 3 P 0 8 0;1=4
P 5.406 3.863 6 P 0 8 0;1=0
P 3.46 4.16 6 P 0 8 0;1=2
P 3.495 4.15 6 P 0 8 0;1=2
P 3.5 4.195 6 P 0 8 0;1=2
P 3.53 4.165 6 P 0 8 0;1=2
P 5.769 4.031 6 P 0 8 0;1=2
P 5.644 3.967 6 P 0 8 0;1=0
P 5.803 3.907 6 P 0 8 0;1=2
P 1.45 3.78 6 P 0 8 0;1=2
P 1.485 3.76 5 P 0 8 0;1=7
P 1.485 3.8 6 P 0 8 0;1=2
P 5.406 2.346 4 P 0 8 0;1=3
P 5.375 2.32 6 P 0 8 0;1=2
P 5.34 2.315 6 P 0 8 0;1=2
P 5.43 3.6 6 P 0 8 0;1=0
P 5.433 3.651 6 P 0 8 0;1=2
P 5.43 3.7 6 P 0 8 0;1=2
P 5.39 3.6 6 P 0 8 0;1=2
P 5.393 3.651 6 P 0 8 0;1=2
P 5.39 3.7 6 P 0 8 0;1=2
P 1.6055 4.134 6 P 0 8 0;1=2
P 1.60581998 4.1 6 P 0 8 0;1=2
P 1.606 4.174 5 P 0 8 0;1=7
P 1.636 3.786 6 P 0 8 0;1=2
P 1.591 3.826 6 P 0 8 0;1=2
P 1.633 3.829 5 P 0 8 0;1=7
P 3.408 4.152 6 P 0 8 0;1=2
P 3.363 4.192 6 P 0 8 0;1=2
P 3.363 4.152 6 P 0 8 0;1=2
P 3.363 4.232 6 P 0 8 0;1=0
P 3.393 3.877 6 P 0 8 0;1=2
P 3.393 3.84 6 P 0 8 0;1=2
P 3.392 3.803 6 P 0 8 0;1=2
P 3.607 4.062 6 P 0 8 0;1=2
P 1.352 4.084 6 P 0 8 0;1=0
P 1.95 0.5455 5 P 0 8 0;1=7
P 5.681 3.617 6 P 0 8 0;1=0
P 5.681 3.664 6 P 0 8 0;1=0
P 5.40318002 2.70436004 5 P 0 8 0;1=7
P 0.55921998 1.40543002 6 P 0 8 0;1=0
P 0.57 0.835 6 P 0 8 0;1=0
P 3.584 1.827 5 P 0 8 0;1=7
P 1.535 3.905 5 P 0 8 0;1=8
P 1.98135 0.365 5 P 0 8 0;1=8
P 1.7317 0.7084 6 P 0 8 0;1=0
P 1.91535 0.412 5 P 0 8 0;1=8
P 1.8039 0.7072 5 P 0 8 0;1=7
P 3.2271 1.90298996 4 P 0 8 0;1=9
P 3.45301004 1.89898996 4 P 0 8 0;1=9
P 3.2591 1.90298996 4 P 0 8 0;1=9
P 3.45301004 1.93098996 4 P 0 8 0;1=9
P 1.26066998 2.64043002 10 P 0 8 0;1=14
P 5.035 3.945 6 P 0 8 0;1=0
P 5.075 3.945 6 P 0 8 0;1=2
P 2.97771998 1.88693996 6 P 0 8 0;1=2
P 3.00995 1.87611004 6 P 0 8 0;1=2
P 2.86066998 2.64043002 10 P 0 8 0;1=14
P 2.105 0.305 5 P 0 8 0;1=8
P 2.235 0.5825 6 P 0 8 0;1=2
P 3.405 0.635 6 P 0 8 0;1=2
P 5.295 0.605 6 P 0 8 0;1=0
P 5.91 4.04 6 P 0 8 0;1=0
P 2.135 0.54 6 P 0 8 0;1=2
P 5.215 0.6 6 P 0 8 0;1=0
P 6.025 4.04 6 P 0 8 0;1=0
P 3.36 0.6106 6 P 0 8 0;1=2
P 0.96 2.41 6 P 0 8 0;1=2
P 0.68 2.355 6 P 0 8 0;1=2
P 2.38 3.45 6 P 0 8 0;1=2
P 1.41 3.795 6 P 0 8 0;1=2
P 3.445 3.613 6 P 0 8 0;1=2
P 3.365 3.613 6 P 0 8 0;1=0
P 3.25 3.63 6 P 0 8 0;1=2
P 3.325 3.613 6 P 0 8 0;1=2
P 3.405 3.613 6 P 0 8 0;1=2
P 3.48418002 3.613 6 P 0 8 0;1=2
P 3.645 4.135 6 P 0 8 0;1=2
P 3.655 3.059 6 P 0 8 0;1=2
P 3.614 3.099 6 P 0 8 0;1=2
P 3.614 3.058 6 P 0 8 0;1=2
P 3.614 3.015 6 P 0 8 0;1=2
P 5.236 2.811 6 P 0 8 0;1=2
P 4.3305 2.914 6 P 0 8 0;1=15
P 4.3815 2.838 6 P 0 8 0;1=15
P 4.29 2.74 4 P 0 8 0;1=3
P 4.456 2.783 6 P 0 8 0;1=2
P 4.355 2.745 6 P 0 8 0;1=2
P 4.346 2.783 6 P 0 8 0;1=2
P 4.4 2.785 6 P 0 8 0;1=2
P 4 2.655 6 P 0 8 0;1=2
P 5.022 2.407 6 P 0 8 0;1=2
P 4.923 2.408 6 P 0 8 0;1=2
P 4.972 2.406 6 P 0 8 0;1=2
P 4.971 2.447 6 P 0 8 0;1=2
P 5.2871 2.275 6 P 0 8 0;1=2
P 5.62533002 1.02001004 6 P 0 8 0;1=2
P 5.65933002 1.02 6 P 0 8 0;1=2
P 3.804 0.816 5 P 0 8 0;1=8
P 4.23 0.7295 6 P 0 8 0;1=2
P 2.31 0.715 6 P 0 8 0;1=2
P 2.31 0.68 6 P 0 8 0;1=2
P 2.595 0.547 6 P 0 8 0;1=2
P 1.87598002 0.289 5 P 0 8 0;1=8
P 1.86 0.33 5 P 0 8 0;1=8
P 1.895 0.33 5 P 0 8 0;1=8
P 1.87598002 0.369 5 P 0 8 0;1=8
P 0.705 3.82 6 P 0 8 0;1=2
P 0.665 3.82 6 P 0 8 0;1=2
P 0.625 3.82 6 P 0 8 0;1=2
P 0.625 3.78 6 P 0 8 0;1=0
P 0.625 3.73 6 P 0 8 0;1=0
P 0.66 3.65 6 P 0 8 0;1=2
P 0.695 3.65 6 P 0 8 0;1=2
P 0.73 3.65 6 P 0 8 0;1=2
P 0.625 3.69 6 P 0 8 0;1=2
P 0.625 3.65 6 P 0 8 0;1=2
P 3.51 2.37 6 P 0 8 0;1=2
P 0.29 2.915 6 P 0 8 0;1=0
P 0.28 2.965 6 P 0 8 0;1=0
P 0.285 3.02 6 P 0 8 0;1=0
P 2.977 3.351 3 P 0 8 0;1=4
P 3.36525 3.255 3 P 0 8 0;1=4
P 3.36525 3.205 3 P 0 8 0;1=4
P 1.8062 0.7789 5 P 0 8 0;1=7
P 3.073 0.613 5 P 0 8 0;1=7
P 2.54526998 0.339 5 P 0 8 0;1=8
P 2.527 0.44 3 P 0 8 0;1=4
P 5.73991004 4.27558002 6 P 0 8 0;1=0
P 5.38558002 4.27558002 6 P 0 8 0;1=0
P 5.50368996 4.27558002 6 P 0 8 0;1=0
P 5.6218 4.27558002 6 P 0 8 0;1=0
P 5.875 1.9 6 P 0 8 0;1=0
P 3.865 3.65 6 P 0 8 0;1=2
P 6.06901998 1.86 6 P 0 8 0;1=0
P 3.81 3.65 6 P 0 8 0;1=2
P 5.97 1.999 5 P 0 8 0;1=7
P 2.86066998 1.04042992 18 P 0 8 0;1=14
P 5.9645 2.1035 6 P 0 8 0;1=15
P 6.0155 2.0845 6 P 0 8 0;1=15
P 0.43705 3.51576004 16 P 0 8 0;1=16
P 0.43705 3.31655 16 P 0 8 0;1=16
P 0.24806998 3.47245 16 P 0 8 0;1=16
P 0.24806998 3.35985 16 P 0 8 0;1=16
P 0.24605994 3.4315 20 P 0 8 0;1=6
P 0.4587 3.4315 20 P 0 8 0;1=6
P 0.44097992 3.4008 20 P 0 8 0;1=6
P 0.22833996 3.4008 20 P 0 8 0;1=6
P 4.94093996 4.12008002 19 P 0 8 0;1=17
P 4.94093996 3.09646004 19 P 0 8 0;1=17
P 2.55906004 4.12008002 19 P 0 8 0;1=17
P 2.55906004 3.09646004 19 P 0 8 0;1=17
P 5.88778996 3.34448996 17 P 0 8 0;1=13
P 5.88778996 3.50983996 17 P 0 8 0;1=13
P 5.88778996 3.67518996 17 P 0 8 0;1=13
P 6.51581998 2.24803996 15 P 0 8 0;1=18
P 6.51581998 1.97243996 14 P 0 8 0;1=19
P 6.40951998 2.20866998 21 P 0 8 0;1=20
P 6.40951998 2.01180994 21 P 0 8 0;1=20
P 0.06038996 1.38345994 22 P 0 8 0;1=21
P 0.26038996 1.38345994 22 P 0 8 0;1=21
P 0.06038996 1.18345994 22 P 0 8 0;1=21
P 0.26038996 1.18345994 22 P 0 8 0;1=21
P 0.06038996 0.8126 22 P 0 8 0;1=21
P 0.26038996 0.8126 22 P 0 8 0;1=21
P 0.06038996 0.6126 22 P 0 8 0;1=21
P 0.26038996 0.6126 22 P 0 8 0;1=21
P 0.06038996 2.5252 22 P 0 8 0;1=21
P 0.26038996 2.5252 22 P 0 8 0;1=21
P 0.06038996 2.3252 22 P 0 8 0;1=21
P 0.26038996 2.3252 22 P 0 8 0;1=21
P 0.06038996 1.95433002 22 P 0 8 0;1=21
P 0.26038996 1.95433002 22 P 0 8 0;1=21
P 0.06038996 1.75433002 22 P 0 8 0;1=21
P 0.26038996 1.75433002 22 P 0 8 0;1=21
P 1.26066998 1.84042992 18 P 0 8 0;1=14
P 5.91901998 2.003 5 P 0 8 0;1=7
P 6.06901998 2.004 5 P 0 8 0;1=7
P 3.49 0.825 5 P 0 8 0;1=7
P 2.65966998 0.93443002 10 P 0 8 0;1=14
P 6.095 2.545 6 P 0 8 0;1=0
P 5.07 1.885 6 P 0 8 0;1=2
P 5.33 0.995 5 P 0 8 0;1=8
P 3.54 0.825 6 P 0 8 0;1=2
P 6.04 2.545 6 P 0 8 0;1=0
P 5.07 1.925 6 P 0 8 0;1=2
P 5.33 0.95 5 P 0 8 0;1=8
P 2.53966998 0.93443002 10 P 0 8 0;1=14
P 2.802 1.987 5 P 0 8 0;1=8
P 2.834 1.987 5 P 0 8 0;1=8
P 2.845 1.875 5 P 0 8 0;1=8
P 2.845 1.843 5 P 0 8 0;1=8
P 2.77866998 0.93443002 10 P 0 8 0;1=14
P 4.97 1.54 4 P 0 8 0;1=3
P 4.9806 1.855 6 P 0 8 0;1=0
P 1.26066998 1.04043002 10 P 0 8 0;1=14
P 0.724 2.646 6 P 0 8 0;1=0
P 0.758 2.743 3 P 0 8 0;1=4
P 3.235 2.63 4 P 0 8 0;1=3
P 3.275 2.32 3 P 0 8 0;1=4
P 3.24 2.275 6 P 0 8 0;1=0
P 3.305 2.65 4 P 0 8 0;1=3
P 3.375 2.65 4 P 0 8 0;1=3
P 3.326 2.466 3 P 0 8 0;1=4
P 2.1481 0.7881 5 P 0 8 0;1=7
P 5.08 1.105 6 P 0 8 0;1=2
P 5.225 1.145 6 P 0 8 0;1=2
P 5.132 0.66 6 P 0 8 0;1=2
P 2.0816 0.7399 6 P 0 8 0;1=2
P 2.03 0.75 5 P 0 8 0;1=7
P 5.08 1.155 6 P 0 8 0;1=2
P 5.08 1.055 6 P 0 8 0;1=2
P 2.0788 0.7874 5 P 0 8 0;1=7
P 2.29581998 0.48918002 4 P 0 8 0;1=3
P 2.633 0.522 5 P 0 8 0;1=8
P 3.455 0.87 6 P 0 8 0;1=2
P 0.9225 0.9775 6 P 0 8 0;1=2
P 4.82 0.835 6 P 0 8 0;1=0
P 0.8825 1.7725 6 P 0 8 0;1=2
P 3.405 0.87 6 P 0 8 0;1=2
P 0.965 0.98 6 P 0 8 0;1=2
P 0.91 1.815 6 P 0 8 0;1=0
P 4.78 0.78 6 P 0 8 0;1=2
P 4.42311004 1.86311004 3 P 0 8 0;1=11
P 3.65101004 1.88358996 4 P 0 8 0;1=9
P 4.46248002 1.86311004 3 P 0 8 0;1=11
P 3.65101004 1.91558996 4 P 0 8 0;1=9
P 3.065 1.695 4 P 0 8 0;1=3
P 2.98283996 1.75183996 6 P 0 8 0;1=2
P 2.225 3.245 6 P 0 8 0;1=2
P 4.595 2.62 6 P 0 8 0;1=2
P 4.025 3.08 6 P 0 8 0;1=2
P 0.62 3.07 6 P 0 8 0;1=2
P 5.865 1.125 6 P 0 8 0;1=0
P 5.865 1.07 6 P 0 8 0;1=0
P 2.265 3.34 6 P 0 8 0;1=2
P 4.57 2.585 6 P 0 8 0;1=2
P 4.02 3.03 6 P 0 8 0;1=2
P 0.645 2.9675 6 P 0 8 0;1=2
P 5.48828996 4.16328996 6 P 0 8 0;1=0
P 3.99005 1.90248002 4 P 0 8 0;1=1
P 5.55315 4.175 6 P 0 8 0;1=0
P 3.99005 1.86311004 4 P 0 8 0;1=1
P 5.67126004 4.175 6 P 0 8 0;1=0
P 3.95066998 1.82373996 4 P 0 8 0;1=1
P 5.78936998 4.175 6 P 0 8 0;1=0
P 3.9113 1.82373996 4 P 0 8 0;1=1
P 4.205 2.295 4 P 0 8 0;1=3
P 4.65933002 1.6269 4 P 0 8 0;1=3
P 4.254 2.296 4 P 0 8 0;1=3
P 4.23 2.354 4 P 0 8 0;1=3
P 4.915 1.485 4 P 0 8 0;1=3
P 4.65933002 1.54816004 4 P 0 8 0;1=1
P 3.94 2.235 4 P 0 8 0;1=3
P 4.85 1.54 4 P 0 8 0;1=3
P 4.149 2.298 4 P 0 8 0;1=3
P 4.161 2.354 4 P 0 8 0;1=3
P 3.75 2.1 4 P 0 8 0;1=3
P 4.975 1.485 4 P 0 8 0;1=3
P 4.58058996 1.58753002 4 P 0 8 0;1=1
P 3.8 2.1 4 P 0 8 0;1=3
P 4.73806998 1.54816004 4 P 0 8 0;1=3
P 3.9 2.325 4 P 0 8 0;1=3
P 4.73806998 1.50878996 4 P 0 8 0;1=3
P 3.83 2.325 4 P 0 8 0;1=3
P 0.846 2.489 3 P 0 8 0;1=4
P 3.28 3.065 6 P 0 8 0;1=2
P 0.796 2.489 3 P 0 8 0;1=4
P 3.325 3.065 6 P 0 8 0;1=2
P 5.03 3.546 3 P 0 8 0;1=4
P 4.935 3.59 3 P 0 8 0;1=4
P 4.67 3.555 4 P 0 8 0;1=3
P 4.885 3.59 5 P 0 8 0;1=7
P 4.70461998 3.69461998 3 P 0 8 0;1=4
P 4.50185 1.82373996 4 P 0 8 0;1=1
P 5.395 2.92 6 P 0 8 0;1=0
P 5.015 1.925 6 P 0 8 0;1=2
P 5.39976998 2.75123996 5 P 0 8 0;1=7
P 4.46248002 1.82373996 4 P 0 8 0;1=1
P 5.375 2.96606998 5 P 0 8 0;1=7
P 4.58058996 1.78436998 4 P 0 8 0;1=1
P 5.4525 2.563 5 P 0 8 0;1=7
P 3.545 0.6092 6 P 0 8 0;1=2
P 1.395 0.625 5 P 0 8 0;1=7
P 5.085 0.645 6 P 0 8 0;1=2
P 3.495 0.61 6 P 0 8 0;1=2
P 5.04 0.645 6 P 0 8 0;1=2
P 1.485 0.625 5 P 0 8 0;1=7
P 3.99005 1.6269 3 P 0 8 0;1=11
P 2.95835 0.385 4 P 0 8 0;1=9
P 3.95066998 1.6269 3 P 0 8 0;1=11
P 2.95835 0.353 4 P 0 8 0;1=9
P 3.9113 1.66626998 3 P 0 8 0;1=11
P 2.80086998 0.385 4 P 0 8 0;1=9
P 3.87193002 1.66626998 3 P 0 8 0;1=11
P 2.80086998 0.353 4 P 0 8 0;1=9
P 3.99005 1.70563996 3 P 0 8 0;1=11
P 2.64338996 0.385 4 P 0 8 0;1=9
P 3.95066998 1.70563996 3 P 0 8 0;1=11
P 2.64338996 0.353 4 P 0 8 0;1=9
P 3.9113 1.58753002 3 P 0 8 0;1=11
P 2.95835 0.481 4 P 0 8 0;1=9
P 2.95835 0.449 4 P 0 8 0;1=9
P 3.87193002 1.58753002 3 P 0 8 0;1=11
P 3.125 0.875 4 P 0 8 0;1=9
P 3.99005 1.54816004 3 P 0 8 0;1=11
P 3.14763002 0.85236998 4 P 0 8 0;1=9
P 3.95066998 1.54816004 3 P 0 8 0;1=11
P 2.81855 0.763 4 P 0 8 0;1=9
P 3.9113 1.50878996 3 P 0 8 0;1=11
P 2.85055 0.763 4 P 0 8 0;1=9
P 3.87193002 1.50878996 3 P 0 8 0;1=11
P 2.66706998 0.763 4 P 0 8 0;1=9
P 3.99005 1.46941998 3 P 0 8 0;1=11
P 2.69906998 0.763 4 P 0 8 0;1=9
P 3.95066998 1.46941998 3 P 0 8 0;1=11
P 2.47021998 0.763 4 P 0 8 0;1=9
P 3.9113 1.43005 3 P 0 8 0;1=11
P 2.50221998 0.763 4 P 0 8 0;1=9
P 3.87193002 1.43005 3 P 0 8 0;1=11
P 1.889 0.5496 6 P 0 8 0;1=2
P 2.435 0.4865 3 P 0 8 0;1=4
P 3.56 3.023 6 P 0 8 0;1=0
P 3.57 2.955 6 P 0 8 0;1=0
P 4.975 2.14 6 P 0 8 0;1=2
P 5.03005 0.99493996 6 P 0 8 0;1=0
P 5.638 3.907 6 P 0 8 0;1=0
P 1.8317 0.5639 5 P 0 8 0;1=7
P 2.68566998 1.12143002 11 P 0 8 0;1=22
P 2.68566998 2.55943002 11 P 0 8 0;1=22
P 1.46066998 2.68043002 11 P 0 8 0;1=22
P 1.43566998 1.06043002 11 P 0 8 0;1=22
P 6.40038996 0.65353996 13 P 0 8 0;1=23
P 0.29528002 3.73031004 13 P 0 8 0;1=23
P 0.29528002 0.36811004 13 P 0 8 0;1=23
P 6.40038996 4.17835 13 P 0 8 0;1=23
P 6.34055 3.34448996 12 P 0 8 0;1=24
P 6.34055 3.67518996 12 P 0 8 0;1=24
L 3.80999961 -1.25 3.80999961 -1.33 1 N 0 ;0
L 3.80999961 -1.33 3.8500003 -1.33 1 N 0 ;0
L 3.90999902 -1.25 3.90199892 -1.25266614 1 N 0 ;0
L 3.90199892 -1.25266614 3.8960002 -1.25933386 1 N 0 ;0
L 3.8960002 -1.25933386 3.89199921 -1.26733209 1 N 0 ;0
L 3.89199921 -1.26733209 3.8889999 -1.27800138 1 N 0 ;0
L 3.8889999 -1.27800138 3.8880001 -1.29000128 1 N 0 ;0
L 3.8880001 -1.29000128 3.8889999 -1.30200118 1 N 0 ;0
L 3.8889999 -1.30200118 3.89199921 -1.31266801 1 N 0 ;0
L 3.89199921 -1.31266801 3.8960002 -1.3206687 1 N 0 ;0
L 3.8960002 -1.3206687 3.90199892 -1.32733396 1 N 0 ;0
L 3.90199892 -1.32733396 3.90999902 -1.33 1 N 0 ;0
L 3.90999902 -1.33 3.91799911 -1.32733396 1 N 0 ;0
L 3.91799911 -1.32733396 3.9239997 -1.3206687 1 N 0 ;0
L 3.9239997 -1.3206687 3.92800069 -1.31266801 1 N 0 ;0
L 3.92800069 -1.31266801 3.931 -1.30200118 1 N 0 ;0
L 3.931 -1.30200118 3.9319998 -1.29000128 1 N 0 ;0
L 3.9319998 -1.29000128 3.931 -1.27800138 1 N 0 ;0
L 3.931 -1.27800138 3.92800069 -1.26733209 1 N 0 ;0
L 3.92800069 -1.26733209 3.9239997 -1.25933386 1 N 0 ;0
L 3.9239997 -1.25933386 3.91799911 -1.25266614 1 N 0 ;0
L 3.91799911 -1.25266614 3.90999902 -1.25 1 N 0 ;0
L 3.97099941 -1.26333297 3.977 -1.25533465 1 N 0 ;0
L 3.977 -1.25533465 3.9840003 -1.25133307 1 N 0 ;0
L 3.9840003 -1.25133307 3.99200039 -1.25 1 N 0 ;0
L 3.99200039 -1.25 4.0020001 -1.25266614 1 N 0 ;0
L 4.0020001 -1.25266614 4.00900049 -1.25933386 1 N 0 ;0
L 4.00900049 -1.25933386 4.011 -1.26733209 1 N 0 ;0
L 4.011 -1.26733209 4.0100003 -1.27533533 1 N 0 ;0
L 4.0100003 -1.27533533 4.00599931 -1.28200049 1 N 0 ;0
L 4.00599931 -1.28200049 3.9859999 -1.29533346 1 N 0 ;0
L 3.9859999 -1.29533346 3.977 -1.30466722 1 N 0 ;0
L 3.977 -1.30466722 3.97099941 -1.31800266 1 N 0 ;0
L 3.97099941 -1.31800266 3.9689999 -1.33 1 N 0 ;0
L 3.9689999 -1.33 4.011 -1.33 1 N 0 ;0
L 4.04 -1.35666585 4.1 -1.35666585 1 N 0 ;0
L 4.15599961 -1.29000128 4.17600079 -1.29000128 1 N 0 ;0
L 4.17600079 -1.29000128 4.17600079 -1.31400098 1 N 0 ;0
L 4.17600079 -1.31400098 4.1700003 -1.32200177 1 N 0 ;0
L 4.1700003 -1.32200177 4.1629999 -1.32733396 1 N 0 ;0
L 4.1629999 -1.32733396 4.1530002 -1.33 1 N 0 ;0
L 4.1530002 -1.33 4.14300049 -1.32733396 1 N 0 ;0
L 4.14300049 -1.32733396 4.1360002 -1.32200177 1 N 0 ;0
L 4.1360002 -1.32200177 4.12999961 -1.31400098 1 N 0 ;0
L 4.12999961 -1.31400098 4.12599862 -1.30466722 1 N 0 ;0
L 4.12599862 -1.30466722 4.12399911 -1.29400039 1 N 0 ;0
L 4.12399911 -1.29400039 4.12399911 -1.28466663 1 N 0 ;0
L 4.12399911 -1.28466663 4.12599862 -1.27666831 1 N 0 ;0
L 4.12599862 -1.27666831 4.12999961 -1.26733209 1 N 0 ;0
L 4.12999961 -1.26733209 4.1360002 -1.25933386 1 N 0 ;0
L 4.1360002 -1.25933386 4.14199892 -1.25400167 1 N 0 ;0
L 4.14199892 -1.25400167 4.14999902 -1.25 1 N 0 ;0
L 4.14999902 -1.25 4.15699941 -1.25 1 N 0 ;0
L 4.15699941 -1.25 4.16499951 -1.25266614 1 N 0 ;0
L 4.16499951 -1.25266614 4.171 -1.25800079 1 N 0 ;0
L 4.2070003 -1.33 4.2070003 -1.25 1 N 0 ;0
L 4.2070003 -1.25 4.25299961 -1.33 1 N 0 ;0
L 4.25299961 -1.33 4.25299961 -1.25 1 N 0 ;0
L 4.2880001 -1.33 4.2880001 -1.25 1 N 0 ;0
L 4.2880001 -1.25 4.30799951 -1.25 1 N 0 ;0
L 4.30799951 -1.25 4.31599961 -1.25400167 1 N 0 ;0
L 4.31599961 -1.25400167 4.3220001 -1.25933386 1 N 0 ;0
L 4.3220001 -1.25933386 4.32700089 -1.26733209 1 N 0 ;0
L 4.32700089 -1.26733209 4.331 -1.27666831 1 N 0 ;0
L 4.331 -1.27666831 4.3319998 -1.29000128 1 N 0 ;0
L 4.3319998 -1.29000128 4.331 -1.30333415 1 N 0 ;0
L 4.331 -1.30333415 4.32700089 -1.31266801 1 N 0 ;0
L 4.32700089 -1.31266801 4.3220001 -1.3206687 1 N 0 ;0
L 4.3220001 -1.3206687 4.31599961 -1.32600089 1 N 0 ;0
L 4.31599961 -1.32600089 4.30799951 -1.33 1 N 0 ;0
L 4.30799951 -1.33 4.2880001 -1.33 1 N 0 ;0
L 4.38999902 -1.33 4.38999902 -1.25 1 N 0 ;0
L 4.38999902 -1.25 4.3779998 -1.26599911 1 N 0 ;0
L 4.3779998 -1.33 4.40199833 -1.33 1 N 0 ;0
L 3.16 -0.655 3.16 -1.58 2 N 0 ;0
L 1.36 -0.655 1.36 -1.58 2 N 0 ;0
L 1.36 -1.58 5.06 -1.58 2 N 0 ;0
L 5.06 -1.58 5.06 -0.655 2 N 0 ;0
L 5.06 -0.655 1.36 -0.655 2 N 0 ;0
A 1.559 -1.33655 1.559 -1.33655 1.55268002 -1.33655 1 N 0 N;0
A 1.54775 -1.205 1.54775 -1.205 1.53883002 -1.205 1 N 0 N;0
A 1.54763996 -0.99775 1.54763996 -0.99775 1.53871998 -0.99775 1 N 0 N;0
A 1.54063996 -1.10118002 1.54063996 -1.10118002 1.52603996 -1.10118002 1 N 0 N;0
A 1.49695 -1.10118002 1.49695 -1.10118002 1.48656998 -1.10118002 1 N 0 N;0
A 1.45963996 -1.10118002 1.45963996 -1.10118002 1.4533 -1.10118002 1 N 0 N;0
A 1.52135 -0.98681004 1.52135 -0.98681004 1.51503002 -0.98681004 1 N 0 N;0
A 1.79433002 -1.43586998 1.79433002 -1.43586998 1.78798996 -1.43586998 1 N 0 N;0
A 1.79841004 -1.40261004 1.79841004 -1.40261004 1.78798996 -1.40261004 1 N 0 N;0
A 1.80255 -1.36311004 1.80255 -1.36311004 1.78798996 -1.36311004 1 N 0 N;0
A 1.80668996 -1.31528002 1.80668996 -1.31528002 1.78798996 -1.31528002 1 N 0 N;0
A 1.68013002 -1.37456004 1.68013002 -1.37456004 1.67378996 -1.37456004 1 N 0 N;0
A 1.69321998 -1.35033002 1.69321998 -1.35033002 1.6843 -1.35033002 1 N 0 N;0
A 1.7108 -1.31738996 1.7108 -1.31738996 1.69798002 -1.31738996 1 N 0 N;0
A 1.89666998 -1.31511004 1.89666998 -1.31511004 1.88383996 -1.31511004 1 N 0 N;0
A 1.88198996 -1.16876004 1.88198996 -1.16876004 1.85558996 -1.16876004 1 N 0 N;0
A 1.87928002 -1.27801998 1.87928002 -1.27801998 1.86343996 -1.27801998 1 N 0 N;0
A 1.86176998 -1.23075 1.86176998 -1.23075 1.84206004 -1.23075 1 N 0 N;0
A 1.80978996 -1.25916998 1.80978996 -1.25916998 1.78798996 -1.25916998 1 N 0 N;0
A 1.74681004 -1.16876004 1.74681004 -1.16876004 1.72041004 -1.16876004 1 N 0 N;0
A 1.67813002 -1.15513002 1.67813002 -1.15513002 1.65841998 -1.15513002 1 N 0 N;0
A 1.73018002 -1.27816004 1.73018002 -1.27816004 1.71433996 -1.27816004 1 N 0 N;0
A 1.75373002 -1.23081004 1.75373002 -1.23081004 1.73405 -1.23081004 1 N 0 N;0
A 1.65531004 -1.25255 1.65531004 -1.25255 1.63661998 -1.25255 1 N 0 N;0
A 1.69808996 -1.21291998 1.69808996 -1.21291998 1.67628996 -1.21291998 1 N 0 N;0
A 1.81438996 -1.1968 1.81438996 -1.1968 1.78798996 -1.1968 1 N 0 N;0
A 1.6269 -1.1749 1.6269 -1.1749 1.61106004 -1.1749 1 N 0 N;0
A 1.58461004 -1.19126004 1.58461004 -1.19126004 1.57178002 -1.19126004 1 N 0 N;0
A 1.5853 -1.31428002 1.5853 -1.31428002 1.57488996 -1.31428002 1 N 0 N;0
A 1.61735 -1.28638996 1.61735 -1.28638996 1.60276998 -1.28638996 1 N 0 N;0
A 1.88198996 -1.03361004 1.88198996 -1.03361004 1.85558996 -1.03361004 1 N 0 N;0
A 1.71881004 -1.10118002 1.71881004 -1.10118002 1.69238996 -1.10118002 1 N 0 N;0
A 1.65183002 -1.10118002 1.65183002 -1.10118002 1.63003002 -1.10118002 1 N 0 N;0
A 1.67801998 -1.04738996 1.67801998 -1.04738996 1.65831004 -1.04738996 1 N 0 N;0
A 1.74681004 -1.03361004 1.74681004 -1.03361004 1.72041004 -1.03361004 1 N 0 N;0
A 1.69811998 -0.98951004 1.69811998 -0.98951004 1.67631998 -0.98951004 1 N 0 N;0
A 1.81438996 -1.00556004 1.81438996 -1.00556004 1.78798996 -1.00556004 1 N 0 N;0
A 1.59258002 -1.10118002 1.59258002 -1.10118002 1.5739 -1.10118002 1 N 0 N;0
A 1.58451004 -1.01148996 1.58451004 -1.01148996 1.57168002 -1.01148996 1 N 0 N;0
A 1.62681004 -1.02773996 1.62681004 -1.02773996 1.61096998 -1.02773996 1 N 0 N;0
A 1.92148002 -1.21285 1.92148002 -1.21285 1.89968002 -1.21285 1 N 0 N;0
A 1.92148002 -0.98951004 1.92148002 -0.98951004 1.89968002 -0.98951004 1 N 0 N;0
A 1.80978996 -0.9432 1.80978996 -0.9432 1.78798996 -0.9432 1 N 0 N;0
A 1.80668996 -0.88708002 1.80668996 -0.88708002 1.78798996 -0.88708002 1 N 0 N;0
A 1.80255 -0.83923996 1.80255 -0.83923996 1.78798996 -0.83923996 1 N 0 N;0
A 1.8919 -0.88538002 1.8919 -0.88538002 1.87906998 -0.88538002 1 N 0 N;0
A 1.87838996 -0.92456998 1.87838996 -0.92456998 1.86255 -0.92456998 1 N 0 N;0
A 1.65531004 -0.94981004 1.65531004 -0.94981004 1.63661998 -0.94981004 1 N 0 N;0
A 1.73123002 -0.92378002 1.73123002 -0.92378002 1.71538996 -0.92378002 1 N 0 N;0
A 1.71216998 -0.88443996 1.71216998 -0.88443996 1.69935 -0.88443996 1 N 0 N;0
A 1.86225 -0.97178002 1.86225 -0.97178002 1.84253996 -0.97178002 1 N 0 N;0
A 1.75451998 -0.97123996 1.75451998 -0.97123996 1.73483996 -0.97123996 1 N 0 N;0
A 1.61741998 -0.91601004 1.61741998 -0.91601004 1.60283996 -0.91601004 1 N 0 N;0
A 1.5853 -0.88808996 1.5853 -0.88808996 1.57488996 -0.88808996 1 N 0 N;0
A 1.79841004 -0.79975 1.79841004 -0.79975 1.78798996 -0.79975 1 N 0 N;0
A 1.79433002 -0.76648002 1.79433002 -0.76648002 1.78798996 -0.76648002 1 N 0 N;0
A 1.92135 -1.36781004 1.92135 -1.36781004 1.91503996 -1.36781004 1 N 0 N;0
A 1.91096004 -1.34658002 1.91096004 -1.34658002 1.90203996 -1.34658002 1 N 0 N;0
A 2.19078996 -1.1806 2.26591004 -1.16473002 2.21741014 -1.12088169 1 N 0 N;0
A 2.15903002 -1.1402 2.19078996 -1.18061004 2.22093406 -1.12423278 1 N 0 N;0
A 2.05721004 -1.16178996 2.08853002 -1.16658996 2.08281614 -1.09929134 1 N 0 N;0
A 2.00546998 -1.13951998 2.03345 -1.17196004 2.07793927 -1.10530069 1 N 0 N;0
A 2.03346004 -1.17195 2.0847 -1.18461004 2.07891181 -1.09801299 1 N 0 N;0
A 2.0847 -1.18461998 2.14261004 -1.15663002 2.07348435 -1.08751378 1 N 0 N;0
A 2.08853996 -1.16658002 2.13313002 -1.14451998 2.06368967 -1.06025512 1 N 0 N;0
A 1.95808002 -1.25255 1.95808002 -1.25255 1.93938996 -1.25255 1 N 0 N;0
A 1.98775 -1.28635 1.98775 -1.28635 1.97316998 -1.28635 1 N 0 N;0
A 2.27411998 -1.11835 2.15906004 -1.11835 2.21658996 -1.11611998 1 N 0 N;0
L 2.25188002 -1.11418002 2.1807 -1.11418002 1 N 0 ;0
L 2.1807 -1.11418002 2.1807 -1.11398996 1 N 8191 ;0
A 2.25188996 -1.11398996 2.18071004 -1.11398996 2.2163 -1.1124 1 N 0 N;0
A 2.08028996 -1.03428996 2.02048996 -1.08258996 2.0798126 -1.09486801 1 N 0 N;0
A 2.13151998 -1.05146004 2.0803 -1.0343 2.0802999 -1.11932195 1 N 0 N;0
A 2.1315 -1.05146998 2.14175 -1.03951004 2.1356003 -1.04461171 1 N 0 N;0
A 2.14175 -1.03951004 2.08283002 -1.01613002 2.07772461 -1.11492805 1 N 0 N;0
A 2.08283996 -1.01611998 2.00698002 -1.05835 2.08064724 -1.10143169 1 N 0 N;0
L 2.27413002 -1.12868996 2.18073996 -1.12868996 1 N 0 ;0
A 2.18075 -1.12868996 2.19083002 -1.15751998 2.22417795 -1.12968307 1 N 0 N;0
A 2.19083002 -1.15753002 2.25311004 -1.15211004 2.21927195 -1.12381791 1 N 0 N;0
L 2.15903996 -1.1402 2.15903996 -1.11835 1 N 8191 ;0
A 2.02048996 -1.0826 2.05721998 -1.16181004 2.09087933 -1.0980811 1 N 0 N;0
A 2.00698996 -1.05836004 2.00546998 -1.13953002 2.09672953 -1.10063967 1 N 0 N;0
A 2.14258996 -1.15661004 2.13313996 -1.14453002 2.13544892 -1.15246004 1 N 0 N;0
A 1.95808002 -0.94981004 1.95808002 -0.94981004 1.93938996 -0.94981004 1 N 0 N;0
A 1.90183996 -0.8525 1.90183996 -0.8525 1.89291004 -0.8525 1 N 0 N;0
A 1.91108002 -0.82726998 1.91108002 -0.82726998 1.90473996 -0.82726998 1 N 0 N;0
L 2.32081004 -1.02041004 2.32081004 -1.17625 1 N 0 ;0
A 2.49568002 -1.15528996 2.47898002 -1.16443002 2.4882003 -1.1614502 1 N 0 N;0
A 2.47896998 -1.16443996 2.50283002 -1.18086004 2.51649242 -1.13546152 1 N 0 N;0
A 2.50281998 -1.18086998 2.54318002 -1.1834 2.52887392 -1.08843022 1 N 0 N;0
A 2.52306998 -1.16761004 2.52848996 -1.16771998 2.52673258 -1.12070098 1 N 0 N;0
A 2.49566004 -1.15528996 2.52306998 -1.1676 2.5255122 -1.12549094 1 N 0 N;0
A 2.37851998 -1.15753002 2.4408 -1.15211004 2.40696191 -1.12381791 1 N 0 N;0
A 2.45358002 -1.16471998 2.44078996 -1.1521 2.44541191 -1.16020689 1 N 0 N;0
A 2.37848002 -1.1806 2.4536 -1.16473002 2.4051001 -1.12088169 1 N 0 N;0
A 2.34673002 -1.1402 2.37848996 -1.18061004 2.40863406 -1.12423278 1 N 0 N;0
A 2.2659 -1.16471998 2.25311004 -1.1521 2.25773199 -1.16020689 1 N 0 N;0
A 2.3006 -1.17626004 2.3208 -1.17626004 2.3107 -1.17386841 1 N 0 N;0
L 2.30058996 -1.17625 2.30058996 -1.02033996 1 N 0 ;0
A 2.50836998 -1.10106004 2.54306004 -1.11513002 2.56106673 -1.02093386 1 N 0 N;0
A 2.51081004 -1.07948002 2.50836998 -1.10103996 2.51886093 -1.09130915 1 N 0 N;0
A 2.53611004 -1.07688996 2.5108 -1.07948996 2.52742205 -1.11680827 1 N 0 N;0
A 2.56883996 -1.07368002 2.50178002 -1.06358996 2.5273123 -1.12178858 1 N 0 N;0
A 2.50178996 -1.06358996 2.48536998 -1.08248996 2.52926211 -1.10403986 1 N 0 N;0
L 2.48536998 -1.0825 2.48536998 -1.09748002 1 N 8191 ;0
A 2.48536998 -1.09748002 2.49956004 -1.12031004 2.51189104 -1.09682067 1 N 0 N;0
A 2.46181004 -1.11835 2.34675 -1.11835 2.40428002 -1.11611998 1 N 0 N;0
L 2.43956998 -1.11418002 2.36841004 -1.11418002 1 N 0 ;0
L 2.36841004 -1.11418002 2.36841004 -1.11398996 1 N 8191 ;0
A 2.43958002 -1.11398996 2.3684 -1.11398996 2.40398996 -1.1124 1 N 0 N;0
L 2.43956998 -1.11398996 2.43956998 -1.11418002 1 N 8191 ;0
A 2.49955 -1.1203 2.52723002 -1.12985 2.58163209 -0.92727982 1 N 0 N;0
A 2.55001998 -1.14328002 2.52723002 -1.12986004 2.51462185 -1.17733228 1 N 0 N;0
L 2.46181004 -1.12868996 2.36843996 -1.12868996 1 N 0 ;0
A 2.36843996 -1.12868996 2.37851998 -1.15751998 2.41186801 -1.12968307 1 N 0 N;0
L 2.34675 -1.1402 2.34675 -1.11835 1 N 8191 ;0
L 2.46181004 -1.11835 2.46181004 -1.12868996 1 N 8191 ;0
L 2.25188002 -1.11398996 2.25188002 -1.11418002 1 N 8191 ;0
A 2.3208 -1.02041004 2.3006 -1.02033996 2.31069163 -1.02276978 1 N 0 N;0
L 2.27413002 -1.11835 2.27413002 -1.12868996 1 N 8191 ;0
A 2.52848996 -1.16771004 2.54891998 -1.15895 2.52774557 -1.13777087 1 N 0 N;0
A 2.55608002 -1.08618002 2.53611998 -1.07688996 2.5249185 -1.12704419 1 N 0 N;0
L 2.71926004 -1.06796998 2.71926004 -1.17483996 1 N 0 ;0
A 2.78888996 -1.16296998 2.81508002 -1.16676998 2.8083499 -1.12100167 1 N 0 N;0
A 2.8151 -1.16675 2.83966004 -1.15211998 2.80521398 -1.12222392 1 N 0 N;0
A 2.85201004 -1.16508002 2.83966004 -1.15211004 2.84505768 -1.15933514 1 N 0 N;0
L 2.85201004 -1.16508002 2.84523996 -1.17161004 1 N 8191 ;0
A 2.81425 -1.1835 2.84525 -1.17161004 2.81425 -1.13714291 1 N 0 N;0
L 2.81425 -1.1835 2.79571004 -1.1835 1 N 8191 ;0
A 2.75886998 -1.16443002 2.79571998 -1.18351998 2.80278976 -1.12476142 1 N 0 N;0
A 2.74528996 -1.13568002 2.75888002 -1.16443002 2.80246565 -1.12624016 1 N 0 N;0
A 2.54316998 -1.1834 2.56906004 -1.1647 2.5305814 -1.13869892 1 N 0 N;0
A 2.56906004 -1.1647 2.57053996 -1.13728002 2.53763041 -1.14925374 1 N 0 N;0
A 2.65463996 -1.18351998 2.66863996 -1.17373996 2.65440246 -1.16826969 1 N 0 N;0
L 2.65463002 -1.1835 2.64165 -1.1835 1 N 8191 ;0
A 2.60955 -1.16043002 2.64163996 -1.18351004 2.63911063 -1.15317815 1 N 0 N;0
A 2.62978002 -1.15461998 2.66001998 -1.16328996 2.6502374 -1.14033868 1 N 0 N;0
A 2.66863996 -1.17375 2.66001998 -1.16328996 2.66100344 -1.17126132 1 N 0 N;0
A 2.6962 -1.17483996 2.71926004 -1.17483996 2.70773002 -1.17286427 1 N 0 N;0
L 2.69618996 -1.17483996 2.69618996 -1.06796998 1 N 0 ;0
A 2.83833002 -1.09275 2.82661998 -1.08201998 2.74555758 -1.18224094 1 N 0 N;0
A 2.82661998 -1.08198996 2.80036998 -1.07538996 2.80348839 -1.11848878 1 N 0 N;0
A 2.80036004 -1.07541998 2.76848996 -1.09933002 2.80700217 -1.1174685 1 N 0 N;0
A 2.76848996 -1.09931998 2.76446004 -1.12066004 2.82315728 -1.120694 1 N 0 N;0
A 2.74998002 -1.09273996 2.74528996 -1.11838996 2.8498563 -1.12425591 1 N 0 N;0
A 2.7954 -1.05776998 2.74998996 -1.09273996 2.80799961 -1.12109961 1 N 0 N;0
L 2.79541004 -1.05776998 2.80918996 -1.05776998 1 N 8191 ;0
A 2.85401998 -1.08106004 2.80918996 -1.05776998 2.80626024 -1.1181998 1 N 0 N;0
A 2.83833002 -1.09273996 2.85403002 -1.08106004 2.84418386 -1.08421683 1 N 0 N;0
L 2.76445 -1.12066004 2.76445 -1.12943002 1 N 8191 ;0
A 2.76446004 -1.12943002 2.76836998 -1.14305 2.80607844 -1.12485364 1 N 0 N;0
A 2.76836998 -1.14305 2.78891004 -1.16296998 2.80906152 -1.12164144 1 N 0 N;0
L 2.74528996 -1.13566004 2.74528996 -1.11838996 1 N 8191 ;0
A 2.55606004 -1.0862 2.56885 -1.07366998 2.56205354 -1.0795252 1 N 0 N;0
L 2.60953996 -1.07953996 2.59981998 -1.07953996 1 N 8191 ;0
A 2.5993 -1.05931998 2.59981004 -1.07955 2.6022813 -1.06936624 1 N 0 N;0
L 2.5993 -1.05931998 2.60953996 -1.05931998 1 N 8191 ;0
L 2.60953996 -1.05931998 2.60953996 -1.03491998 1 N 8191 ;0
A 2.62971998 -1.03418002 2.60953996 -1.03491004 2.61966791 -1.03559478 1 N 0 N;0
L 2.62971004 -1.03418996 2.62978002 -1.05931998 1 N 8191 ;0
L 2.62978002 -1.05931998 2.66008002 -1.05931998 1 N 8191 ;0
A 2.66003996 -1.07955 2.66008002 -1.05931998 2.65827421 -1.0694314 1 N 0 N;0
L 2.66003002 -1.07953996 2.62978002 -1.07953996 1 N 8191 ;0
A 2.71926004 -1.06796998 2.6962 -1.06796998 2.70773002 -1.0720561 1 N 0 N;0
A 2.71968996 -1.02341998 2.71968996 -1.02341998 2.70775 -1.02341998 1 N 0 N;0
A 2.57053996 -1.13728996 2.54306998 -1.11513002 2.53584449 -1.15219301 1 N 0 N;0
A 2.54891998 -1.15895 2.55001004 -1.14328002 2.54127923 -1.15054557 1 N 0 N;0
L 2.60953996 -1.16041004 2.60953996 -1.07953996 1 N 0 ;0
L 2.62978002 -1.07953996 2.62978002 -1.15463002 1 N 0 ;0
L 2.98495 -1.09393996 2.98495 -1.17625 1 N 0 ;0
A 2.96473996 -1.17626998 2.98493996 -1.17626998 2.97483996 -1.17442303 1 N 0 N;0
L 2.96473002 -1.17625 2.96473002 -1.17226004 1 N 8191 ;0
A 2.94165 -1.1835 2.96471004 -1.17226004 2.93076516 -1.1318935 1 N 0 N;0
L 2.94165 -1.1835 2.90701004 -1.1835 1 N 8191 ;0
A 2.90671004 -1.10841998 2.90703002 -1.18351004 2.9153065 -1.14592904 1 N 0 N;0
A 2.91853002 -1.12288996 2.91853002 -1.16618996 2.92048209 -1.14453996 1 N 0 N;0
L 2.91853002 -1.1662 2.94456004 -1.1662 1 N 8191 ;0
A 2.94456998 -1.16618996 2.94456998 -1.12288996 2.94406004 -1.14453996 1 N 0 N;0
A 2.96473002 -1.09686004 2.94741998 -1.07955 2.94874833 -1.09553169 1 N 0 N;0
L 2.9474 -1.07953996 2.90986998 -1.07953996 1 N 8191 ;0
A 2.90986998 -1.07953996 2.89821004 -1.0852 2.92433445 -1.12417766 1 N 0 N;0
A 2.89111998 -1.07086004 2.8982 -1.0852 2.8969689 -1.07688996 1 N 0 N;0
A 2.91561998 -1.05931998 2.89111998 -1.07085 2.92146033 -1.103525 1 N 0 N;0
L 2.91563002 -1.05931998 2.95031004 -1.05931998 1 N 8191 ;0
A 2.98496004 -1.09393996 2.95031004 -1.05933002 2.9453438 -1.09895197 1 N 0 N;0
A 2.92878996 -1.10535 2.9067 -1.10841998 2.93158484 -1.20646998 1 N 0 N;0
A 2.96471998 -1.10841004 2.92878002 -1.10536004 2.93215738 -1.27883829 1 N 0 N;0
L 2.96473002 -1.10841004 2.96473002 -1.09686004 1 N 8191 ;0
L 2.94456004 -1.12288002 2.91853002 -1.12288002 1 N 8191 ;0
L 3.04731004 -1.06001004 3.04191998 -1.07631998 1 N 8191 ;0
L 3.04191998 -1.07631998 3.03648002 -1.06001004 1 N 8191 ;0
L 3.03648002 -1.06001004 3.03243002 -1.06001004 1 N 8191 ;0
L 3.03243002 -1.06001004 3.02698002 -1.08543996 1 N 8191 ;0
L 3.02698002 -1.08543996 3.03226004 -1.08543996 1 N 8191 ;0
L 3.03226004 -1.08543996 3.03501004 -1.06886998 1 N 8191 ;0
L 3.03501004 -1.06886998 3.04086004 -1.08543996 1 N 8191 ;0
L 3.04086004 -1.08543996 3.04308996 -1.08543996 1 N 8191 ;0
L 3.04308996 -1.08543996 3.04888996 -1.06871004 1 N 8191 ;0
L 3.04888996 -1.06871004 3.05171004 -1.08543996 1 N 8191 ;0
L 3.05171004 -1.08543996 3.05713002 -1.08543996 1 N 8191 ;0
L 3.05713002 -1.08543996 3.05163996 -1.06001004 1 N 8191 ;0
L 3.05163996 -1.06001004 3.04731004 -1.06001004 1 N 8191 ;0
L 3.01066998 -1.06508002 3.00223002 -1.06508002 1 N 8191 ;0
L 3.00223002 -1.06508002 3.00223002 -1.06001004 1 N 8191 ;0
L 3.00223002 -1.06001004 3.02461004 -1.06001004 1 N 8191 ;0
L 3.02461004 -1.06001004 3.02461004 -1.06508002 1 N 8191 ;0
L 3.02461004 -1.06508002 3.01615 -1.06508002 1 N 8191 ;0
L 3.01615 -1.06508002 3.01615 -1.08533996 1 N 8191 ;0
L 3.01615 -1.08533996 3.01066998 -1.08533996 1 N 8191 ;0
L 3.01066998 -1.08533996 3.01066998 -1.06508002 1 N 8191 ;0
L 3.36933297 -0.955 3.36933297 -0.88 0 N 0 ;0
L 3.36933297 -0.88 3.39173337 -0.88 0 N 0 ;0
L 3.39173337 -0.88 3.3992001 -0.88375157 0 N 0 ;0
L 3.3992001 -0.88375157 3.40480059 -0.8924997 0 N 0 ;0
L 3.40480059 -0.8924997 3.40666693 -0.9024998 0 N 0 ;0
L 3.40666693 -0.9024998 3.40480059 -0.9125 0 N 0 ;0
L 3.40480059 -0.9125 3.40013327 -0.92000069 0 N 0 ;0
L 3.40013327 -0.92000069 3.39173337 -0.92375217 0 N 0 ;0
L 3.39173337 -0.92375217 3.36933297 -0.92375217 0 N 0 ;0
L 3.44619931 -0.95749941 3.47980059 -0.88 0 N 0 ;0
L 3.51653356 -0.955 3.51653356 -0.88 0 N 0 ;0
L 3.51653356 -0.88 3.55946634 -0.955 0 N 0 ;0
L 3.55946634 -0.955 3.55946634 -0.88 0 N 0 ;0
L 3.68799911 -0.95749941 3.68613287 -0.9562497 0 N 0 ;0
L 3.68613287 -0.9562497 3.68613287 -0.9537503 0 N 0 ;0
L 3.68613287 -0.9537503 3.68799911 -0.95250059 0 N 0 ;0
L 3.68799911 -0.95250059 3.68986703 -0.9537503 0 N 0 ;0
L 3.68986703 -0.9537503 3.68986703 -0.9562497 0 N 0 ;0
L 3.68986703 -0.9562497 3.68799911 -0.95749941 0 N 0 ;0
L 3.68799911 -0.92375217 3.68613287 -0.9225001 0 N 0 ;0
L 3.68613287 -0.9225001 3.68613287 -0.92000069 0 N 0 ;0
L 3.68613287 -0.92000069 3.68799911 -0.91875089 0 N 0 ;0
L 3.68799911 -0.91875089 3.68986703 -0.92000069 0 N 0 ;0
L 3.68986703 -0.92000069 3.68986703 -0.9225001 0 N 0 ;0
L 3.68986703 -0.9225001 3.68799911 -0.92375217 0 N 0 ;0
L 3.81933297 -0.955 3.81933297 -0.88 0 N 0 ;0
L 3.81933297 -0.88 3.84266644 -0.88 0 N 0 ;0
L 3.84266644 -0.88 3.85013327 -0.88375157 0 N 0 ;0
L 3.85013327 -0.88375157 3.85480059 -0.88875049 0 N 0 ;0
L 3.85480059 -0.88875049 3.85666693 -0.89875059 0 N 0 ;0
L 3.85666693 -0.89875059 3.85480059 -0.90875079 0 N 0 ;0
L 3.85480059 -0.90875079 3.8492001 -0.91499941 0 N 0 ;0
L 3.8492001 -0.91499941 3.84266644 -0.91875089 0 N 0 ;0
L 3.84266644 -0.91875089 3.81933297 -0.91875089 0 N 0 ;0
L 3.84266644 -0.91875089 3.85666693 -0.955 0 N 0 ;0
L 3.9242001 -0.955 3.9242001 -0.88 0 N 0 ;0
L 3.9242001 -0.88 3.88966565 -0.93375 0 N 0 ;0
L 3.88966565 -0.93375 3.93633425 -0.93375 0 N 0 ;0
L 3.98799911 -0.88 3.98053228 -0.88249951 0 N 0 ;0
L 3.98053228 -0.88249951 3.97493346 -0.88875049 0 N 0 ;0
L 3.97493346 -0.88875049 3.97119931 -0.89624882 0 N 0 ;0
L 3.97119931 -0.89624882 3.9683999 -0.90625128 0 N 0 ;0
L 3.9683999 -0.90625128 3.96746673 -0.91750118 0 N 0 ;0
L 3.96746673 -0.91750118 3.9683999 -0.92875108 0 N 0 ;0
L 3.9683999 -0.92875108 3.97119931 -0.93875128 0 N 0 ;0
L 3.97119931 -0.93875128 3.97493346 -0.94625187 0 N 0 ;0
L 3.97493346 -0.94625187 3.98053228 -0.95250059 0 N 0 ;0
L 3.98053228 -0.95250059 3.98799911 -0.955 0 N 0 ;0
L 3.98799911 -0.955 3.99546585 -0.95250059 0 N 0 ;0
L 3.99546585 -0.95250059 4.00106644 -0.94625187 0 N 0 ;0
L 4.00106644 -0.94625187 4.00480059 -0.93875128 0 N 0 ;0
L 4.00480059 -0.93875128 4.0076 -0.92875108 0 N 0 ;0
L 4.0076 -0.92875108 4.00853317 -0.91750118 0 N 0 ;0
L 4.00853317 -0.91750118 4.0076 -0.90625128 0 N 0 ;0
L 4.0076 -0.90625128 4.00480059 -0.89624882 0 N 0 ;0
L 4.00480059 -0.89624882 4.00106644 -0.88875049 0 N 0 ;0
L 4.00106644 -0.88875049 3.99546585 -0.88249951 0 N 0 ;0
L 3.99546585 -0.88249951 3.98799911 -0.88 0 N 0 ;0
L 4.06299911 -0.88 4.05553228 -0.88249951 0 N 0 ;0
L 4.05553228 -0.88249951 4.04993346 -0.88875049 0 N 0 ;0
L 4.04993346 -0.88875049 4.04619931 -0.89624882 0 N 0 ;0
L 4.04619931 -0.89624882 4.0433999 -0.90625128 0 N 0 ;0
L 4.0433999 -0.90625128 4.04246673 -0.91750118 0 N 0 ;0
L 4.04246673 -0.91750118 4.0433999 -0.92875108 0 N 0 ;0
L 4.0433999 -0.92875108 4.04619931 -0.93875128 0 N 0 ;0
L 4.04619931 -0.93875128 4.04993346 -0.94625187 0 N 0 ;0
L 4.04993346 -0.94625187 4.05553228 -0.95250059 0 N 0 ;0
L 4.05553228 -0.95250059 4.06299911 -0.955 0 N 0 ;0
L 4.06299911 -0.955 4.07046585 -0.95250059 0 N 0 ;0
L 4.07046585 -0.95250059 4.07606644 -0.94625187 0 N 0 ;0
L 4.07606644 -0.94625187 4.07980059 -0.93875128 0 N 0 ;0
L 4.07980059 -0.93875128 4.0826 -0.92875108 0 N 0 ;0
L 4.0826 -0.92875108 4.08353317 -0.91750118 0 N 0 ;0
L 4.08353317 -0.91750118 4.0826 -0.90625128 0 N 0 ;0
L 4.0826 -0.90625128 4.07980059 -0.89624882 0 N 0 ;0
L 4.07980059 -0.89624882 4.07606644 -0.88875049 0 N 0 ;0
L 4.07606644 -0.88875049 4.07046585 -0.88249951 0 N 0 ;0
L 4.07046585 -0.88249951 4.06299911 -0.88 0 N 0 ;0
L 4.12026614 -0.92375217 4.1267998 -0.91499941 0 N 0 ;0
L 4.1267998 -0.91499941 4.1324003 -0.91000049 0 N 0 ;0
L 4.1324003 -0.91000049 4.13986703 -0.90750108 0 N 0 ;0
L 4.13986703 -0.90750108 4.14640069 -0.91000049 0 N 0 ;0
L 4.14640069 -0.91000049 4.15106644 -0.91499941 0 N 0 ;0
L 4.15106644 -0.91499941 4.15480059 -0.9225001 0 N 0 ;0
L 4.15480059 -0.9225001 4.15573376 -0.93125059 0 N 0 ;0
L 4.15573376 -0.93125059 4.15480059 -0.93875128 0 N 0 ;0
L 4.15480059 -0.93875128 4.15106644 -0.94625187 0 N 0 ;0
L 4.15106644 -0.94625187 4.14546585 -0.95250059 0 N 0 ;0
L 4.14546585 -0.95250059 4.13893396 -0.955 0 N 0 ;0
L 4.13893396 -0.955 4.13146713 -0.95250059 0 N 0 ;0
L 4.13146713 -0.95250059 4.12493346 -0.94500217 0 N 0 ;0
L 4.12493346 -0.94500217 4.12119931 -0.93375 0 N 0 ;0
L 4.12119931 -0.93375 4.12026614 -0.92125039 0 N 0 ;0
L 4.12026614 -0.92125039 4.12213238 -0.90500157 0 N 0 ;0
L 4.12213238 -0.90500157 4.12493346 -0.89624882 0 N 0 ;0
L 4.12493346 -0.89624882 4.12959921 -0.88750069 0 N 0 ;0
L 4.12959921 -0.88750069 4.13613287 -0.8812498 0 N 0 ;0
L 4.13613287 -0.8812498 4.14266644 -0.88 0 N 0 ;0
L 4.14266644 -0.88 4.1492001 -0.88249951 0 N 0 ;0
L 4.1492001 -0.88249951 4.15386752 -0.88875049 0 N 0 ;0
L 4.20086663 -0.93000079 4.22513327 -0.93000079 0 N 0 ;0
L 4.29546585 -0.91499941 4.2992001 -0.9112502 0 N 0 ;0
L 4.2992001 -0.9112502 4.30199951 -0.90500157 0 N 0 ;0
L 4.30199951 -0.90500157 4.30386752 -0.89624882 0 N 0 ;0
L 4.30386752 -0.89624882 4.30199951 -0.88875049 0 N 0 ;0
L 4.30199951 -0.88875049 4.29826703 -0.88375157 0 N 0 ;0
L 4.29826703 -0.88375157 4.29173337 -0.88 0 N 0 ;0
L 4.29173337 -0.88 4.26653356 -0.88 0 N 0 ;0
L 4.26653356 -0.88 4.26653356 -0.955 0 N 0 ;0
L 4.26653356 -0.955 4.29733386 -0.955 0 N 0 ;0
L 4.29733386 -0.955 4.30386752 -0.95000108 0 N 0 ;0
L 4.30386752 -0.95000108 4.3076 -0.94250039 0 N 0 ;0
L 4.3076 -0.94250039 4.30946634 -0.93375 0 N 0 ;0
L 4.30946634 -0.93375 4.3076 -0.92500187 0 N 0 ;0
L 4.3076 -0.92500187 4.30199951 -0.91750118 0 N 0 ;0
L 4.30199951 -0.91750118 4.29546585 -0.91499941 0 N 0 ;0
L 4.29546585 -0.91499941 4.26653356 -0.91499941 0 N 0 ;0
L 4.36299911 -0.88 4.35553228 -0.88249951 0 N 0 ;0
L 4.35553228 -0.88249951 4.34993346 -0.88875049 0 N 0 ;0
L 4.34993346 -0.88875049 4.34619931 -0.89624882 0 N 0 ;0
L 4.34619931 -0.89624882 4.3433999 -0.90625128 0 N 0 ;0
L 4.3433999 -0.90625128 4.34246673 -0.91750118 0 N 0 ;0
L 4.34246673 -0.91750118 4.3433999 -0.92875108 0 N 0 ;0
L 4.3433999 -0.92875108 4.34619931 -0.93875128 0 N 0 ;0
L 4.34619931 -0.93875128 4.34993346 -0.94625187 0 N 0 ;0
L 4.34993346 -0.94625187 4.35553228 -0.95250059 0 N 0 ;0
L 4.35553228 -0.95250059 4.36299911 -0.955 0 N 0 ;0
L 4.36299911 -0.955 4.37046585 -0.95250059 0 N 0 ;0
L 4.37046585 -0.95250059 4.37606644 -0.94625187 0 N 0 ;0
L 4.37606644 -0.94625187 4.37980059 -0.93875128 0 N 0 ;0
L 4.37980059 -0.93875128 4.3826 -0.92875108 0 N 0 ;0
L 4.3826 -0.92875108 4.38353317 -0.91750118 0 N 0 ;0
L 4.38353317 -0.91750118 4.3826 -0.90625128 0 N 0 ;0
L 4.3826 -0.90625128 4.37980059 -0.89624882 0 N 0 ;0
L 4.37980059 -0.89624882 4.37606644 -0.88875049 0 N 0 ;0
L 4.37606644 -0.88875049 4.37046585 -0.88249951 0 N 0 ;0
L 4.37046585 -0.88249951 4.36299911 -0.88 0 N 0 ;0
L 4.43799911 -0.88 4.43053228 -0.88249951 0 N 0 ;0
L 4.43053228 -0.88249951 4.42493346 -0.88875049 0 N 0 ;0
L 4.42493346 -0.88875049 4.42119931 -0.89624882 0 N 0 ;0
L 4.42119931 -0.89624882 4.4183999 -0.90625128 0 N 0 ;0
L 4.4183999 -0.90625128 4.41746673 -0.91750118 0 N 0 ;0
L 4.41746673 -0.91750118 4.4183999 -0.92875108 0 N 0 ;0
L 4.4183999 -0.92875108 4.42119931 -0.93875128 0 N 0 ;0
L 4.42119931 -0.93875128 4.42493346 -0.94625187 0 N 0 ;0
L 4.42493346 -0.94625187 4.43053228 -0.95250059 0 N 0 ;0
L 4.43053228 -0.95250059 4.43799911 -0.955 0 N 0 ;0
L 4.43799911 -0.955 4.44546585 -0.95250059 0 N 0 ;0
L 4.44546585 -0.95250059 4.45106644 -0.94625187 0 N 0 ;0
L 4.45106644 -0.94625187 4.45480059 -0.93875128 0 N 0 ;0
L 4.45480059 -0.93875128 4.4576 -0.92875108 0 N 0 ;0
L 4.4576 -0.92875108 4.45853317 -0.91750118 0 N 0 ;0
L 4.45853317 -0.91750118 4.4576 -0.90625128 0 N 0 ;0
L 4.4576 -0.90625128 4.45480059 -0.89624882 0 N 0 ;0
L 4.45480059 -0.89624882 4.45106644 -0.88875049 0 N 0 ;0
L 4.45106644 -0.88875049 4.44546585 -0.88249951 0 N 0 ;0
L 4.44546585 -0.88249951 4.43799911 -0.88 0 N 0 ;0
L 4.51299911 -0.88 4.50553228 -0.88249951 0 N 0 ;0
L 4.50553228 -0.88249951 4.49993346 -0.88875049 0 N 0 ;0
L 4.49993346 -0.88875049 4.49619931 -0.89624882 0 N 0 ;0
L 4.49619931 -0.89624882 4.4933999 -0.90625128 0 N 0 ;0
L 4.4933999 -0.90625128 4.49246673 -0.91750118 0 N 0 ;0
L 4.49246673 -0.91750118 4.4933999 -0.92875108 0 N 0 ;0
L 4.4933999 -0.92875108 4.49619931 -0.93875128 0 N 0 ;0
L 4.49619931 -0.93875128 4.49993346 -0.94625187 0 N 0 ;0
L 4.49993346 -0.94625187 4.50553228 -0.95250059 0 N 0 ;0
L 4.50553228 -0.95250059 4.51299911 -0.955 0 N 0 ;0
L 4.51299911 -0.955 4.52046585 -0.95250059 0 N 0 ;0
L 4.52046585 -0.95250059 4.52606644 -0.94625187 0 N 0 ;0
L 4.52606644 -0.94625187 4.52980059 -0.93875128 0 N 0 ;0
L 4.52980059 -0.93875128 4.5326 -0.92875108 0 N 0 ;0
L 4.5326 -0.92875108 4.53353317 -0.91750118 0 N 0 ;0
L 4.53353317 -0.91750118 4.5326 -0.90625128 0 N 0 ;0
L 4.5326 -0.90625128 4.52980059 -0.89624882 0 N 0 ;0
L 4.52980059 -0.89624882 4.52606644 -0.88875049 0 N 0 ;0
L 4.52606644 -0.88875049 4.52046585 -0.88249951 0 N 0 ;0
L 4.52046585 -0.88249951 4.51299911 -0.88 0 N 0 ;0
L 4.58799911 -0.955 4.58799911 -0.88 0 N 0 ;0
L 4.58799911 -0.88 4.5767998 -0.89499911 0 N 0 ;0
L 4.5767998 -0.955 4.59919843 -0.955 0 N 0 ;0
L 4.65086663 -0.93000079 4.67513327 -0.93000079 0 N 0 ;0
L 4.73799911 -0.88 4.73053228 -0.88249951 0 N 0 ;0
L 4.73053228 -0.88249951 4.72493346 -0.88875049 0 N 0 ;0
L 4.72493346 -0.88875049 4.72119931 -0.89624882 0 N 0 ;0
L 4.72119931 -0.89624882 4.7183999 -0.90625128 0 N 0 ;0
L 4.7183999 -0.90625128 4.71746673 -0.91750118 0 N 0 ;0
L 4.71746673 -0.91750118 4.7183999 -0.92875108 0 N 0 ;0
L 4.7183999 -0.92875108 4.72119931 -0.93875128 0 N 0 ;0
L 4.72119931 -0.93875128 4.72493346 -0.94625187 0 N 0 ;0
L 4.72493346 -0.94625187 4.73053228 -0.95250059 0 N 0 ;0
L 4.73053228 -0.95250059 4.73799911 -0.955 0 N 0 ;0
L 4.73799911 -0.955 4.74546585 -0.95250059 0 N 0 ;0
L 4.74546585 -0.95250059 4.75106644 -0.94625187 0 N 0 ;0
L 4.75106644 -0.94625187 4.75480059 -0.93875128 0 N 0 ;0
L 4.75480059 -0.93875128 4.7576 -0.92875108 0 N 0 ;0
L 4.7576 -0.92875108 4.75853317 -0.91750118 0 N 0 ;0
L 4.75853317 -0.91750118 4.7576 -0.90625128 0 N 0 ;0
L 4.7576 -0.90625128 4.75480059 -0.89624882 0 N 0 ;0
L 4.75480059 -0.89624882 4.75106644 -0.88875049 0 N 0 ;0
L 4.75106644 -0.88875049 4.74546585 -0.88249951 0 N 0 ;0
L 4.74546585 -0.88249951 4.73799911 -0.88 0 N 0 ;0
L 4.79526614 -0.8924997 4.80086663 -0.88500128 0 N 0 ;0
L 4.80086663 -0.88500128 4.8074003 -0.8812498 0 N 0 ;0
L 4.8074003 -0.8812498 4.81486703 -0.88 0 N 0 ;0
L 4.81486703 -0.88 4.8242001 -0.88249951 0 N 0 ;0
L 4.8242001 -0.88249951 4.83073376 -0.88875049 0 N 0 ;0
L 4.83073376 -0.88875049 4.8326 -0.89624882 0 N 0 ;0
L 4.8326 -0.89624882 4.83166693 -0.90375187 0 N 0 ;0
L 4.83166693 -0.90375187 4.82793268 -0.91000049 0 N 0 ;0
L 4.82793268 -0.91000049 4.80926654 -0.9225001 0 N 0 ;0
L 4.80926654 -0.9225001 4.80086663 -0.93125059 0 N 0 ;0
L 4.80086663 -0.93125059 4.79526614 -0.94375246 0 N 0 ;0
L 4.79526614 -0.94375246 4.7933999 -0.955 0 N 0 ;0
L 4.7933999 -0.955 4.8326 -0.955 0 N 0 ;0
L 3.36746673 -1.205 3.36746673 -1.13 0 N 0 ;0
L 3.36746673 -1.13 3.38613287 -1.13 0 N 0 ;0
L 3.38613287 -1.13 3.39359961 -1.13375157 0 N 0 ;0
L 3.39359961 -1.13375157 3.3992001 -1.13875049 0 N 0 ;0
L 3.3992001 -1.13875049 3.40386752 -1.14624882 0 N 0 ;0
L 3.40386752 -1.14624882 3.4076 -1.15500157 0 N 0 ;0
L 3.4076 -1.15500157 3.40853317 -1.16750118 0 N 0 ;0
L 3.40853317 -1.16750118 3.4076 -1.18000079 0 N 0 ;0
L 3.4076 -1.18000079 3.40386752 -1.18875128 0 N 0 ;0
L 3.40386752 -1.18875128 3.3992001 -1.19625187 0 N 0 ;0
L 3.3992001 -1.19625187 3.39359961 -1.20125089 0 N 0 ;0
L 3.39359961 -1.20125089 3.38613287 -1.205 0 N 0 ;0
L 3.38613287 -1.205 3.36746673 -1.205 0 N 0 ;0
L 3.47980059 -1.205 3.47980059 -1.15500157 0 N 0 ;0
L 3.47980059 -1.1637497 3.47606644 -1.15875079 0 N 0 ;0
L 3.47606644 -1.15875079 3.47046585 -1.15625128 0 N 0 ;0
L 3.47046585 -1.15625128 3.46393396 -1.15500157 0 N 0 ;0
L 3.46393396 -1.15500157 3.4574003 -1.15750108 0 N 0 ;0
L 3.4574003 -1.15750108 3.4517998 -1.1625 0 N 0 ;0
L 3.4517998 -1.1625 3.44806555 -1.17000069 0 N 0 ;0
L 3.44806555 -1.17000069 3.44619931 -1.18000079 0 N 0 ;0
L 3.44619931 -1.18000079 3.44806555 -1.19000098 0 N 0 ;0
L 3.44806555 -1.19000098 3.4517998 -1.19750167 0 N 0 ;0
L 3.4517998 -1.19750167 3.4574003 -1.20250059 0 N 0 ;0
L 3.4574003 -1.20250059 3.46393396 -1.205 0 N 0 ;0
L 3.46393396 -1.205 3.47046585 -1.2037503 0 N 0 ;0
L 3.47046585 -1.2037503 3.47606644 -1.20000108 0 N 0 ;0
L 3.47606644 -1.20000108 3.47980059 -1.19500217 0 N 0 ;0
L 3.53799911 -1.13 3.53799911 -1.205 0 N 0 ;0
L 3.52493346 -1.15500157 3.55106644 -1.15500157 0 N 0 ;0
L 3.59900039 -1.17125039 3.62886752 -1.17125039 0 N 0 ;0
L 3.62886752 -1.17125039 3.62606644 -1.1625 0 N 0 ;0
L 3.62606644 -1.1625 3.62140069 -1.15750108 0 N 0 ;0
L 3.62140069 -1.15750108 3.61486703 -1.15500157 0 N 0 ;0
L 3.61486703 -1.15500157 3.60833346 -1.15625128 0 N 0 ;0
L 3.60833346 -1.15625128 3.60273287 -1.16000049 0 N 0 ;0
L 3.60273287 -1.16000049 3.59900039 -1.16875089 0 N 0 ;0
L 3.59900039 -1.16875089 3.59713238 -1.17625157 0 N 0 ;0
L 3.59713238 -1.17625157 3.59713238 -1.18375 0 N 0 ;0
L 3.59713238 -1.18375 3.59900039 -1.19125069 0 N 0 ;0
L 3.59900039 -1.19125069 3.60366604 -1.19875138 0 N 0 ;0
L 3.60366604 -1.19875138 3.60926654 -1.2037503 0 N 0 ;0
L 3.60926654 -1.2037503 3.6158002 -1.205 0 N 0 ;0
L 3.6158002 -1.205 3.62233386 -1.20250059 0 N 0 ;0
L 3.62233386 -1.20250059 3.62886752 -1.19500217 0 N 0 ;0
L 3.68799911 -1.20749941 3.68613287 -1.2062497 0 N 0 ;0
L 3.68613287 -1.2062497 3.68613287 -1.2037503 0 N 0 ;0
L 3.68613287 -1.2037503 3.68799911 -1.20250059 0 N 0 ;0
L 3.68799911 -1.20250059 3.68986703 -1.2037503 0 N 0 ;0
L 3.68986703 -1.2037503 3.68986703 -1.2062497 0 N 0 ;0
L 3.68986703 -1.2062497 3.68799911 -1.20749941 0 N 0 ;0
L 3.68799911 -1.17375217 3.68613287 -1.1725001 0 N 0 ;0
L 3.68613287 -1.1725001 3.68613287 -1.17000069 0 N 0 ;0
L 3.68613287 -1.17000069 3.68799911 -1.16875089 0 N 0 ;0
L 3.68799911 -1.16875089 3.68986703 -1.17000069 0 N 0 ;0
L 3.68986703 -1.17000069 3.68986703 -1.1725001 0 N 0 ;0
L 3.68986703 -1.1725001 3.68799911 -1.17375217 0 N 0 ;0
L 3.82026614 -1.1424997 3.82586663 -1.13500128 0 N 0 ;0
L 3.82586663 -1.13500128 3.8324003 -1.1312498 0 N 0 ;0
L 3.8324003 -1.1312498 3.83986703 -1.13 0 N 0 ;0
L 3.83986703 -1.13 3.8492001 -1.13249951 0 N 0 ;0
L 3.8492001 -1.13249951 3.85573376 -1.13875049 0 N 0 ;0
L 3.85573376 -1.13875049 3.8576 -1.14624882 0 N 0 ;0
L 3.8576 -1.14624882 3.85666693 -1.15375187 0 N 0 ;0
L 3.85666693 -1.15375187 3.85293268 -1.16000049 0 N 0 ;0
L 3.85293268 -1.16000049 3.83426654 -1.1725001 0 N 0 ;0
L 3.83426654 -1.1725001 3.82586663 -1.18125059 0 N 0 ;0
L 3.82586663 -1.18125059 3.82026614 -1.19375246 0 N 0 ;0
L 3.82026614 -1.19375246 3.8183999 -1.205 0 N 0 ;0
L 3.8183999 -1.205 3.8576 -1.205 0 N 0 ;0
L 3.91299911 -1.13 3.90553228 -1.13249951 0 N 0 ;0
L 3.90553228 -1.13249951 3.89993346 -1.13875049 0 N 0 ;0
L 3.89993346 -1.13875049 3.89619931 -1.14624882 0 N 0 ;0
L 3.89619931 -1.14624882 3.8933999 -1.15625128 0 N 0 ;0
L 3.8933999 -1.15625128 3.89246673 -1.16750118 0 N 0 ;0
L 3.89246673 -1.16750118 3.8933999 -1.17875108 0 N 0 ;0
L 3.8933999 -1.17875108 3.89619931 -1.18875128 0 N 0 ;0
L 3.89619931 -1.18875128 3.89993346 -1.19625187 0 N 0 ;0
L 3.89993346 -1.19625187 3.90553228 -1.20250059 0 N 0 ;0
L 3.90553228 -1.20250059 3.91299911 -1.205 0 N 0 ;0
L 3.91299911 -1.205 3.92046585 -1.20250059 0 N 0 ;0
L 3.92046585 -1.20250059 3.92606644 -1.19625187 0 N 0 ;0
L 3.92606644 -1.19625187 3.92980059 -1.18875128 0 N 0 ;0
L 3.92980059 -1.18875128 3.9326 -1.17875108 0 N 0 ;0
L 3.9326 -1.17875108 3.93353317 -1.16750118 0 N 0 ;0
L 3.93353317 -1.16750118 3.9326 -1.15625128 0 N 0 ;0
L 3.9326 -1.15625128 3.92980059 -1.14624882 0 N 0 ;0
L 3.92980059 -1.14624882 3.92606644 -1.13875049 0 N 0 ;0
L 3.92606644 -1.13875049 3.92046585 -1.13249951 0 N 0 ;0
L 3.92046585 -1.13249951 3.91299911 -1.13 0 N 0 ;0
L 3.97026614 -1.1424997 3.97586663 -1.13500128 0 N 0 ;0
L 3.97586663 -1.13500128 3.9824003 -1.1312498 0 N 0 ;0
L 3.9824003 -1.1312498 3.98986703 -1.13 0 N 0 ;0
L 3.98986703 -1.13 3.9992001 -1.13249951 0 N 0 ;0
L 3.9992001 -1.13249951 4.00573376 -1.13875049 0 N 0 ;0
L 4.00573376 -1.13875049 4.0076 -1.14624882 0 N 0 ;0
L 4.0076 -1.14624882 4.00666693 -1.15375187 0 N 0 ;0
L 4.00666693 -1.15375187 4.00293268 -1.16000049 0 N 0 ;0
L 4.00293268 -1.16000049 3.98426654 -1.1725001 0 N 0 ;0
L 3.98426654 -1.1725001 3.97586663 -1.18125059 0 N 0 ;0
L 3.97586663 -1.18125059 3.97026614 -1.19375246 0 N 0 ;0
L 3.97026614 -1.19375246 3.9683999 -1.205 0 N 0 ;0
L 3.9683999 -1.205 4.0076 -1.205 0 N 0 ;0
L 4.04526614 -1.1424997 4.05086663 -1.13500128 0 N 0 ;0
L 4.05086663 -1.13500128 4.0574003 -1.1312498 0 N 0 ;0
L 4.0574003 -1.1312498 4.06486703 -1.13 0 N 0 ;0
L 4.06486703 -1.13 4.0742001 -1.13249951 0 N 0 ;0
L 4.0742001 -1.13249951 4.08073376 -1.13875049 0 N 0 ;0
L 4.08073376 -1.13875049 4.0826 -1.14624882 0 N 0 ;0
L 4.0826 -1.14624882 4.08166693 -1.15375187 0 N 0 ;0
L 4.08166693 -1.15375187 4.07793268 -1.16000049 0 N 0 ;0
L 4.07793268 -1.16000049 4.05926654 -1.1725001 0 N 0 ;0
L 4.05926654 -1.1725001 4.05086663 -1.18125059 0 N 0 ;0
L 4.05086663 -1.18125059 4.04526614 -1.19375246 0 N 0 ;0
L 4.04526614 -1.19375246 4.0433999 -1.205 0 N 0 ;0
L 4.0433999 -1.205 4.0826 -1.205 0 N 0 ;0
L 4.12586663 -1.18000079 4.15013327 -1.18000079 0 N 0 ;0
L 4.21299911 -1.13 4.20553228 -1.13249951 0 N 0 ;0
L 4.20553228 -1.13249951 4.19993346 -1.13875049 0 N 0 ;0
L 4.19993346 -1.13875049 4.19619931 -1.14624882 0 N 0 ;0
L 4.19619931 -1.14624882 4.1933999 -1.15625128 0 N 0 ;0
L 4.1933999 -1.15625128 4.19246673 -1.16750118 0 N 0 ;0
L 4.19246673 -1.16750118 4.1933999 -1.17875108 0 N 0 ;0
L 4.1933999 -1.17875108 4.19619931 -1.18875128 0 N 0 ;0
L 4.19619931 -1.18875128 4.19993346 -1.19625187 0 N 0 ;0
L 4.19993346 -1.19625187 4.20553228 -1.20250059 0 N 0 ;0
L 4.20553228 -1.20250059 4.21299911 -1.205 0 N 0 ;0
L 4.21299911 -1.205 4.22046585 -1.20250059 0 N 0 ;0
L 4.22046585 -1.20250059 4.22606644 -1.19625187 0 N 0 ;0
L 4.22606644 -1.19625187 4.22980059 -1.18875128 0 N 0 ;0
L 4.22980059 -1.18875128 4.2326 -1.17875108 0 N 0 ;0
L 4.2326 -1.17875108 4.23353317 -1.16750118 0 N 0 ;0
L 4.23353317 -1.16750118 4.2326 -1.15625128 0 N 0 ;0
L 4.2326 -1.15625128 4.22980059 -1.14624882 0 N 0 ;0
L 4.22980059 -1.14624882 4.22606644 -1.13875049 0 N 0 ;0
L 4.22606644 -1.13875049 4.22046585 -1.13249951 0 N 0 ;0
L 4.22046585 -1.13249951 4.21299911 -1.13 0 N 0 ;0
L 4.27026614 -1.1424997 4.27586663 -1.13500128 0 N 0 ;0
L 4.27586663 -1.13500128 4.2824003 -1.1312498 0 N 0 ;0
L 4.2824003 -1.1312498 4.28986703 -1.13 0 N 0 ;0
L 4.28986703 -1.13 4.2992001 -1.13249951 0 N 0 ;0
L 4.2992001 -1.13249951 4.30573376 -1.13875049 0 N 0 ;0
L 4.30573376 -1.13875049 4.3076 -1.14624882 0 N 0 ;0
L 4.3076 -1.14624882 4.30666693 -1.15375187 0 N 0 ;0
L 4.30666693 -1.15375187 4.30293268 -1.16000049 0 N 0 ;0
L 4.30293268 -1.16000049 4.28426654 -1.1725001 0 N 0 ;0
L 4.28426654 -1.1725001 4.27586663 -1.18125059 0 N 0 ;0
L 4.27586663 -1.18125059 4.27026614 -1.19375246 0 N 0 ;0
L 4.27026614 -1.19375246 4.2683999 -1.205 0 N 0 ;0
L 4.2683999 -1.205 4.3076 -1.205 0 N 0 ;0
L 4.35086663 -1.18000079 4.37513327 -1.18000079 0 N 0 ;0
L 4.42026614 -1.1424997 4.42586663 -1.13500128 0 N 0 ;0
L 4.42586663 -1.13500128 4.4324003 -1.1312498 0 N 0 ;0
L 4.4324003 -1.1312498 4.43986703 -1.13 0 N 0 ;0
L 4.43986703 -1.13 4.4492001 -1.13249951 0 N 0 ;0
L 4.4492001 -1.13249951 4.45573376 -1.13875049 0 N 0 ;0
L 4.45573376 -1.13875049 4.4576 -1.14624882 0 N 0 ;0
L 4.4576 -1.14624882 4.45666693 -1.15375187 0 N 0 ;0
L 4.45666693 -1.15375187 4.45293268 -1.16000049 0 N 0 ;0
L 4.45293268 -1.16000049 4.43426654 -1.1725001 0 N 0 ;0
L 4.43426654 -1.1725001 4.42586663 -1.18125059 0 N 0 ;0
L 4.42586663 -1.18125059 4.42026614 -1.19375246 0 N 0 ;0
L 4.42026614 -1.19375246 4.4183999 -1.205 0 N 0 ;0
L 4.4183999 -1.205 4.4576 -1.205 0 N 0 ;0
L 4.49246673 -1.19375246 4.49806555 -1.20000108 0 N 0 ;0
L 4.49806555 -1.20000108 4.50459921 -1.2037503 0 N 0 ;0
L 4.50459921 -1.2037503 4.51299911 -1.205 0 N 0 ;0
L 4.51299911 -1.205 4.52140069 -1.20250059 0 N 0 ;0
L 4.52140069 -1.20250059 4.52793268 -1.19750167 0 N 0 ;0
L 4.52793268 -1.19750167 4.5326 -1.18875128 0 N 0 ;0
L 4.5326 -1.18875128 4.53353317 -1.17875108 0 N 0 ;0
L 4.53353317 -1.17875108 4.53166693 -1.16875089 0 N 0 ;0
L 4.53166693 -1.16875089 4.52699951 -1.1625 0 N 0 ;0
L 4.52699951 -1.1625 4.52046585 -1.15750108 0 N 0 ;0
L 4.52046585 -1.15750108 4.51393396 -1.15625128 0 N 0 ;0
L 4.51393396 -1.15625128 4.5074003 -1.15750108 0 N 0 ;0
L 4.5074003 -1.15750108 4.49900039 -1.1625 0 N 0 ;0
L 4.49900039 -1.1625 4.5017998 -1.13 0 N 0 ;0
L 4.5017998 -1.13 4.52699951 -1.13 0 N 0 ;0
L 3.29433297 -1.255 3.29433297 -1.33 0 N 0 ;0
L 3.29433297 -1.33 3.33166693 -1.33 0 N 0 ;0
L 3.40480059 -1.33 3.40480059 -1.28000157 0 N 0 ;0
L 3.40480059 -1.2887497 3.40106644 -1.28375079 0 N 0 ;0
L 3.40106644 -1.28375079 3.39546585 -1.28125128 0 N 0 ;0
L 3.39546585 -1.28125128 3.38893396 -1.28000157 0 N 0 ;0
L 3.38893396 -1.28000157 3.3824003 -1.28250108 0 N 0 ;0
L 3.3824003 -1.28250108 3.3767998 -1.2875 0 N 0 ;0
L 3.3767998 -1.2875 3.37306555 -1.29500069 0 N 0 ;0
L 3.37306555 -1.29500069 3.37119931 -1.30500079 0 N 0 ;0
L 3.37119931 -1.30500079 3.37306555 -1.31500098 0 N 0 ;0
L 3.37306555 -1.31500098 3.3767998 -1.32250167 0 N 0 ;0
L 3.3767998 -1.32250167 3.3824003 -1.32750059 0 N 0 ;0
L 3.3824003 -1.32750059 3.38893396 -1.33 0 N 0 ;0
L 3.38893396 -1.33 3.39546585 -1.3287503 0 N 0 ;0
L 3.39546585 -1.3287503 3.40106644 -1.32500108 0 N 0 ;0
L 3.40106644 -1.32500108 3.40480059 -1.32000217 0 N 0 ;0
L 3.4433999 -1.3524997 3.44900039 -1.35499921 0 N 0 ;0
L 3.44900039 -1.35499921 3.45646713 -1.3524997 0 N 0 ;0
L 3.45646713 -1.3524997 3.46113287 -1.34750079 0 N 0 ;0
L 3.46113287 -1.34750079 3.46486703 -1.3412498 0 N 0 ;0
L 3.46486703 -1.3412498 3.47046585 -1.32125187 0 N 0 ;0
L 3.47046585 -1.32125187 3.4826 -1.28000157 0 N 0 ;0
L 3.45273287 -1.28000157 3.47046585 -1.32125187 0 N 0 ;0
L 3.52400039 -1.29625039 3.55386752 -1.29625039 0 N 0 ;0
L 3.55386752 -1.29625039 3.55106644 -1.2875 0 N 0 ;0
L 3.55106644 -1.2875 3.54640069 -1.28250108 0 N 0 ;0
L 3.54640069 -1.28250108 3.53986703 -1.28000157 0 N 0 ;0
L 3.53986703 -1.28000157 3.53333346 -1.28125128 0 N 0 ;0
L 3.53333346 -1.28125128 3.52773287 -1.28500049 0 N 0 ;0
L 3.52773287 -1.28500049 3.52400039 -1.29375089 0 N 0 ;0
L 3.52400039 -1.29375089 3.52213238 -1.30125157 0 N 0 ;0
L 3.52213238 -1.30125157 3.52213238 -1.30875 0 N 0 ;0
L 3.52213238 -1.30875 3.52400039 -1.31625069 0 N 0 ;0
L 3.52400039 -1.31625069 3.52866604 -1.32375138 0 N 0 ;0
L 3.52866604 -1.32375138 3.53426654 -1.3287503 0 N 0 ;0
L 3.53426654 -1.3287503 3.5408002 -1.33 0 N 0 ;0
L 3.5408002 -1.33 3.54733386 -1.32750059 0 N 0 ;0
L 3.54733386 -1.32750059 3.55386752 -1.32000217 0 N 0 ;0
L 3.59993346 -1.33 3.59993346 -1.28000157 0 N 0 ;0
L 3.59993346 -1.28999941 3.60459921 -1.28500049 0 N 0 ;0
L 3.60459921 -1.28500049 3.60926654 -1.28125128 0 N 0 ;0
L 3.60926654 -1.28125128 3.6158002 -1.28000157 0 N 0 ;0
L 3.6158002 -1.28000157 3.62046585 -1.28125128 0 N 0 ;0
L 3.62046585 -1.28125128 3.62606644 -1.28500049 0 N 0 ;0
L 3.68799911 -1.33249941 3.68613287 -1.3312497 0 N 0 ;0
L 3.68613287 -1.3312497 3.68613287 -1.3287503 0 N 0 ;0
L 3.68613287 -1.3287503 3.68799911 -1.32750059 0 N 0 ;0
L 3.68799911 -1.32750059 3.68986703 -1.3287503 0 N 0 ;0
L 3.68986703 -1.3287503 3.68986703 -1.3312497 0 N 0 ;0
L 3.68986703 -1.3312497 3.68799911 -1.33249941 0 N 0 ;0
L 3.68799911 -1.29875217 3.68613287 -1.2975001 0 N 0 ;0
L 3.68613287 -1.2975001 3.68613287 -1.29500069 0 N 0 ;0
L 3.68613287 -1.29500069 3.68799911 -1.29375089 0 N 0 ;0
L 3.68799911 -1.29375089 3.68986703 -1.29500069 0 N 0 ;0
L 3.68986703 -1.29500069 3.68986703 -1.2975001 0 N 0 ;0
L 3.68986703 -1.2975001 3.68799911 -1.29875217 0 N 0 ;0
L 3.36933297 -1.08 3.36933297 -1.005 0 N 0 ;0
L 3.36933297 -1.005 3.39266644 -1.005 0 N 0 ;0
L 3.39266644 -1.005 3.40013327 -1.00875157 0 N 0 ;0
L 3.40013327 -1.00875157 3.40480059 -1.01375049 0 N 0 ;0
L 3.40480059 -1.01375049 3.40666693 -1.02375059 0 N 0 ;0
L 3.40666693 -1.02375059 3.40480059 -1.03375079 0 N 0 ;0
L 3.40480059 -1.03375079 3.3992001 -1.03999941 0 N 0 ;0
L 3.3992001 -1.03999941 3.39266644 -1.04375089 0 N 0 ;0
L 3.39266644 -1.04375089 3.36933297 -1.04375089 0 N 0 ;0
L 3.39266644 -1.04375089 3.40666693 -1.08 0 N 0 ;0
L 3.44900039 -1.04625039 3.47886752 -1.04625039 0 N 0 ;0
L 3.47886752 -1.04625039 3.47606644 -1.0375 0 N 0 ;0
L 3.47606644 -1.0375 3.47140069 -1.03250108 0 N 0 ;0
L 3.47140069 -1.03250108 3.46486703 -1.03000157 0 N 0 ;0
L 3.46486703 -1.03000157 3.45833346 -1.03125128 0 N 0 ;0
L 3.45833346 -1.03125128 3.45273287 -1.03500049 0 N 0 ;0
L 3.45273287 -1.03500049 3.44900039 -1.04375089 0 N 0 ;0
L 3.44900039 -1.04375089 3.44713238 -1.05125157 0 N 0 ;0
L 3.44713238 -1.05125157 3.44713238 -1.05875 0 N 0 ;0
L 3.44713238 -1.05875 3.44900039 -1.06625069 0 N 0 ;0
L 3.44900039 -1.06625069 3.45366604 -1.07375138 0 N 0 ;0
L 3.45366604 -1.07375138 3.45926654 -1.0787503 0 N 0 ;0
L 3.45926654 -1.0787503 3.4658002 -1.08 0 N 0 ;0
L 3.4658002 -1.08 3.47233386 -1.07750059 0 N 0 ;0
L 3.47233386 -1.07750059 3.47886752 -1.07000217 0 N 0 ;0
L 3.52119931 -1.03000157 3.53799911 -1.08 0 N 0 ;0
L 3.53799911 -1.08 3.55480059 -1.03000157 0 N 0 ;0
L 3.68799911 -1.08249941 3.68613287 -1.0812497 0 N 0 ;0
L 3.68613287 -1.0812497 3.68613287 -1.0787503 0 N 0 ;0
L 3.68613287 -1.0787503 3.68799911 -1.07750059 0 N 0 ;0
L 3.68799911 -1.07750059 3.68986703 -1.0787503 0 N 0 ;0
L 3.68986703 -1.0787503 3.68986703 -1.0812497 0 N 0 ;0
L 3.68986703 -1.0812497 3.68799911 -1.08249941 0 N 0 ;0
L 3.68799911 -1.04875217 3.68613287 -1.0475001 0 N 0 ;0
L 3.68613287 -1.0475001 3.68613287 -1.04500069 0 N 0 ;0
L 3.68613287 -1.04500069 3.68799911 -1.04375089 0 N 0 ;0
L 3.68799911 -1.04375089 3.68986703 -1.04500069 0 N 0 ;0
L 3.68986703 -1.04500069 3.68986703 -1.0475001 0 N 0 ;0
L 3.68986703 -1.0475001 3.68799911 -1.04875217 0 N 0 ;0
L 3.83799911 -1.005 3.83053228 -1.00749951 0 N 0 ;0
L 3.83053228 -1.00749951 3.82493346 -1.01375049 0 N 0 ;0
L 3.82493346 -1.01375049 3.82119931 -1.02124882 0 N 0 ;0
L 3.82119931 -1.02124882 3.8183999 -1.03125128 0 N 0 ;0
L 3.8183999 -1.03125128 3.81746673 -1.04250118 0 N 0 ;0
L 3.81746673 -1.04250118 3.8183999 -1.05375108 0 N 0 ;0
L 3.8183999 -1.05375108 3.82119931 -1.06375128 0 N 0 ;0
L 3.82119931 -1.06375128 3.82493346 -1.07125187 0 N 0 ;0
L 3.82493346 -1.07125187 3.83053228 -1.07750059 0 N 0 ;0
L 3.83053228 -1.07750059 3.83799911 -1.08 0 N 0 ;0
L 3.83799911 -1.08 3.84546585 -1.07750059 0 N 0 ;0
L 3.84546585 -1.07750059 3.85106644 -1.07125187 0 N 0 ;0
L 3.85106644 -1.07125187 3.85480059 -1.06375128 0 N 0 ;0
L 3.85480059 -1.06375128 3.8576 -1.05375108 0 N 0 ;0
L 3.8576 -1.05375108 3.85853317 -1.04250118 0 N 0 ;0
L 3.85853317 -1.04250118 3.8576 -1.03125128 0 N 0 ;0
L 3.8576 -1.03125128 3.85480059 -1.02124882 0 N 0 ;0
L 3.85480059 -1.02124882 3.85106644 -1.01375049 0 N 0 ;0
L 3.85106644 -1.01375049 3.84546585 -1.00749951 0 N 0 ;0
L 3.84546585 -1.00749951 3.83799911 -1.005 0 N 0 ;0
L 3.91299911 -1.08 3.91299911 -1.005 0 N 0 ;0
L 3.91299911 -1.005 3.9017998 -1.01999911 0 N 0 ;0
L 3.9017998 -1.08 3.92419843 -1.08 0 N 0 ;0

### steps/pcb/layers/l03_sig1/features
#
#Num Features
#
F 3779

#
#Units
#
U INCH

#
#Feature symbol names
#
$0 r4
$1 r5
$2 r6
$3 r6.2
$4 r10
$5 r15
$6 r18
$7 r20
$8 r24
$9 r100

#
#Feature attribute names
#
@0 .nomenclature
@1 .geometry
@2 .string
@3 .pad_usage
@4 .string_angle

#
#Feature attribute text strings
#
&0 V010C020P_TP030B
&1 V008C018P-ANTI28-NSM
&2 V010C020P
&3 TPV010CT020B030
&4 V008C018P_ANTI026_TP030B
&5 V008C018P_NATI28_TP030B_NSMT
&6 016C024P
&7 V008C018P_TP030B
&8 V008C018P
&9 V008C018P_ANTI28
&10 059C086P
&11 V008C018P_ANTI026_NSM
&12 076S104P
&13 076C104P
&14 079C100P
&15 V010C020P_SM014-NTH
&16 V012C024-NTH
&17 024X063OB035X075P
&18 166CT244CB198P
&19 024X051OB071X075P_R
&20 024X051OB071X075P_L
&21 033C057P
&22 063C090P
&23 L03_SIG1
&24 MTH100C090N
&25 MTH125C115N
&26 MTH118C108N
&27 P/N : R4006-B0001-02
&28 Date: 2022-02-25
&29 Layer:
&30 Rev : 01

#
#Layer features
#
P 3.125 1.605 7 P 0 8 0;1=0,3=1
L 3.12 2.645 3.06716998 2.59216998 1 P 0 
L 3.06716998 2.59216998 3.06716998 2.02111004 1 P 0 
L 3.06716998 2.02111004 3.0875 2.00078002 1 P 0 
L 3.0875 2.00078002 3.0875 1.7525 1 P 0 
L 3.0875 1.7525 3.125 1.715 1 P 0 
L 3.125 1.715 3.125 1.605 1 P 0 
P 3.12 2.645 7 P 0 8 0;1=2,3=1
L 4.06878996 1.58753002 4.08428996 1.60303002 1 P 0 
L 4.08428996 1.60303002 4.10803002 1.60303002 1 P 0 
L 4.10803002 1.60303002 4.13 1.625 1 P 0 
L 4.13 1.625 4.13 1.73 1 P 0 
L 4.13 1.73 4.105 1.755 1 P 0 
L 4.105 1.755 3.945 1.755 1 P 0 
L 3.945 1.755 3.925 1.735 1 P 0 
L 3.925 1.735 3.78 1.735 1 P 0 
L 3.78 1.735 3.746 1.769 1 P 0 
L 3.746 1.769 3.746 1.782 1 P 0 
P 3.746 1.782 7 P 0 8 0;1=3,3=0
P 4.06878996 1.58753002 6 P 0 8 0;1=1,3=1
P 5.762 3.425 6 P 0 8 0;1=7,3=1
P 5.6 3.421 7 P 0 8 0;1=0,3=1
L 5.6 3.421 5.604 3.425 5 P 0 
L 5.604 3.425 5.762 3.425 5 P 0 
L 3.51 3.08 3.4825 3.1075 1 P 0 
L 3.4825 3.1075 3.36238002 3.1075 1 P 0 
L 3.36238002 3.1075 3.34488002 3.125 1 P 0 
L 3.34488002 3.125 3.06001004 3.125 1 P 0 
L 3.06001004 3.125 3.01501004 3.08 1 P 0 
L 3.01501004 3.08 2.90841004 3.08 1 P 0 
L 2.90841004 3.08 2.63341004 3.355 1 P 0 
L 2.63341004 3.355 2.33 3.355 1 P 0 
L 2.33 3.355 2.3 3.385 1 P 0 
L 2.3 3.385 2.23498996 3.385 1 P 0 
L 2.23498996 3.385 2.21498996 3.365 1 P 0 
L 2.21498996 3.365 2.08711998 3.365 1 P 0 
L 2.08711998 3.365 2.06761998 3.3455 1 P 0 
L 2.06761998 3.3455 2.0145 3.3455 1 P 0 
L 2.0145 3.3455 2 3.36 1 P 0 
L 2 3.36 1.79 3.36 1 P 0 
L 1.79 3.36 1.585 3.155 1 P 0 
L 1.585 3.155 1.585 3.09 1 P 0 
L 1.585 3.09 1.5225 3.0275 1 P 0 
L 1.5225 3.0275 1.39238002 3.0275 1 P 0 
L 1.39238002 3.0275 1.37288002 3.008 1 P 0 
L 1.37288002 3.008 1.213 3.008 1 P 0 
L 1.213 3.008 1.135 2.93 1 P 0 
L 1.135 2.93 1.055 2.93 1 P 0 
L 1.055 2.93 1.025 2.9 1 P 0 
P 3.51 3.08 7 P 0 8 0;1=0,3=1
P 1.025 2.9 7 P 0 8 0;1=2,3=1
L 1.125 2.9 1.135 2.9 1 P 0 
L 1.135 2.9 1.223 2.988 1 P 0 
L 1.223 2.988 1.38116998 2.988 1 P 0 
L 1.38116998 2.988 1.40066998 3.0075 1 P 0 
L 1.40066998 3.0075 1.53078996 3.0075 1 P 0 
L 1.53078996 3.0075 1.605 3.08171004 1 P 0 
L 1.605 3.08171004 1.605 3.14501004 1 P 0 
L 1.605 3.14501004 1.77998996 3.32 1 P 0 
L 1.77998996 3.32 1.93216998 3.32 1 P 0 
L 1.93216998 3.32 1.94966998 3.3025 1 P 0 
L 1.94966998 3.3025 1.96833002 3.3025 1 P 0 
L 1.96833002 3.3025 1.98583002 3.32 1 P 0 
L 1.98583002 3.32 2.01171004 3.32 1 P 0 
L 2.01171004 3.32 2.01721004 3.3255 1 P 0 
L 2.01721004 3.3255 2.07591004 3.3255 1 P 0 
L 2.07591004 3.3255 2.09541004 3.345 1 P 0 
L 2.09541004 3.345 2.22328002 3.345 1 P 0 
L 2.22328002 3.345 2.24328002 3.365 1 P 0 
L 2.24328002 3.365 2.29 3.365 1 P 0 
L 2.29 3.365 2.32 3.335 1 P 0 
L 2.32 3.335 2.62511998 3.335 1 P 0 
L 2.62511998 3.335 2.90011998 3.06 1 P 0 
L 2.90011998 3.06 3.025 3.06 1 P 0 
L 3.025 3.06 3.065 3.1 1 P 0 
L 3.065 3.1 3.33316004 3.1 1 P 0 
L 3.33316004 3.1 3.35316004 3.08 1 P 0 
L 3.35316004 3.08 3.445 3.08 1 P 0 
L 3.445 3.08 3.46 3.065 1 P 0 
P 3.46 3.065 7 P 0 8 0;1=0,3=1
P 1.125 2.9 7 P 0 8 0;1=2,3=1
P 3.035 1.64 7 P 0 8 0;1=2,3=1
L 3.445 2.65 3.445 2.88 1 P 0 
L 3.445 2.88 3.465 2.9 1 P 0 
L 3.465 2.9 3.465 2.96 1 P 0 
L 3.465 2.96 3.44 2.985 1 P 0 
L 3.44 2.985 3.355 2.985 1 P 0 
L 3.355 2.985 3.335 2.965 1 P 0 
L 3.335 2.965 3.335 2.905 1 P 0 
L 3.335 2.905 3.315 2.885 1 P 0 
L 3.315 2.885 3.19 2.885 1 P 0 
L 3.19 2.885 3.03216998 2.72716998 1 P 0 
L 3.03216998 2.72716998 3.03216998 1.99283996 1 P 0 
L 3.03216998 1.99283996 3.0525 1.97251004 1 P 0 
L 3.0525 1.97251004 3.0525 1.75921004 1 P 0 
L 3.0525 1.75921004 3.03 1.73671004 1 P 0 
L 3.03 1.73671004 3.03 1.645 1 P 0 
L 3.03 1.645 3.035 1.64 1 P 0 
P 3.445 2.65 7 P 0 8 0;1=3,3=0
P 3.075 1.605 7 P 0 8 0;1=2,3=1
L 3.365 2.95 3.365 2.91 1 P 0 
L 3.365 2.91 3.325 2.87 1 P 0 
L 3.325 2.87 3.205 2.87 1 P 0 
L 3.205 2.87 3.09 2.755 1 P 0 
L 3.09 2.755 3.09 2.64328996 1 P 0 
L 3.09 2.64328996 3.04716998 2.60046004 1 P 0 
L 3.04716998 2.60046004 3.04716998 2.01281998 1 P 0 
L 3.04716998 2.01281998 3.0675 1.99248996 1 P 0 
L 3.0675 1.99248996 3.0675 1.74421004 1 P 0 
L 3.0675 1.74421004 3.1 1.71171004 1 P 0 
L 3.1 1.71171004 3.1 1.68683002 1 P 0 
L 3.1 1.68683002 3.065 1.65183002 1 P 0 
L 3.065 1.65183002 3.065 1.615 1 P 0 
L 3.065 1.615 3.075 1.605 1 P 0 
P 3.365 2.95 6 P 0 8 0;1=4,3=1
L 0.33466004 3.4008 0.3012 3.42013002 0 P 0 
A 0.3012 3.42013002 0.2992 3.4236 0.30321024 3.4236 0 P 0 Y
L 0.2992 3.4236 0.2992 3.44016998 0 P 0 
A 0.2992 3.44016998 0.30346004 3.45046004 0.31375768 3.44016998 0 P 0 Y
L 0.30346004 3.45046004 0.31208002 3.45908002 3 P 0 
A 0.31208002 3.45908002 0.31671004 3.461 0.31670994 3.45445748 3 P 0 Y
L 0.31671004 3.461 0.33733002 3.461 3 P 0 
A 0.33733002 3.461 0.34531004 3.45768996 0.33732441 3.4497123 3 P 0 Y
L 0.34531004 3.45768996 0.34891998 3.45408002 3 P 0 
A 0.34891998 3.45408002 0.35238002 3.44571998 0.34055039 3.44571998 3 P 0 Y
L 0.35238002 3.44571998 0.35238002 3.4315 3 P 0 
P 0.35238002 3.4315 8 P 0 8 0;1=6,3=0
P 0.33466004 3.4008 8 P 0 8 0;1=6,3=0
L 0.29921998 3.4008 0.31643996 3.38358002 3 P 0 
A 0.31643996 3.38358002 0.33473002 3.376 0.33472992 3.4018562 3 P 0 N
L 0.33473002 3.376 0.37333002 3.376 3 P 0 
A 0.37333002 3.376 0.38131004 3.37931004 0.37332441 3.3872877 3 P 0 N
L 0.38131004 3.37931004 0.38781998 3.38581998 3 P 0 
L 0.38781998 3.38581998 0.38781998 3.4315 0 P 0 
P 0.38781998 3.4315 8 P 0 8 0;1=6,3=0
P 0.29921998 3.4008 8 P 0 8 0;1=6,3=0
L 0.995 3.7 1.01 3.715 1 P 0 
L 1.01 3.715 1.025 3.715 1 P 0 
L 1.025 3.715 1.085 3.775 1 P 0 
L 1.085 3.775 1.155 3.775 1 P 0 
L 1.155 3.775 1.17 3.76 1 P 0 
L 1.17 3.76 1.19 3.76 1 P 0 
L 1.19 3.76 1.27 3.68 1 P 0 
L 1.27 3.68 1.365 3.68 1 P 0 
L 1.365 3.68 1.4 3.645 1 P 0 
L 1.4 3.645 1.83998996 3.645 1 P 0 
L 1.83998996 3.645 1.88998996 3.695 1 P 0 
L 1.88998996 3.695 2.72206998 3.695 1 P 0 
L 2.72206998 3.695 2.87706998 3.54 1 P 0 
L 2.87706998 3.54 3.52 3.54 1 P 0 
L 3.52 3.54 3.7605 3.7805 1 P 0 
L 3.7605 3.7805 3.81033002 3.7805 1 P 0 
L 3.81033002 3.7805 3.81583002 3.775 1 P 0 
L 3.81583002 3.775 3.92 3.775 1 P 0 
L 3.92 3.775 4.035 3.66 1 P 0 
L 4.035 3.66 4.17316998 3.66 1 P 0 
L 4.17316998 3.66 4.19566998 3.6825 1 P 0 
L 4.19566998 3.6825 4.2175 3.6825 1 P 0 
L 4.2175 3.6825 4.285 3.615 1 P 0 
L 4.285 3.615 4.285 3.46 1 P 0 
P 0.995 3.7 7 P 0 8 0;1=3,3=0
P 4.285 3.46 7 P 0 8 0;1=2,3=1
L 1.3 3.49663996 1.24986004 3.4465 6 P 0 
L 1.24986004 3.4465 1.24751998 3.4465 6 P 0 
L 1.24751998 3.4465 1.24701998 3.446 6 P 0 
L 1.24701998 3.446 1.22298002 3.446 6 P 0 
L 1.22298002 3.446 1.22248002 3.4465 6 P 0 
L 1.22248002 3.4465 1.1985 3.4465 6 P 0 
L 1.1985 3.4465 1.17075 3.47425 6 P 0 
L 1.17075 3.47425 1.04018996 3.47425 6 P 0 
L 1.29 3.215 1.0841 3.215 6 P 0 
L 1.0841 3.215 1.0541 3.185 6 P 0 
P 1.29 3.215 7 P 0 8 0;1=2,3=1
P 1.0541 3.185 7 P 0 8 0;1=0,3=1
P 1.3 3.49663996 7 P 0 8 0;1=2,3=1
P 1.04018996 3.47425 7 P 0 8 0;1=2,3=1
L 4.205 3.66 4.26 3.605 1 P 0 
L 4.26 3.605 4.26 3.525 1 P 0 
L 4.26 3.525 4.2541 3.5191 1 P 0 
L 4.2541 3.5191 4.2101 3.5191 1 P 0 
L 4.2101 3.5191 4.1686 3.5606 1 P 0 
L 4.1686 3.5606 4.042 3.5606 1 P 0 
L 4.042 3.5606 4.0236 3.5422 1 P 0 
L 4.0236 3.5422 4.0236 3.5209 1 P 0 
L 4.0236 3.5209 3.9927 3.49 1 P 0 
L 3.9927 3.49 3.8128 3.49 1 P 0 
L 3.8128 3.49 3.7628 3.44 1 P 0 
L 3.7628 3.44 3.586 3.44 1 P 0 
L 3.586 3.44 3.575 3.429 1 P 0 
L 3.575 3.429 3.42858996 3.429 1 P 0 
L 3.42858996 3.429 3.38958996 3.39 1 P 0 
L 3.38958996 3.39 3.3217 3.39 1 P 0 
L 3.3217 3.39 3.3042 3.4075 1 P 0 
L 3.3042 3.4075 3.20966004 3.4075 1 P 0 
L 3.20966004 3.4075 3.19216004 3.425 1 P 0 
L 3.19216004 3.425 2.85061998 3.425 1 P 0 
L 2.85061998 3.425 2.76381998 3.5118 1 P 0 
L 2.76381998 3.5118 2.4036 3.5118 1 P 0 
L 2.4036 3.5118 2.3204 3.595 1 P 0 
L 2.3204 3.595 1.93486998 3.595 1 P 0 
L 1.93486998 3.595 1.88486998 3.545 1 P 0 
L 1.88486998 3.545 1.69211998 3.545 1 P 0 
L 1.69211998 3.545 1.60711998 3.46 1 P 0 
L 1.60711998 3.46 1.47828996 3.46 1 P 0 
L 1.47828996 3.46 1.43828996 3.42 1 P 0 
L 1.43828996 3.42 1.395 3.42 1 P 0 
L 1.395 3.42 1.35 3.375 1 P 0 
L 1.35 3.375 1.01 3.375 1 P 0 
L 1.01 3.375 0.975 3.41 1 P 0 
P 4.205 3.66 7 P 0 8 0;1=0,3=1
P 0.975 3.41 7 P 0 8 0;1=2,3=1
L 1.015 3.41 1.03 3.395 1 P 0 
L 1.03 3.395 1.325 3.395 1 P 0 
L 1.325 3.395 1.37 3.44 1 P 0 
L 1.37 3.44 1.43 3.44 1 P 0 
L 1.43 3.44 1.47 3.48 1 P 0 
L 1.47 3.48 1.59883002 3.48 1 P 0 
L 1.59883002 3.48 1.68383002 3.565 1 P 0 
L 1.68383002 3.565 1.87658002 3.565 1 P 0 
L 1.87658002 3.565 1.92658002 3.615 1 P 0 
L 1.92658002 3.615 2.3387 3.615 1 P 0 
L 2.3387 3.615 2.3945 3.5592 1 P 0 
L 2.3945 3.5592 2.62088996 3.5592 1 P 0 
L 2.62088996 3.5592 2.62588996 3.5542 1 P 0 
L 2.62588996 3.5542 2.62588996 3.5416 1 P 0 
L 2.62588996 3.5416 2.63088996 3.5366 1 P 0 
L 2.63088996 3.5366 2.64588996 3.5366 1 P 0 
L 2.64588996 3.5366 2.65088996 3.5416 1 P 0 
L 2.65088996 3.5416 2.65088996 3.5542 1 P 0 
L 2.65088996 3.5542 2.65588996 3.5592 1 P 0 
L 2.65588996 3.5592 2.67088996 3.5592 1 P 0 
L 2.67088996 3.5592 2.67588996 3.5542 1 P 0 
L 2.67588996 3.5542 2.67588996 3.5416 1 P 0 
L 2.67588996 3.5416 2.68088996 3.5366 1 P 0 
L 2.68088996 3.5366 2.69588996 3.5366 1 P 0 
L 2.69588996 3.5366 2.70088996 3.5416 1 P 0 
L 2.70088996 3.5416 2.70088996 3.5542 1 P 0 
L 2.70088996 3.5542 2.70588996 3.5592 1 P 0 
L 2.70588996 3.5592 2.74471004 3.5592 1 P 0 
L 2.74471004 3.5592 2.84391004 3.46 1 P 0 
L 2.84391004 3.46 3.27998996 3.46 1 P 0 
L 3.27998996 3.46 3.32998996 3.41 1 P 0 
L 3.32998996 3.41 3.3789 3.41 1 P 0 
L 3.3789 3.41 3.4239 3.455 1 P 0 
L 3.4239 3.455 3.561 3.455 1 P 0 
L 3.561 3.455 3.579 3.473 1 P 0 
L 3.579 3.473 3.61801004 3.473 1 P 0 
L 3.61801004 3.473 3.63273996 3.48773002 1 P 0 
L 3.63273996 3.48773002 3.63273996 3.52143996 1 P 0 
L 3.63273996 3.52143996 3.6713 3.56 1 P 0 
L 3.6713 3.56 3.93828996 3.56 1 P 0 
L 3.93828996 3.56 3.93928996 3.561 1 P 0 
L 3.93928996 3.561 3.9818 3.561 1 P 0 
L 3.9818 3.561 4.0316 3.6108 1 P 0 
L 4.0316 3.6108 4.1592 3.6108 1 P 0 
L 4.1592 3.6108 4.225 3.545 1 P 0 
P 4.225 3.545 7 P 0 8 0;1=0,3=1
P 1.015 3.41 7 P 0 8 0;1=2,3=1
L 0.835 3.6 0.985 3.45 1 P 0 
L 0.985 3.45 1.02696004 3.45 1 P 0 
L 1.02696004 3.45 1.06196004 3.415 1 P 0 
L 1.06196004 3.415 1.30001004 3.415 1 P 0 
L 1.30001004 3.415 1.41001004 3.525 1 P 0 
L 1.41001004 3.525 1.53 3.525 1 P 0 
L 1.53 3.525 1.59 3.585 1 P 0 
L 1.59 3.585 1.86828996 3.585 1 P 0 
L 1.86828996 3.585 1.91828996 3.635 1 P 0 
L 1.91828996 3.635 2.3557 3.635 1 P 0 
L 2.3557 3.635 2.3778 3.6129 1 P 0 
L 2.3778 3.6129 2.40728996 3.6129 1 P 0 
L 2.40728996 3.6129 2.41228996 3.6079 1 P 0 
L 2.41228996 3.6079 2.41228996 3.5872 1 P 0 
L 2.41228996 3.5872 2.41728996 3.5822 1 P 0 
L 2.41728996 3.5822 2.43228996 3.5822 1 P 0 
L 2.43228996 3.5822 2.43728996 3.5872 1 P 0 
L 2.43728996 3.5872 2.43728996 3.6079 1 P 0 
L 2.43728996 3.6079 2.44228996 3.6129 1 P 0 
L 2.44228996 3.6129 2.45728996 3.6129 1 P 0 
L 2.45728996 3.6129 2.46228996 3.6079 1 P 0 
L 2.46228996 3.6079 2.46228996 3.5872 1 P 0 
L 2.46228996 3.5872 2.46728996 3.5822 1 P 0 
L 2.46728996 3.5822 2.48228996 3.5822 1 P 0 
L 2.48228996 3.5822 2.48728996 3.5872 1 P 0 
L 2.48728996 3.5872 2.48728996 3.6079 1 P 0 
L 2.48728996 3.6079 2.49228996 3.6129 1 P 0 
L 2.49228996 3.6129 2.50728996 3.6129 1 P 0 
L 2.50728996 3.6129 2.51228996 3.6079 1 P 0 
L 2.51228996 3.6079 2.51228996 3.59 1 P 0 
L 2.51228996 3.59 2.51728996 3.585 1 P 0 
L 2.51728996 3.585 2.53228996 3.585 1 P 0 
L 2.53228996 3.585 2.53728996 3.59 1 P 0 
L 2.53728996 3.59 2.53728996 3.6079 1 P 0 
L 2.53728996 3.6079 2.54228996 3.6129 1 P 0 
L 2.54228996 3.6129 2.55728996 3.6129 1 P 0 
L 2.55728996 3.6129 2.56228996 3.6079 1 P 0 
L 2.56228996 3.6079 2.56228996 3.5872 1 P 0 
L 2.56228996 3.5872 2.56728996 3.5822 1 P 0 
L 2.56728996 3.5822 2.58228996 3.5822 1 P 0 
L 2.58228996 3.5822 2.58728996 3.5872 1 P 0 
L 2.58728996 3.5872 2.58728996 3.6079 1 P 0 
L 2.58728996 3.6079 2.59228996 3.6129 1 P 0 
L 2.59228996 3.6129 2.60728996 3.6129 1 P 0 
L 2.60728996 3.6129 2.61228996 3.6079 1 P 0 
L 2.61228996 3.6079 2.61228996 3.5872 1 P 0 
L 2.61228996 3.5872 2.61728996 3.5822 1 P 0 
L 2.61728996 3.5822 2.63228996 3.5822 1 P 0 
L 2.63228996 3.5822 2.63728996 3.5872 1 P 0 
L 2.63728996 3.5872 2.63728996 3.6079 1 P 0 
L 2.63728996 3.6079 2.64228996 3.6129 1 P 0 
L 2.64228996 3.6129 2.65728996 3.6129 1 P 0 
L 2.65728996 3.6129 2.66228996 3.6079 1 P 0 
L 2.66228996 3.6079 2.66228996 3.5872 1 P 0 
L 2.66228996 3.5872 2.66728996 3.5822 1 P 0 
L 2.66728996 3.5822 2.68228996 3.5822 1 P 0 
L 2.68228996 3.5822 2.68728996 3.5872 1 P 0 
L 2.68728996 3.5872 2.68728996 3.6079 1 P 0 
L 2.68728996 3.6079 2.69228996 3.6129 1 P 0 
L 2.69228996 3.6129 2.7193 3.6129 1 P 0 
L 2.7193 3.6129 2.8522 3.48 1 P 0 
L 2.8522 3.48 3.5566 3.48 1 P 0 
L 3.5566 3.48 3.6566 3.58 1 P 0 
L 3.6566 3.58 3.87385 3.58 1 P 0 
L 3.87385 3.58 3.87885 3.585 1 P 0 
L 3.87885 3.585 3.87885 3.5943 1 P 0 
L 3.87885 3.5943 3.88385 3.5993 1 P 0 
L 3.88385 3.5993 3.89885 3.5993 1 P 0 
L 3.89885 3.5993 3.90385 3.5943 1 P 0 
L 3.90385 3.5943 3.90385 3.585 1 P 0 
L 3.90385 3.585 3.90885 3.58 1 P 0 
L 3.90885 3.58 3.93 3.58 1 P 0 
L 3.93 3.58 3.95 3.6 1 P 0 
P 3.95 3.6 7 P 0 8 0;1=0,3=1
P 0.835 3.6 7 P 0 8 0;1=2,3=1
L 3.95 3.7 3.95 3.68998996 1 P 0 
L 3.95 3.68998996 3.93028002 3.67026998 1 P 0 
L 3.93028002 3.67026998 3.93028002 3.66321004 1 P 0 
L 3.93028002 3.66321004 3.9398 3.65368002 1 P 0 
L 3.9398 3.65368002 3.9398 3.64661998 1 P 0 
L 3.9398 3.64661998 3.92918002 3.636 1 P 0 
L 3.92918002 3.636 3.92211998 3.636 1 P 0 
L 3.92211998 3.636 3.9126 3.64553002 1 P 0 
L 3.9126 3.64553002 3.89993996 3.64553002 1 P 0 
L 3.89993996 3.64553002 3.86941004 3.615 1 P 0 
L 3.86941004 3.615 3.78366998 3.615 1 P 0 
L 3.78366998 3.615 3.77866998 3.62 1 P 0 
L 3.77866998 3.62 3.77866998 3.7063 1 P 0 
L 3.77866998 3.7063 3.77366998 3.7113 1 P 0 
L 3.77366998 3.7113 3.75866998 3.7113 1 P 0 
L 3.75866998 3.7113 3.75366998 3.7063 1 P 0 
L 3.75366998 3.7063 3.75366998 3.62 1 P 0 
L 3.75366998 3.62 3.74866998 3.615 1 P 0 
L 3.74866998 3.615 3.73366998 3.615 1 P 0 
L 3.73366998 3.615 3.72866998 3.62 1 P 0 
L 3.72866998 3.62 3.72866998 3.6609 1 P 0 
L 3.72866998 3.6609 3.72366998 3.6659 1 P 0 
L 3.72366998 3.6659 3.70866998 3.6659 1 P 0 
L 3.70866998 3.6659 3.70366998 3.6609 1 P 0 
L 3.70366998 3.6609 3.70366998 3.62 1 P 0 
L 3.70366998 3.62 3.69866998 3.615 1 P 0 
L 3.69866998 3.615 3.65361004 3.615 1 P 0 
L 3.65361004 3.615 3.53861004 3.5 1 P 0 
L 3.53861004 3.5 2.86048996 3.5 1 P 0 
L 2.86048996 3.5 2.70548996 3.655 1 P 0 
L 2.70548996 3.655 2.68286998 3.655 1 P 0 
L 2.68286998 3.655 2.67786998 3.65 1 P 0 
L 2.67786998 3.65 2.67786998 3.6392 1 P 0 
L 2.67786998 3.6392 2.67286998 3.6342 1 P 0 
L 2.67286998 3.6342 2.65786998 3.6342 1 P 0 
L 2.65786998 3.6342 2.65286998 3.6392 1 P 0 
L 2.65286998 3.6392 2.65286998 3.65 1 P 0 
L 2.65286998 3.65 2.64786998 3.655 1 P 0 
L 2.64786998 3.655 2.63286998 3.655 1 P 0 
L 2.63286998 3.655 2.62786998 3.65 1 P 0 
L 2.62786998 3.65 2.62786998 3.6392 1 P 0 
L 2.62786998 3.6392 2.62286998 3.6342 1 P 0 
L 2.62286998 3.6342 2.60786998 3.6342 1 P 0 
L 2.60786998 3.6342 2.60286998 3.6392 1 P 0 
L 2.60286998 3.6392 2.60286998 3.65 1 P 0 
L 2.60286998 3.65 2.59786998 3.655 1 P 0 
L 2.59786998 3.655 2.58286998 3.655 1 P 0 
L 2.58286998 3.655 2.57786998 3.65 1 P 0 
L 2.57786998 3.65 2.57786998 3.6392 1 P 0 
L 2.57786998 3.6392 2.57286998 3.6342 1 P 0 
L 2.57286998 3.6342 2.55786998 3.6342 1 P 0 
L 2.55786998 3.6342 2.55286998 3.6392 1 P 0 
L 2.55286998 3.6392 2.55286998 3.65 1 P 0 
L 2.55286998 3.65 2.54786998 3.655 1 P 0 
L 2.54786998 3.655 2.53286998 3.655 1 P 0 
L 2.53286998 3.655 2.52786998 3.65 1 P 0 
L 2.52786998 3.65 2.52786998 3.6392 1 P 0 
L 2.52786998 3.6392 2.52286998 3.6342 1 P 0 
L 2.52286998 3.6342 2.50786998 3.6342 1 P 0 
L 2.50786998 3.6342 2.50286998 3.6392 1 P 0 
L 2.50286998 3.6392 2.50286998 3.65 1 P 0 
L 2.50286998 3.65 2.49786998 3.655 1 P 0 
L 2.49786998 3.655 2.48286998 3.655 1 P 0 
L 2.48286998 3.655 2.47786998 3.65 1 P 0 
L 2.47786998 3.65 2.47786998 3.6392 1 P 0 
L 2.47786998 3.6392 2.47286998 3.6342 1 P 0 
L 2.47286998 3.6342 2.45786998 3.6342 1 P 0 
L 2.45786998 3.6342 2.45286998 3.6392 1 P 0 
L 2.45286998 3.6392 2.45286998 3.65 1 P 0 
L 2.45286998 3.65 2.44786998 3.655 1 P 0 
L 2.44786998 3.655 1.91 3.655 1 P 0 
L 1.91 3.655 1.86 3.605 1 P 0 
L 1.86 3.605 1.50501004 3.605 1 P 0 
L 1.50501004 3.605 1.46001004 3.56 1 P 0 
L 1.46001004 3.56 1.435 3.56 1 P 0 
L 1.435 3.56 1.41 3.585 1 P 0 
L 1.41 3.585 1.39 3.585 1 P 0 
L 1.39 3.585 1.38 3.575 1 P 0 
L 1.38 3.575 1.205 3.575 1 P 0 
L 1.205 3.575 1.16 3.62 1 P 0 
L 1.16 3.62 1.115 3.62 1 P 0 
L 1.115 3.62 1.08 3.585 1 P 0 
L 1.08 3.585 0.925 3.585 1 P 0 
L 0.925 3.585 0.915 3.595 1 P 0 
P 3.95 3.7 7 P 0 8 0;1=0,3=1
P 0.915 3.595 7 P 0 8 0;1=2,3=1
L 4.1184 3.5362 4.16303002 3.49156998 1 P 0 
L 4.16303002 3.49156998 4.16303002 3.48448996 1 P 0 
L 4.16303002 3.48448996 4.14346004 3.46491998 1 P 0 
L 4.14346004 3.46491998 4.14346004 3.45783996 1 P 0 
L 4.14346004 3.45783996 4.15406004 3.44723996 1 P 0 
L 4.15406004 3.44723996 4.16113996 3.44723996 1 P 0 
L 4.16113996 3.44723996 4.18071004 3.46681004 1 P 0 
L 4.18071004 3.46681004 4.18778996 3.46681004 1 P 0 
L 4.18778996 3.46681004 4.2042 3.4504 1 P 0 
L 4.2042 3.4504 4.2042 3.3186 1 P 0 
L 4.2042 3.3186 4.109 3.2234 1 P 0 
L 4.109 3.2234 4.109 3.134 1 P 0 
L 4.109 3.134 4.085 3.11 1 P 0 
P 4.1184 3.5362 7 P 0 8 0;1=2,3=1
P 4.085 3.11 7 P 0 8 0;1=0,3=1
P 3.38 1.025 7 P 0 8 0;1=2,3=1
L 0.62 3.235 0.59 3.205 1 P 0 
L 0.59 3.205 0.59 3.18 1 P 0 
L 0.59 3.18 0.515 3.105 1 P 0 
L 0.515 3.105 0.515 2.88621998 1 P 0 
L 0.515 2.88621998 0.60121998 2.8 1 P 0 
L 0.60121998 2.8 0.91616998 2.8 1 P 0 
L 0.91616998 2.8 0.94966998 2.7665 1 P 0 
L 0.94966998 2.7665 0.96833002 2.7665 1 P 0 
L 0.96833002 2.7665 1.00183002 2.8 1 P 0 
L 1.00183002 2.8 1.17571998 2.8 1 P 0 
L 1.17571998 2.8 1.24786004 2.87213996 1 P 0 
L 1.24786004 2.87213996 1.24786004 2.91286004 1 P 0 
L 1.24786004 2.91286004 1.263 2.928 1 P 0 
L 1.263 2.928 1.36871004 2.928 1 P 0 
L 1.36871004 2.928 1.46998996 2.82671998 1 P 0 
L 1.46998996 2.82671998 2.86328002 2.82671998 1 P 0 
L 2.86328002 2.82671998 2.97216998 2.71783002 1 P 0 
L 2.97216998 2.71783002 2.97216998 2.05716998 1 P 0 
L 2.97216998 2.05716998 2.868 1.953 1 P 0 
L 2.868 1.953 2.868 1.787 1 P 0 
L 2.868 1.787 2.97 1.685 1 P 0 
L 2.97 1.685 2.97 1.58841998 1 P 0 
L 2.97 1.58841998 3.305 1.25341998 1 P 0 
L 3.305 1.25341998 3.305 1.1 1 P 0 
L 3.305 1.1 3.38 1.025 1 P 0 
P 0.62 3.235 7 P 0 8 0;1=2,3=1
L 0.825 3.39 0.8275 3.3925 1 P 0 
L 0.8275 3.3925 0.96066998 3.3925 1 P 0 
L 0.96066998 3.3925 0.99816998 3.355 1 P 0 
L 0.99816998 3.355 1.36 3.355 1 P 0 
L 1.36 3.355 1.405 3.4 1 P 0 
L 1.405 3.4 1.45501004 3.4 1 P 0 
L 1.45501004 3.4 1.49501004 3.44 1 P 0 
L 1.49501004 3.44 1.62 3.44 1 P 0 
L 1.62 3.44 1.705 3.525 1 P 0 
L 1.705 3.525 1.89316004 3.525 1 P 0 
L 1.89316004 3.525 1.94316004 3.575 1 P 0 
L 1.94316004 3.575 2.3072 3.575 1 P 0 
L 2.3072 3.575 2.3922 3.49 1 P 0 
L 2.3922 3.49 2.75733002 3.49 1 P 0 
L 2.75733002 3.49 2.84233002 3.405 1 P 0 
L 2.84233002 3.405 3.13501004 3.405 1 P 0 
L 3.13501004 3.405 3.31351004 3.2265 1 P 0 
L 3.31351004 3.2265 3.37416004 3.2265 1 P 0 
L 3.37416004 3.2265 3.40023996 3.20041998 1 P 0 
L 3.40023996 3.20041998 3.48041004 3.20041998 1 P 0 
L 3.48041004 3.20041998 3.50583002 3.175 1 P 0 
L 3.50583002 3.175 3.871 3.175 1 P 0 
L 3.871 3.175 3.925 3.229 1 P 0 
L 3.925 3.229 3.925 3.239 1 P 0 
P 3.925 3.239 7 P 0 8 0;1=0,3=1
P 0.825 3.39 7 P 0 8 0;1=2,3=1
L 3.795 3.758 3.768 3.758 1 P 0 
L 3.768 3.758 3.53 3.52 1 P 0 
L 3.53 3.52 2.86878002 3.52 1 P 0 
L 2.86878002 3.52 2.71378002 3.675 1 P 0 
L 2.71378002 3.675 1.90001004 3.675 1 P 0 
L 1.90001004 3.675 1.85001004 3.625 1 P 0 
L 1.85001004 3.625 1.39501004 3.625 1 P 0 
L 1.39501004 3.625 1.36501004 3.595 1 P 0 
L 1.36501004 3.595 1.215 3.595 1 P 0 
L 1.215 3.595 1.165 3.645 1 P 0 
L 1.165 3.645 1.13 3.645 1 P 0 
L 1.13 3.645 1.11 3.665 1 P 0 
L 1.11 3.665 1.02 3.665 1 P 0 
L 1.02 3.665 0.9775 3.6225 1 P 0 
L 0.9775 3.6225 0.82566998 3.6225 1 P 0 
L 0.82566998 3.6225 0.8125 3.60933002 1 P 0 
L 0.8125 3.60933002 0.8125 3.58251004 1 P 0 
L 0.8125 3.58251004 0.86 3.53501004 1 P 0 
L 0.86 3.53501004 0.86 3.4229 1 P 0 
L 0.86 3.4229 0.855 3.4179 1 P 0 
L 0.855 3.4179 0.795 3.4179 1 P 0 
P 0.795 3.4179 7 P 0 8 0;1=2,3=1
P 3.795 3.758 7 P 0 8 0;1=0,3=1
L 0.66 3.185 0.66 3.165 1 P 0 
L 0.66 3.165 0.565 3.07 1 P 0 
L 0.565 3.07 0.565 3.04845 1 P 0 
L 0.565 3.04845 0.57 3.04345 1 P 0 
L 0.57 3.04345 0.575 3.04345 1 P 0 
L 0.575 3.04345 0.58 3.03845 1 P 0 
L 0.58 3.03845 0.58 3.02345 1 P 0 
L 0.58 3.02345 0.575 3.01845 1 P 0 
L 0.575 3.01845 0.57 3.01845 1 P 0 
L 0.57 3.01845 0.565 3.01345 1 P 0 
L 0.565 3.01345 0.565 2.99845 1 P 0 
L 0.565 2.99845 0.57 2.99345 1 P 0 
L 0.57 2.99345 0.5844 2.99345 1 P 0 
L 0.5844 2.99345 0.5894 2.98845 1 P 0 
L 0.5894 2.98845 0.5894 2.97345 1 P 0 
L 0.5894 2.97345 0.5844 2.96845 1 P 0 
L 0.5844 2.96845 0.57 2.96845 1 P 0 
L 0.57 2.96845 0.565 2.96345 1 P 0 
L 0.565 2.96345 0.565 2.94498996 1 P 0 
L 0.565 2.94498996 0.62498996 2.885 1 P 0 
L 0.62498996 2.885 0.75998996 2.885 1 P 0 
L 0.75998996 2.885 0.79498996 2.85 1 P 0 
L 0.79498996 2.85 0.79755 2.85 1 P 0 
L 0.79755 2.85 0.79756998 2.84998002 1 P 0 
L 0.79756998 2.84998002 0.81538996 2.84998002 1 P 0 
L 0.81538996 2.84998002 0.81541004 2.85 1 P 0 
L 0.81541004 2.85 1.165 2.85 1 P 0 
L 1.165 2.85 1.2075 2.8925 1 P 0 
L 1.2075 2.8925 1.2075 2.92908002 1 P 0 
L 1.2075 2.92908002 1.24641998 2.968 1 P 0 
L 1.24641998 2.968 1.38528996 2.968 1 P 0 
L 1.38528996 2.968 1.48656998 2.86671998 1 P 0 
L 1.48656998 2.86671998 2.89328002 2.86671998 1 P 0 
L 2.89328002 2.86671998 3.01216998 2.74783002 1 P 0 
L 3.01216998 2.74783002 3.01216998 1.98455 1 P 0 
L 3.01216998 1.98455 3.0325 1.96421998 1 P 0 
L 3.0325 1.96421998 3.0325 1.7675 1 P 0 
L 3.0325 1.7675 3.01 1.745 1 P 0 
L 3.01 1.745 3.01 1.605 1 P 0 
L 3.01 1.605 3.32378996 1.29121004 1 P 0 
L 3.32378996 1.29121004 3.40878996 1.29121004 1 P 0 
L 3.40878996 1.29121004 3.46878996 1.23121004 1 P 0 
L 3.46878996 1.23121004 3.57121004 1.23121004 1 P 0 
L 3.57121004 1.23121004 3.62 1.28 1 P 0 
P 3.62 1.28 7 P 0 8 0;1=2,3=1
P 0.66 3.185 7 P 0 8 0;1=2,3=1
P 3.62 1.235 7 P 0 8 0;1=2,3=1
L 0.66 3.235 0.6204 3.1954 1 P 0 
L 0.6204 3.1954 0.6204 3.1654 1 P 0 
L 0.6204 3.1654 0.53671998 3.08171998 1 P 0 
L 0.53671998 3.08171998 0.53671998 2.89328002 1 P 0 
L 0.53671998 2.89328002 0.57 2.86 1 P 0 
L 0.57 2.86 0.7567 2.86 1 P 0 
L 0.7567 2.86 0.79498002 2.82171998 1 P 0 
L 0.79498002 2.82171998 1.16671998 2.82171998 1 P 0 
L 1.16671998 2.82171998 1.2275 2.8825 1 P 0 
L 1.2275 2.8825 1.2275 2.92078996 1 P 0 
L 1.2275 2.92078996 1.25471004 2.948 1 P 0 
L 1.25471004 2.948 1.377 2.948 1 P 0 
L 1.377 2.948 1.47828002 2.84671998 1 P 0 
L 1.47828002 2.84671998 2.87828002 2.84671998 1 P 0 
L 2.87828002 2.84671998 2.99216998 2.73283002 1 P 0 
L 2.99216998 2.73283002 2.99216998 2.04718002 1 P 0 
L 2.99216998 2.04718002 2.888 1.94301004 1 P 0 
L 2.888 1.94301004 2.888 1.802 1 P 0 
L 2.888 1.802 2.99 1.7 1 P 0 
L 2.99 1.7 2.99 1.59671004 1 P 0 
L 2.99 1.59671004 3.3155 1.27121004 1 P 0 
L 3.3155 1.27121004 3.39878996 1.27121004 1 P 0 
L 3.39878996 1.27121004 3.46 1.21 1 P 0 
L 3.46 1.21 3.595 1.21 1 P 0 
L 3.595 1.21 3.62 1.235 1 P 0 
P 0.66 3.235 7 P 0 8 0;1=2,3=1
L 6.33 2.67 6.275 2.67 1 P 0 
L 6.275 2.67 6.255 2.69 1 P 0 
L 6.255 2.69 6.255 2.935 1 P 0 
L 6.255 2.935 6.11 3.08 1 P 0 
L 6.11 3.08 5.885 3.08 1 P 0 
L 5.885 3.08 5.83 3.135 1 P 0 
L 5.83 3.135 5.24158002 3.135 1 P 0 
L 5.24158002 3.135 5.13 3.24658002 1 P 0 
L 5.13 3.24658002 5.13 3.32 1 P 0 
L 5.13 3.32 5.045 3.405 1 P 0 
L 1.35 3.12 1.35 3.185 1 P 0 
L 1.35 3.185 1.3725 3.2075 1 P 0 
L 1.3725 3.2075 1.3725 3.3325 1 P 0 
L 1.3725 3.3325 1.42 3.38 1 P 0 
L 1.42 3.38 1.4633 3.38 1 P 0 
L 1.4633 3.38 1.4988 3.4155 1 P 0 
L 1.4988 3.4155 1.67633002 3.4155 1 P 0 
L 1.67633002 3.4155 1.76583002 3.505 1 P 0 
L 1.76583002 3.505 1.9583 3.505 1 P 0 
L 1.9583 3.505 1.9688 3.5155 1 P 0 
L 1.9688 3.5155 2.05933002 3.5155 1 P 0 
L 2.05933002 3.5155 2.08883002 3.545 1 P 0 
L 2.08883002 3.545 2.23 3.545 1 P 0 
L 2.23 3.545 2.3 3.475 1 P 0 
P 2.3 3.475 7 P 0 8 0;1=2,3=1
P 5.045 3.405 7 P 0 8 0;1=2,3=1
P 6.33 2.67 6 P 0 8 0;1=7,3=1
P 1.35 3.12 7 P 0 8 0;1=2,3=1
L 6.33 2.865 6.33 2.9 1 P 0 
L 6.33 2.9 6.12171998 3.10828002 1 P 0 
L 6.12171998 3.10828002 5.89671998 3.10828002 1 P 0 
L 5.89671998 3.10828002 5.85 3.155 1 P 0 
L 5.85 3.155 5.24986998 3.155 1 P 0 
L 5.24986998 3.155 5.15 3.25486998 1 P 0 
L 5.15 3.25486998 5.15 3.345 1 P 0 
L 5.15 3.345 5.09 3.405 1 P 0 
L 2.255 3.475 2.215 3.515 1 P 0 
L 2.215 3.515 2.10883002 3.515 1 P 0 
L 2.10883002 3.515 2.05933002 3.4655 1 P 0 
L 2.05933002 3.4655 2.01113996 3.4655 1 P 0 
L 2.01113996 3.4655 2.00613996 3.4605 1 P 0 
L 2.00613996 3.4605 2.00613996 3.445 1 P 0 
L 2.00613996 3.445 2.00113996 3.44 1 P 0 
L 2.00113996 3.44 1.98613996 3.44 1 P 0 
L 1.98613996 3.44 1.98113996 3.445 1 P 0 
L 1.98113996 3.445 1.98113996 3.4605 1 P 0 
L 1.98113996 3.4605 1.97613996 3.4655 1 P 0 
L 1.97613996 3.4655 1.96113996 3.4655 1 P 0 
L 1.96113996 3.4655 1.95613996 3.4605 1 P 0 
L 1.95613996 3.4605 1.95613996 3.445 1 P 0 
L 1.95613996 3.445 1.95113996 3.44 1 P 0 
L 1.95113996 3.44 1.93613996 3.44 1 P 0 
L 1.93613996 3.44 1.93113996 3.445 1 P 0 
L 1.93113996 3.445 1.93113996 3.4605 1 P 0 
L 1.93113996 3.4605 1.92613996 3.4655 1 P 0 
L 1.92613996 3.4655 1.91113996 3.4655 1 P 0 
L 1.91113996 3.4655 1.90613996 3.4605 1 P 0 
L 1.90613996 3.4605 1.90613996 3.445 1 P 0 
L 1.90613996 3.445 1.90113996 3.44 1 P 0 
L 1.90113996 3.44 1.88613996 3.44 1 P 0 
L 1.88613996 3.44 1.88113996 3.445 1 P 0 
L 1.88113996 3.445 1.88113996 3.4605 1 P 0 
L 1.88113996 3.4605 1.87613996 3.4655 1 P 0 
L 1.87613996 3.4655 1.86113996 3.4655 1 P 0 
L 1.86113996 3.4655 1.85613996 3.4605 1 P 0 
L 1.85613996 3.4605 1.85613996 3.445 1 P 0 
L 1.85613996 3.445 1.85113996 3.44 1 P 0 
L 1.85113996 3.44 1.83613996 3.44 1 P 0 
L 1.83613996 3.44 1.83113996 3.445 1 P 0 
L 1.83113996 3.445 1.83113996 3.4605 1 P 0 
L 1.83113996 3.4605 1.82613996 3.4655 1 P 0 
L 1.82613996 3.4655 1.77633002 3.4655 1 P 0 
L 1.77633002 3.4655 1.67633002 3.3655 1 P 0 
L 1.67633002 3.3655 1.59223002 3.3655 1 P 0 
L 1.59223002 3.3655 1.58723002 3.3705 1 P 0 
L 1.58723002 3.3705 1.58723002 3.39 1 P 0 
L 1.58723002 3.39 1.58223002 3.395 1 P 0 
L 1.58223002 3.395 1.56723002 3.395 1 P 0 
L 1.56723002 3.395 1.56223002 3.39 1 P 0 
L 1.56223002 3.39 1.56223002 3.3705 1 P 0 
L 1.56223002 3.3705 1.55723002 3.3655 1 P 0 
L 1.55723002 3.3655 1.54223002 3.3655 1 P 0 
L 1.54223002 3.3655 1.53723002 3.3705 1 P 0 
L 1.53723002 3.3705 1.53723002 3.39 1 P 0 
L 1.53723002 3.39 1.53223002 3.395 1 P 0 
L 1.53223002 3.395 1.51723002 3.395 1 P 0 
L 1.51723002 3.395 1.51223002 3.39 1 P 0 
L 1.51223002 3.39 1.51223002 3.3705 1 P 0 
L 1.51223002 3.3705 1.50723002 3.3655 1 P 0 
L 1.50723002 3.3655 1.4855 3.3655 1 P 0 
L 1.4855 3.3655 1.46 3.34 1 P 0 
P 2.255 3.475 7 P 0 8 0;1=2,3=1
P 5.09 3.405 7 P 0 8 0;1=2,3=1
P 6.33 2.865 7 P 0 8 0;1=0,3=1
P 1.46 3.34 7 P 0 8 0;1=2,3=1
L 1.26 0.72 1.2859 0.72 1 P 0 
L 1.2859 0.72 1.3977 0.8318 1 P 0 
L 1.3977 0.8318 1.81621998 0.8318 1 P 0 
L 1.81621998 0.8318 1.84 0.80801998 1 P 0 
L 1.84 0.80801998 1.84 0.75 1 P 0 
L 1.84 0.75 1.94 0.65 1 P 0 
L 1.94 0.65 2.07001004 0.65 1 P 0 
L 2.07001004 0.65 2.10931004 0.6107 1 P 0 
L 2.10931004 0.6107 2.24931004 0.6107 1 P 0 
L 2.24931004 0.6107 2.27501004 0.585 1 P 0 
L 2.27501004 0.585 2.47001004 0.585 1 P 0 
L 2.47001004 0.585 2.53001004 0.645 1 P 0 
L 2.53001004 0.645 2.9244 0.645 1 P 0 
L 2.9244 0.645 2.9254 0.646 1 P 0 
L 2.9254 0.646 3.2231 0.646 1 P 0 
L 3.2231 0.646 3.2246 0.6475 1 P 0 
L 3.2246 0.6475 3.36066998 0.6475 1 P 0 
L 3.36066998 0.6475 3.39566998 0.6125 1 P 0 
L 3.39566998 0.6125 3.41433002 0.6125 1 P 0 
L 3.41433002 0.6125 3.43433002 0.6325 1 P 0 
L 3.43433002 0.6325 3.65296998 0.6325 1 P 0 
L 3.65296998 0.6325 3.72196998 0.5635 1 P 0 
L 3.72196998 0.5635 4.82836998 0.5635 1 P 0 
L 4.82836998 0.5635 5.14 0.87513002 1 P 0 
L 5.14 0.87513002 5.14 0.92998996 1 P 0 
L 5.14 0.92998996 5.17 0.95998996 1 P 0 
L 5.17 0.95998996 5.17 0.96171004 1 P 0 
L 5.17 0.96171004 5.195 0.98671004 1 P 0 
L 5.195 0.98671004 5.195 1.21488996 1 P 0 
L 5.195 1.21488996 5.17 1.23988996 1 P 0 
L 5.17 1.23988996 5.17 1.62158996 1 P 0 
L 5.17 1.62158996 5.0031 1.78848996 1 P 0 
L 5.0031 1.78848996 5.0031 1.86433002 1 P 0 
L 5.0031 1.86433002 4.98583002 1.8816 1 P 0 
L 4.98583002 1.8816 4.8145 1.8816 1 P 0 
L 4.8145 1.8816 4.7761 1.8432 1 P 0 
L 4.7761 1.8432 4.7303 1.8432 1 P 0 
L 4.7303 1.8432 4.71083996 1.82373996 1 P 0 
L 4.71083996 1.82373996 4.6987 1.82373996 1 P 0 
P 1.26 0.72 7 P 0 8 0;1=0,3=1
P 4.6987 1.82373996 6 P 0 8 0;1=1,3=1
L 4.73806998 1.82373996 4.78673996 1.82373996 1 P 0 
L 4.78673996 1.82373996 4.803 1.84 1 P 0 
L 4.803 1.84 4.82 1.84 1 P 0 
L 4.82 1.84 4.8275 1.8325 1 P 0 
L 4.8275 1.8325 4.86078996 1.8325 1 P 0 
L 4.86078996 1.8325 4.92 1.77328996 1 P 0 
L 4.92 1.77328996 4.92 1.75326998 1 P 0 
L 4.92 1.75326998 4.95326998 1.72 1 P 0 
L 4.95326998 1.72 5.01501004 1.72 1 P 0 
L 5.01501004 1.72 5.1025 1.63251004 1 P 0 
L 5.1025 1.63251004 5.1025 1.42238002 1 P 0 
L 5.1025 1.42238002 5.125 1.39988002 1 P 0 
L 5.125 1.39988002 5.125 1.22178996 1 P 0 
L 5.125 1.22178996 5.14998996 1.1968 1 P 0 
L 5.14998996 1.1968 5.14998996 1 1 P 0 
L 5.14998996 1 5.09 0.94001004 1 P 0 
L 5.09 0.94001004 5.09 0.88171004 1 P 0 
L 5.09 0.88171004 4.82328996 0.615 1 P 0 
L 4.82328996 0.615 4.17985 0.615 1 P 0 
L 4.17985 0.615 4.16835 0.6035 1 P 0 
L 4.16835 0.6035 3.73855 0.6035 1 P 0 
L 3.73855 0.6035 3.65455 0.6875 1 P 0 
L 3.65455 0.6875 3.24118002 0.6875 1 P 0 
L 3.24118002 0.6875 3.22483996 0.70383996 1 P 0 
L 3.22483996 0.70383996 3.06916004 0.70383996 1 P 0 
L 3.06916004 0.70383996 3.042 0.731 1 P 0 
L 3.042 0.731 2.931 0.731 1 P 0 
L 2.931 0.731 2.905 0.705 1 P 0 
L 2.905 0.705 2.635 0.705 1 P 0 
L 2.635 0.705 2.615 0.725 1 P 0 
L 2.615 0.725 2.55 0.725 1 P 0 
L 2.55 0.725 2.45 0.625 1 P 0 
L 2.45 0.625 2.29998996 0.625 1 P 0 
L 2.29998996 0.625 2.26998996 0.655 1 P 0 
L 2.26998996 0.655 2.13218996 0.655 1 P 0 
L 2.13218996 0.655 2.06418996 0.723 1 P 0 
L 2.06418996 0.723 1.93528996 0.723 1 P 0 
L 1.93528996 0.723 1.8898 0.76848996 1 P 0 
L 1.8898 0.76848996 1.8898 0.8148 1 P 0 
L 1.8898 0.8148 1.5096 1.195 1 P 0 
L 1.5096 1.195 1.26 1.195 1 P 0 
L 1.26 1.195 0.885 0.82 1 P 0 
L 0.885 0.82 0.885 0.793 1 P 0 
L 0.885 0.793 0.842 0.75 1 P 0 
P 0.842 0.75 7 P 0 8 0;1=0,3=1
P 4.73806998 1.82373996 6 P 0 8 0;1=1,3=1
P 4.10816004 1.90248002 6 P 0 8 0;1=5,3=1
L 3.73648996 1.85735 3.775 1.81883996 1 P 0 
L 3.775 1.81883996 3.775 1.76 1 P 0 
L 3.775 1.76 3.785 1.75 1 P 0 
L 3.785 1.75 3.91 1.75 1 P 0 
L 3.91 1.75 3.935 1.775 1 P 0 
L 3.935 1.775 3.935 1.795 1 P 0 
L 3.935 1.795 3.945 1.805 1 P 0 
L 3.945 1.805 4.075 1.805 1 P 0 
L 4.075 1.805 4.09 1.82 1 P 0 
L 4.09 1.82 4.09 1.88431998 1 P 0 
L 4.09 1.88431998 4.10816004 1.90248002 1 P 0 
P 3.73648996 1.85735 7 P 0 8 0;1=2,3=1
P 4.10816004 1.82373996 6 P 0 8 0;1=1,3=1
L 3.925 3.291 3.935 3.291 1 P 0 
L 3.935 3.291 4.0475 3.1785 1 P 0 
L 4.0475 3.1785 4.0475 3.0325 1 P 0 
L 4.0475 3.0325 4.075 3.005 1 P 0 
L 4.345 3.02 4.2715 2.9465 1 P 0 
L 4.2715 2.9465 4.2715 2.91966998 1 P 0 
L 4.2715 2.91966998 4.25833002 2.9065 1 P 0 
L 4.25833002 2.9065 4.2365 2.9065 1 P 0 
L 4.2365 2.9065 4.18 2.85 1 P 0 
L 4.18 2.85 4.18 2.695 1 P 0 
L 4.18 2.695 4.035 2.55 1 P 0 
L 4.035 2.55 3.81828002 2.55 1 P 0 
L 3.81828002 2.55 3.7585 2.49021998 1 P 0 
L 3.7585 2.49021998 3.7585 2.4465 1 P 0 
L 3.7585 2.4465 3.82 2.385 1 P 0 
L 3.82 2.385 3.82 2.3539 1 P 0 
L 3.82 2.3539 3.8025 2.3364 1 P 0 
L 3.8025 2.3364 3.8025 2.2975 1 P 0 
L 3.8025 2.2975 3.93913996 2.16086004 1 P 0 
L 3.93913996 2.16086004 3.99913996 2.16086004 1 P 0 
L 3.99913996 2.16086004 4.01 2.15 1 P 0 
L 4.01 2.15 4.01 1.97073002 1 P 0 
L 4.01 1.97073002 4.02073002 1.96 1 P 0 
L 4.02073002 1.96 4.115 1.96 1 P 0 
L 4.115 1.96 4.13 1.945 1 P 0 
L 4.13 1.945 4.13 1.84558002 1 P 0 
L 4.13 1.84558002 4.10816004 1.82373996 1 P 0 
P 4.345 3.02 7 P 0 8 0;1=2,3=1
P 4.075 3.005 7 P 0 8 0;1=2,3=1
P 3.925 3.291 7 P 0 8 0;1=0,3=1
P 4.14753002 1.82373996 6 P 0 8 0;1=1,3=1
L 4.39 3.02 4.2915 2.9215 1 P 0 
L 4.2915 2.9215 4.2915 2.91138002 1 P 0 
L 4.2915 2.91138002 4.26661998 2.8865 1 P 0 
L 4.26661998 2.8865 4.24651004 2.8865 1 P 0 
L 4.24651004 2.8865 4.205 2.84498996 1 P 0 
L 4.205 2.84498996 4.205 2.69 1 P 0 
L 4.205 2.69 4.045 2.53 1 P 0 
L 4.045 2.53 3.83116998 2.53 1 P 0 
L 3.83116998 2.53 3.7785 2.47733002 1 P 0 
L 3.7785 2.47733002 3.7785 2.45651004 1 P 0 
L 3.7785 2.45651004 3.8725 2.36251004 1 P 0 
L 3.8725 2.36251004 3.8725 2.3136 1 P 0 
L 3.8725 2.3136 3.905 2.2811 1 P 0 
L 3.905 2.2811 3.905 2.225 1 P 0 
L 3.905 2.225 3.955 2.175 1 P 0 
L 3.955 2.175 4.005 2.175 1 P 0 
L 4.005 2.175 4.05 2.13 1 P 0 
L 4.05 2.13 4.05 2.055 1 P 0 
L 4.05 2.055 4.065 2.04 1 P 0 
L 4.065 2.04 4.16 2.04 1 P 0 
L 4.16 2.04 4.17 2.03 1 P 0 
L 4.17 2.03 4.17 1.84621004 1 P 0 
L 4.17 1.84621004 4.14753002 1.82373996 1 P 0 
L 4.13 3.005 4.1404 3.0154 1 P 0 
L 4.1404 3.0154 4.1404 3.2058 1 P 0 
L 4.1404 3.2058 4.2259 3.2913 1 P 0 
L 4.2259 3.2913 4.2259 3.3659 1 P 0 
L 4.2259 3.3659 4.31 3.45 1 P 0 
L 4.31 3.45 4.31 3.51 1 P 0 
L 4.31 3.51 4.305 3.515 1 P 0 
L 4.305 3.515 4.305 3.62328996 1 P 0 
L 4.305 3.62328996 4.22578996 3.7025 1 P 0 
L 4.22578996 3.7025 4.18738002 3.7025 1 P 0 
L 4.18738002 3.7025 4.17488002 3.69 1 P 0 
L 4.17488002 3.69 4.0411 3.69 1 P 0 
L 4.0411 3.69 3.9211 3.81 1 P 0 
L 3.9211 3.81 3.795 3.81 1 P 0 
P 4.39 3.02 7 P 0 8 0;1=2,3=1
P 4.13 3.005 7 P 0 8 0;1=2,3=1
P 3.795 3.81 7 P 0 8 0;1=0,3=1
L 4.615 3.11 4.645 3.08 1 P 0 
L 4.645 3.08 4.645 3.02 1 P 0 
L 4.645 3.02 4.605 2.98 1 P 0 
L 4.605 2.98 4.57 2.98 1 P 0 
L 4.57 2.98 4.545 2.955 1 P 0 
L 4.545 2.955 4.545 2.56183002 1 P 0 
L 4.545 2.56183002 4.5975 2.50933002 1 P 0 
L 4.5975 2.50933002 4.5975 2.3975 1 P 0 
L 4.5975 2.3975 4.64 2.355 1 P 0 
L 4.64 2.355 4.64 2.28 1 P 0 
L 4.64 2.28 4.715 2.205 1 P 0 
L 4.715 2.205 4.745 2.205 1 P 0 
L 4.745 2.205 4.765 2.185 1 P 0 
L 4.765 2.185 4.765 2.035 1 P 0 
L 4.765 2.035 4.7175 1.9875 1 P 0 
L 4.7175 1.9875 4.7175 1.92128002 1 P 0 
L 4.7175 1.92128002 4.6987 1.90248002 1 P 0 
P 4.615 3.11 7 P 0 8 0;1=2,3=1
P 4.6987 1.90248002 6 P 0 8 0;1=1,3=1
L 4.615 2.68408996 4.66591004 2.68408996 1 P 0 
L 4.66591004 2.68408996 4.6725 2.6775 1 P 0 
L 4.6725 2.6775 4.7347 2.6775 1 P 0 
L 4.7347 2.6775 4.83 2.5822 1 P 0 
L 4.83 2.5822 4.83 2.28656998 1 P 0 
L 4.83 2.28656998 4.8425 2.27406998 1 P 0 
L 4.8425 2.27406998 4.8425 2.17078002 1 P 0 
L 4.8425 2.17078002 4.90828002 2.105 1 P 0 
L 4.90828002 2.105 4.94501004 2.105 1 P 0 
L 4.94501004 2.105 5.01001004 2.04 1 P 0 
L 5.01001004 2.04 5.04658002 2.04 1 P 0 
L 5.04658002 2.04 5.14 1.94658002 1 P 0 
L 5.14 1.94658002 5.14 1.79303996 1 P 0 
L 5.14 1.79303996 5.285 1.64803996 1 P 0 
L 5.285 1.64803996 5.285 1.58501004 1 P 0 
L 5.285 1.58501004 5.32751004 1.5425 1 P 0 
L 5.32751004 1.5425 5.35533002 1.5425 1 P 0 
L 5.35533002 1.5425 5.40783002 1.49 1 P 0 
L 5.40783002 1.49 6.145 1.49 1 P 0 
L 6.145 1.49 6.22 1.415 1 P 0 
P 4.615 2.68408996 7 P 0 8 0;1=2,3=1
P 6.22 1.415 7 P 0 8 0;1=0,3=1
L 4.685 2.7 4.68671004 2.70171004 1 P 0 
L 4.68671004 2.70171004 4.73171004 2.70171004 1 P 0 
L 4.73171004 2.70171004 4.845 2.58841998 1 P 0 
L 4.845 2.58841998 4.845 2.29278996 1 P 0 
L 4.845 2.29278996 4.8575 2.28028996 1 P 0 
L 4.8575 2.28028996 4.8575 2.1775 1 P 0 
L 4.8575 2.1775 4.915 2.12 1 P 0 
L 4.915 2.12 4.95123002 2.12 1 P 0 
L 4.95123002 2.12 5.01623002 2.055 1 P 0 
L 5.01623002 2.055 5.0528 2.055 1 P 0 
L 5.0528 2.055 5.155 1.9528 1 P 0 
L 5.155 1.9528 5.155 1.79926004 1 P 0 
L 5.155 1.79926004 5.3 1.65426004 1 P 0 
L 5.3 1.65426004 5.3 1.59123002 1 P 0 
L 5.3 1.59123002 5.33373002 1.5575 1 P 0 
L 5.33373002 1.5575 5.36155 1.5575 1 P 0 
L 5.36155 1.5575 5.41405 1.505 1 P 0 
L 5.41405 1.505 5.815 1.505 1 P 0 
L 5.815 1.505 5.85 1.54 1 P 0 
L 5.85 1.54 5.93 1.54 1 P 0 
L 5.93 1.54 5.954 1.516 1 P 0 
L 5.954 1.516 6.22 1.516 1 P 0 
L 4.34436998 2.1387 4.322 2.16106998 1 P 0 
L 4.322 2.16106998 4.322 2.252 1 P 0 
L 4.322 2.252 4.39 2.32 1 P 0 
L 4.39 2.32 4.39 2.395 1 P 0 
L 4.39 2.395 4.375 2.41 1 P 0 
L 4.375 2.41 4.267 2.41 1 P 0 
L 4.267 2.41 4.209 2.468 1 P 0 
P 4.685 2.7 7 P 0 8 0;1=2,3=1
P 4.209 2.468 7 P 0 8 0;1=2,3=1
P 4.34436998 2.1387 6 P 0 8 0;1=1,3=1
P 6.22 1.516 7 P 0 8 0;1=0,3=1
L 4.975 2.26 4.975 2.17683002 1 P 0 
L 4.975 2.17683002 5 2.15183002 1 P 0 
L 5 2.15183002 5 2.13001004 1 P 0 
L 5 2.13001004 5.17 1.96001004 1 P 0 
L 5.17 1.96001004 5.17 1.81498996 1 P 0 
L 5.17 1.81498996 5.3625 1.62248996 1 P 0 
L 5.3625 1.62248996 5.3625 1.59248996 1 P 0 
L 5.3625 1.59248996 5.41498996 1.54 1 P 0 
L 5.41498996 1.54 5.825 1.54 1 P 0 
L 5.825 1.54 5.88 1.595 1 P 0 
L 5.88 1.595 6.195 1.595 1 P 0 
L 6.195 1.595 6.22 1.62 1 P 0 
P 4.975 2.26 7 P 0 8 0;1=2,3=1
P 6.22 1.62 7 P 0 8 0;1=0,3=1
L 4.925 2.26 4.955 2.29 1 P 0 
L 4.955 2.29 5 2.29 1 P 0 
L 5 2.29 5.04 2.25 1 P 0 
L 5.04 2.25 5.08 2.25 1 P 0 
L 5.08 2.25 5.22 2.11 1 P 0 
L 5.22 2.11 5.22 1.78621004 1 P 0 
L 5.22 1.78621004 5.3775 1.62871004 1 P 0 
L 5.3775 1.62871004 5.3775 1.6025 1 P 0 
L 5.3775 1.6025 5.42 1.56 1 P 0 
L 5.42 1.56 5.805 1.56 1 P 0 
L 5.805 1.56 5.9 1.655 1 P 0 
L 5.9 1.655 6.06 1.655 1 P 0 
L 6.06 1.655 6.22 1.815 1 P 0 
P 4.925 2.26 7 P 0 8 0;1=0,3=1
P 6.22 1.815 7 P 0 8 0;1=0,3=1
L 3.801 2.468 3.87308996 2.39591004 1 P 0 
L 3.87308996 2.39591004 3.87591004 2.39591004 1 P 0 
L 3.87591004 2.39591004 4.092 2.17981998 1 P 0 
L 4.092 2.17981998 4.092 2.11548996 1 P 0 
L 4.092 2.11548996 4.10816004 2.09933002 1 P 0 
P 3.801 2.468 7 P 0 8 0;1=2,3=1
P 4.10816004 2.09933002 6 P 0 8 0;1=1,3=1
L 4.14753002 2.09933002 4.114 2.13286004 1 P 0 
L 4.114 2.13286004 4.114 2.251 1 P 0 
L 4.114 2.251 3.94 2.425 1 P 0 
L 3.94 2.425 3.903 2.425 1 P 0 
L 3.903 2.425 3.86 2.468 1 P 0 
P 3.86 2.468 7 P 0 8 0;1=2,3=1
P 4.14753002 2.09933002 6 P 0 8 0;1=1,3=1
L 3.415 3.335 3.4485 3.3015 1 P 0 
L 3.4485 3.3015 3.4861 3.3015 1 P 0 
L 3.4861 3.3015 3.4911 3.3065 1 P 0 
L 3.4911 3.3065 3.4911 3.382 1 P 0 
L 3.4911 3.382 3.4961 3.387 1 P 0 
L 3.4961 3.387 3.5111 3.387 1 P 0 
L 3.5111 3.387 3.5161 3.382 1 P 0 
L 3.5161 3.382 3.5161 3.3065 1 P 0 
L 3.5161 3.3065 3.5211 3.3015 1 P 0 
L 3.5211 3.3015 3.81608996 3.3015 1 P 0 
L 3.81608996 3.3015 3.82808996 3.3135 1 P 0 
L 3.82808996 3.3135 3.9465 3.3135 1 P 0 
L 3.9465 3.3135 4.085 3.175 1 P 0 
L 4.085 3.175 4.085 3.165 1 P 0 
P 4.085 3.165 7 P 0 8 0;1=2,3=1
P 3.415 3.335 6 P 0 8 0;1=4,3=1
L 1.315 2.905 1.115 2.705 1 P 0 
L 1.115 2.705 1.115 1.59221998 1 P 0 
L 1.115 1.59221998 0.99 1.46721998 1 P 0 
L 0.99 1.46721998 0.99 1.45 1 P 0 
L 0.99 1.45 0.965 1.425 1 P 0 
L 0.965 1.425 0.94 1.425 1 P 0 
L 0.94 1.425 0.915 1.4 1 P 0 
P 1.315 2.905 6 P 0 8 0;1=8,3=1
P 0.915 1.4 7 P 0 8 0;1=2,3=1
L 0.965 1.4 0.97 1.4 1 P 0 
L 0.97 1.4 1.01553002 1.44553002 1 P 0 
L 1.01553002 1.44553002 1.01553002 1.46446004 1 P 0 
L 1.01553002 1.46446004 1.135 1.58393002 1 P 0 
L 1.135 1.58393002 1.135 2.695 1 P 0 
L 1.135 2.695 1.305 2.865 1 P 0 
L 1.305 2.865 1.32 2.865 1 P 0 
L 1.32 2.865 1.36 2.905 1 P 0 
P 1.36 2.905 6 P 0 8 0;1=8,3=1
P 0.965 1.4 7 P 0 8 0;1=2,3=1
L 0.345 3.09 0.44 2.995 1 P 0 
L 0.44 2.995 0.44 2.83316998 1 P 0 
L 0.44 2.83316998 0.51566998 2.7575 1 P 0 
L 0.51566998 2.7575 0.5225 2.7575 1 P 0 
L 0.5225 2.7575 0.5692 2.7108 1 P 0 
L 0.5692 2.7108 0.5692 2.6008 1 P 0 
L 0.5692 2.6008 0.58 2.59 1 P 0 
L 0.58 2.59 0.58 2.53116998 1 P 0 
L 0.58 2.53116998 0.57 2.52116998 1 P 0 
L 0.57 2.52116998 0.57 2.35 1 P 0 
L 0.57 2.35 0.545 2.325 1 P 0 
L 0.545 2.325 0.545 2.18 1 P 0 
L 0.545 2.18 0.565 2.16 1 P 0 
L 0.565 2.16 0.595 2.16 1 P 0 
L 0.595 2.16 0.605 2.15 1 P 0 
L 0.605 2.15 0.605 2.045 1 P 0 
L 0.605 2.045 0.625 2.025 1 P 0 
L 0.625 2.025 0.675 2.025 1 P 0 
L 0.675 2.025 0.7 2.05 1 P 0 
L 0.7 2.05 0.86683002 2.05 1 P 0 
L 0.86683002 2.05 0.87683002 2.04 1 P 0 
L 0.87683002 2.04 1 2.04 1 P 0 
L 1 2.04 1.015 2.025 1 P 0 
L 1.015 2.025 1.015 1.91 1 P 0 
L 1.015 1.91 0.99 1.885 1 P 0 
P 0.345 3.09 7 P 0 8 0;1=2,3=1
P 0.99 1.885 7 P 0 8 0;1=2,3=1
L 0.99 2.065 0.71 2.065 1 P 0 
L 0.71 2.065 0.65323002 2.12176998 1 P 0 
L 0.65323002 2.12176998 0.65323002 2.16678002 1 P 0 
L 0.65323002 2.16678002 0.6175 2.20251004 1 P 0 
L 0.6175 2.20251004 0.6175 2.28261998 1 P 0 
L 0.6175 2.28261998 0.585 2.31511998 1 P 0 
L 0.585 2.31511998 0.585 2.51495 1 P 0 
L 0.585 2.51495 0.595 2.52495 1 P 0 
L 0.595 2.52495 0.595 2.60395 1 P 0 
L 0.595 2.60395 0.5887 2.61025 1 P 0 
L 0.5887 2.61025 0.5887 2.7513 1 P 0 
L 0.5887 2.7513 0.47 2.87 1 P 0 
L 0.47 2.87 0.47 3.015 1 P 0 
L 0.47 3.015 0.395 3.09 1 P 0 
P 0.395 3.09 7 P 0 8 0;1=2,3=1
P 0.99 2.065 7 P 0 8 0;1=2,3=1
L 0.445 3.09 0.495 3.04 1 P 0 
L 0.495 3.04 0.495 2.875 1 P 0 
L 0.495 2.875 0.6037 2.7663 1 P 0 
L 0.6037 2.7663 0.6037 2.61646998 1 P 0 
L 0.6037 2.61646998 0.61 2.61016998 1 P 0 
L 0.61 2.61016998 0.61 2.36 1 P 0 
L 0.61 2.36 0.625 2.345 1 P 0 
L 0.625 2.345 0.625 2.29633996 1 P 0 
L 0.625 2.29633996 0.6325 2.28883996 1 P 0 
L 0.6325 2.28883996 0.6325 2.20873002 1 P 0 
L 0.6325 2.20873002 0.70123002 2.14 1 P 0 
L 0.70123002 2.14 0.975 2.14 1 P 0 
P 0.445 3.09 7 P 0 8 0;1=0,3=1
P 0.975 2.14 7 P 0 8 0;1=2,3=1
L 4.34436998 2.02058996 4.3641 2.04031998 1 P 0 
L 4.3641 2.04031998 4.3641 2.20388996 1 P 0 
L 4.3641 2.20388996 4.41 2.24978996 1 P 0 
L 4.41 2.24978996 4.41 2.405 1 P 0 
L 4.41 2.405 4.38 2.435 1 P 0 
L 4.38 2.435 4.325 2.435 1 P 0 
L 4.325 2.435 4.305 2.455 1 P 0 
L 4.305 2.455 4.305 2.6415 1 P 0 
L 4.305 2.6415 4.4335 2.77 1 P 0 
L 4.4335 2.77 4.4335 2.96308996 1 P 0 
L 4.4335 2.96308996 4.455 2.98458996 1 P 0 
L 4.455 2.98458996 4.455 3.125 1 P 0 
L 4.455 3.125 4.475 3.145 1 P 0 
L 4.475 3.145 4.52 3.145 1 P 0 
L 4.52 3.145 4.565 3.19 1 P 0 
L 4.565 3.19 4.60341998 3.19 1 P 0 
L 4.60341998 3.19 4.6175 3.20408002 1 P 0 
L 4.6175 3.20408002 4.6175 3.34566998 1 P 0 
L 4.6175 3.34566998 4.7325 3.46066998 1 P 0 
L 4.7325 3.46066998 4.7325 3.47933002 1 P 0 
L 4.7325 3.47933002 4.76816998 3.515 1 P 0 
L 4.76816998 3.515 4.93 3.515 1 P 0 
L 4.93 3.515 5 3.445 1 P 0 
L 5 3.445 5 3.38988002 1 P 0 
L 5 3.38988002 5.065 3.32488002 1 P 0 
L 5.065 3.32488002 5.065 3.255 1 P 0 
L 5.065 3.255 5.285 3.035 1 P 0 
L 5.285 3.035 5.285 2.99 1 P 0 
P 4.34436998 2.02058996 6 P 0 8 0;1=1,3=1
P 5.285 2.99 6 P 0 8 0;1=8,3=1
L 3.125 3.075 3.085 3.035 1 P 0 
L 3.085 3.035 2.895 3.035 1 P 0 
L 2.895 3.035 2.64 3.29 1 P 0 
L 2.64 3.29 2.28 3.29 1 P 0 
L 2.28 3.29 2.245 3.325 1 P 0 
L 2.245 3.325 2.15 3.325 1 P 0 
L 2.15 3.325 2.104 3.279 1 P 0 
L 2.104 3.279 2.017 3.279 1 P 0 
P 3.125 3.075 7 P 0 8 0;1=2,3=1
P 2.017 3.279 7 P 0 8 0;1=3,3=0
L 4.61996004 1.66626998 4.64283002 1.6434 1 P 0 
L 4.64283002 1.6434 4.64283002 1.62006004 1 P 0 
L 4.64283002 1.62006004 4.65288996 1.61 1 P 0 
L 4.65288996 1.61 4.665 1.61 1 P 0 
L 4.665 1.61 4.6875 1.5875 1 P 0 
L 4.6875 1.5875 4.75038002 1.5875 1 P 0 
L 4.75038002 1.5875 4.7847 1.55318002 1 P 0 
L 4.7847 1.55318002 4.7847 1.5144 1 P 0 
L 4.7847 1.5144 4.8726 1.4265 1 P 0 
L 4.8726 1.4265 4.9269 1.4265 1 P 0 
L 4.9269 1.4265 4.9512 1.4022 1 P 0 
L 4.9512 1.4022 4.9512 1.3178 1 P 0 
L 4.9512 1.3178 4.9165 1.2831 1 P 0 
L 4.9165 1.2831 4.9165 1.25366998 1 P 0 
L 4.9165 1.25366998 4.8755 1.21266998 1 P 0 
L 4.8755 1.21266998 4.8755 1.08331004 1 P 0 
L 4.8755 1.08331004 4.84768996 1.0555 1 P 0 
L 4.84768996 1.0555 4.6965 1.0555 1 P 0 
L 4.6965 1.0555 4.673 1.032 1 P 0 
L 4.673 1.032 4.136 1.032 1 P 0 
L 4.136 1.032 4.1157 1.0523 1 P 0 
L 4.1157 1.0523 3.75826004 1.0523 1 P 0 
L 3.75826004 1.0523 3.72588002 1.01991998 1 P 0 
L 3.72588002 1.01991998 3.72588002 0.99088002 1 P 0 
L 3.72588002 0.99088002 3.69 0.955 1 P 0 
L 3.69 0.955 3.3616 0.955 1 P 0 
L 3.3616 0.955 2.9766 1.34 1 P 0 
L 2.9766 1.34 1.19171004 1.34 1 P 0 
L 1.19171004 1.34 1.00171004 1.15 1 P 0 
L 1.00171004 1.15 0.835 1.15 1 P 0 
L 0.835 1.15 0.78 1.095 1 P 0 
L 0.78 1.095 0.685 1.095 1 P 0 
L 0.685 1.095 0.68 1.09 1 P 0 
L 0.68 1.09 0.67 1.09 1 P 0 
P 0.67 1.09 7 P 0 8 0;1=0,3=1
P 4.61996004 1.66626998 6 P 0 8 0;1=1,3=1
L 4.5806 1.70563996 4.60026998 1.68596998 1 P 0 
L 4.60026998 1.68596998 4.60026998 1.60971998 1 P 0 
L 4.60026998 1.60971998 4.60696004 1.60303002 1 P 0 
L 4.60696004 1.60303002 4.62638996 1.60303002 1 P 0 
L 4.62638996 1.60303002 4.63546004 1.59396004 1 P 0 
L 4.63546004 1.59396004 4.63546004 1.58575 1 P 0 
L 4.63546004 1.58575 4.65371004 1.5675 1 P 0 
L 4.65371004 1.5675 4.74208002 1.5675 1 P 0 
L 4.74208002 1.5675 4.7676 1.54198002 1 P 0 
L 4.7676 1.54198002 4.7676 1.5032 1 P 0 
L 4.7676 1.5032 4.8643 1.4065 1 P 0 
L 4.8643 1.4065 4.91861004 1.4065 1 P 0 
L 4.91861004 1.4065 4.9312 1.39391004 1 P 0 
L 4.9312 1.39391004 4.9312 1.32608996 1 P 0 
L 4.9312 1.32608996 4.89511004 1.29 1 P 0 
L 4.89511004 1.29 4.8869 1.29 1 P 0 
L 4.8869 1.29 4.8555 1.2586 1 P 0 
L 4.8555 1.2586 4.8555 1.0916 1 P 0 
L 4.8555 1.0916 4.8394 1.0755 1 P 0 
L 4.8394 1.0755 4.6882 1.0755 1 P 0 
L 4.6882 1.0755 4.6647 1.052 1 P 0 
L 4.6647 1.052 4.148 1.052 1 P 0 
L 4.148 1.052 4.1277 1.0723 1 P 0 
L 4.1277 1.0723 3.74671004 1.0723 1 P 0 
L 3.74671004 1.0723 3.72518996 1.05078002 1 P 0 
L 3.72518996 1.05078002 3.68238996 1.05078002 1 P 0 
L 3.68238996 1.05078002 3.66921998 1.03761004 1 P 0 
L 3.66921998 1.03761004 3.66921998 1.02421998 1 P 0 
L 3.66921998 1.02421998 3.6205 0.9755 1 P 0 
L 3.6205 0.9755 3.36938996 0.9755 1 P 0 
L 3.36938996 0.9755 2.98488996 1.36 1 P 0 
L 2.98488996 1.36 1.18341998 1.36 1 P 0 
L 1.18341998 1.36 0.99841998 1.175 1 P 0 
L 0.99841998 1.175 0.83 1.175 1 P 0 
L 0.83 1.175 0.78 1.125 1 P 0 
L 0.78 1.125 0.735 1.125 1 P 0 
P 4.5806 1.70563996 6 P 0 8 0;1=1,3=1
P 0.735 1.125 7 P 0 8 0;1=0,3=1
L 4.6 0.76 4.605 0.76 1 P 0 
L 4.605 0.76 4.615 0.75 1 P 0 
L 4.615 0.75 4.82498996 0.75 1 P 0 
L 4.82498996 0.75 5.105 1.03001004 1 P 0 
L 5.105 1.03001004 5.105 1.17498996 1 P 0 
L 5.105 1.17498996 5.085 1.19498996 1 P 0 
L 5.085 1.19498996 5.085 1.3833 1 P 0 
L 5.085 1.3833 5.0625 1.4058 1 P 0 
L 5.0625 1.4058 5.0625 1.60433002 1 P 0 
L 5.0625 1.60433002 5.01433002 1.6525 1 P 0 
L 5.01433002 1.6525 4.95066998 1.6525 1 P 0 
L 4.95066998 1.6525 4.93 1.67316998 1 P 0 
L 4.93 1.67316998 4.93 1.68668996 1 P 0 
L 4.93 1.68668996 4.88 1.73668996 1 P 0 
L 4.88 1.73668996 4.88 1.75501004 1 P 0 
L 4.88 1.75501004 4.86316998 1.77183996 1 P 0 
L 4.86316998 1.77183996 4.82313996 1.77183996 1 P 0 
L 4.82313996 1.77183996 4.81343996 1.76213996 1 P 0 
L 4.81343996 1.76213996 4.64218996 1.76213996 1 P 0 
L 4.64218996 1.76213996 4.61996004 1.78436998 1 P 0 
L 4.175 0.75 4.16 0.765 1 P 0 
L 4.16 0.765 4.16 0.91 1 P 0 
L 4.16 0.91 4.1107 0.9593 1 P 0 
L 4.1107 0.9593 3.8193 0.9593 1 P 0 
L 3.8193 0.9593 3.76 0.9 1 P 0 
L 3.76 0.9 3.76 0.835 1 P 0 
L 3.76 0.835 3.735 0.81 1 P 0 
L 3.735 0.81 3.62328996 0.81 1 P 0 
L 3.62328996 0.81 3.56328996 0.87 1 P 0 
L 3.56328996 0.87 3.48683002 0.87 1 P 0 
L 3.48683002 0.87 3.46433002 0.8925 1 P 0 
L 3.46433002 0.8925 3.33823002 0.8925 1 P 0 
L 3.33823002 0.8925 2.95073002 1.28 1 P 0 
L 2.95073002 1.28 1.235 1.28 1 P 0 
L 1.235 1.28 1.03 1.075 1 P 0 
L 1.03 1.075 0.93 1.075 1 P 0 
L 0.93 1.075 0.905 1.05 1 P 0 
P 4.6 0.76 7 P 0 8 0;1=2,3=1
P 4.61996004 1.78436998 6 P 0 8 0;1=1,3=1
P 0.905 1.05 7 P 0 8 0;1=2,3=1
P 4.175 0.75 7 P 0 8 0;1=2,3=1
P 2.078 0.8301 7 P 0 8 0;1=2,3=1
L 4.65933002 1.78436998 4.67583002 1.80086998 1 P 0 
L 4.67583002 1.80086998 4.76 1.80086998 1 P 0 
L 4.76 1.80086998 4.76626998 1.80713996 1 P 0 
L 4.76626998 1.80713996 4.80178002 1.80713996 1 P 0 
L 4.80178002 1.80713996 4.81126004 1.79766004 1 P 0 
L 4.81126004 1.79766004 4.86733996 1.79766004 1 P 0 
L 4.86733996 1.79766004 4.9 1.765 1 P 0 
L 4.9 1.765 4.9 1.74498002 1 P 0 
L 4.9 1.74498002 4.94498002 1.7 1 P 0 
L 4.94498002 1.7 4.99511998 1.7 1 P 0 
L 4.99511998 1.7 5.0825 1.61261998 1 P 0 
L 5.0825 1.61261998 5.0825 1.41408996 1 P 0 
L 5.0825 1.41408996 5.105 1.39158996 1 P 0 
L 5.105 1.39158996 5.105 1.205 1 P 0 
L 5.105 1.205 5.125 1.185 1 P 0 
L 5.125 1.185 5.125 1.01 1 P 0 
L 5.125 1.01 5.06 0.945 1 P 0 
L 5.06 0.945 5.06 0.88 1 P 0 
L 5.06 0.88 4.8216 0.6416 1 P 0 
L 4.8216 0.6416 4.17816004 0.6416 1 P 0 
L 4.17816004 0.6416 4.16006004 0.6235 1 P 0 
L 4.16006004 0.6235 3.74683996 0.6235 1 P 0 
L 3.74683996 0.6235 3.66283996 0.7075 1 P 0 
L 3.66283996 0.7075 3.24946998 0.7075 1 P 0 
L 3.24946998 0.7075 3.22948002 0.72748996 1 P 0 
L 3.22948002 0.72748996 3.08451004 0.72748996 1 P 0 
L 3.08451004 0.72748996 3.047 0.765 1 P 0 
L 3.047 0.765 2.925 0.765 1 P 0 
L 2.925 0.765 2.885 0.725 1 P 0 
L 2.885 0.725 2.645 0.725 1 P 0 
L 2.645 0.725 2.625 0.745 1 P 0 
L 2.625 0.745 2.54171004 0.745 1 P 0 
L 2.54171004 0.745 2.44171004 0.645 1 P 0 
L 2.44171004 0.645 2.30828002 0.645 1 P 0 
L 2.30828002 0.645 2.23988002 0.7134 1 P 0 
L 2.23988002 0.7134 2.15651004 0.7134 1 P 0 
L 2.15651004 0.7134 2.10551004 0.7644 1 P 0 
L 2.10551004 0.7644 2.07138996 0.7644 1 P 0 
L 2.07138996 0.7644 2.0573 0.77848996 1 P 0 
L 2.0573 0.77848996 2.0573 0.8094 1 P 0 
L 2.0573 0.8094 2.078 0.8301 1 P 0 
P 4.65933002 1.78436998 6 P 0 8 0;1=1,3=1
L 4.61996004 1.70563996 4.64 1.6856 1 P 0 
L 4.64 1.6856 4.64 1.65896998 1 P 0 
L 4.64 1.65896998 4.65396998 1.645 1 P 0 
L 4.65396998 1.645 4.66456998 1.645 1 P 0 
L 4.66456998 1.645 4.68 1.62956998 1 P 0 
L 4.68 1.62956998 4.68 1.62366998 1 P 0 
L 4.68 1.62366998 4.69616998 1.6075 1 P 0 
L 4.69616998 1.6075 4.75868002 1.6075 1 P 0 
L 4.75868002 1.6075 4.8047 1.56148002 1 P 0 
L 4.8047 1.56148002 4.8047 1.5227 1 P 0 
L 4.8047 1.5227 4.8809 1.4465 1 P 0 
L 4.8809 1.4465 4.93518996 1.4465 1 P 0 
L 4.93518996 1.4465 4.9712 1.41048996 1 P 0 
L 4.9712 1.41048996 4.9712 1.30671004 1 P 0 
L 4.9712 1.30671004 4.9555 1.29101004 1 P 0 
L 4.9555 1.29101004 4.9555 1.20566998 1 P 0 
L 4.9555 1.20566998 4.93 1.18016998 1 P 0 
L 4.93 1.18016998 4.93 1.1095 1 P 0 
L 4.93 1.1095 4.856 1.0355 1 P 0 
L 4.856 1.0355 4.7048 1.0355 1 P 0 
L 4.7048 1.0355 4.6793 1.01 1 P 0 
L 4.6793 1.01 4.53 1.01 1 P 0 
L 4.53 1.01 4.5005 0.9805 1 P 0 
L 4.5005 0.9805 4.2215 0.9805 1 P 0 
L 4.2215 0.9805 4.1985 1.0035 1 P 0 
L 4.1985 1.0035 4.132 1.0035 1 P 0 
L 4.132 1.0035 4.109 1.0265 1 P 0 
L 4.109 1.0265 3.89108002 1.0265 1 P 0 
L 3.89108002 1.0265 3.87188002 1.0073 1 P 0 
L 3.87188002 1.0073 3.8258 1.0073 1 P 0 
L 3.8258 1.0073 3.8083 1.0248 1 P 0 
L 3.8083 1.0248 3.75905 1.0248 1 P 0 
L 3.75905 1.0248 3.74588002 1.01163002 1 P 0 
L 3.74588002 1.01163002 3.74588002 0.9822 1 P 0 
L 3.74588002 0.9822 3.71 0.94631998 1 P 0 
L 3.71 0.94631998 3.71 0.895 1 P 0 
L 3.71 0.895 3.7025 0.8875 1 P 0 
L 3.7025 0.8875 3.60236998 0.8875 1 P 0 
L 3.60236998 0.8875 3.57986998 0.91 1 P 0 
L 3.57986998 0.91 3.50341004 0.91 1 P 0 
L 3.50341004 0.91 3.48091004 0.9325 1 P 0 
L 3.48091004 0.9325 3.35581004 0.9325 1 P 0 
L 3.35581004 0.9325 2.96831004 1.32 1 P 0 
L 2.96831004 1.32 1.2 1.32 1 P 0 
L 1.2 1.32 1.01 1.13 1 P 0 
L 1.01 1.13 0.87 1.13 1 P 0 
L 0.87 1.13 0.7815 1.0415 1 P 0 
L 0.7815 1.0415 0.6615 1.0415 1 P 0 
L 0.6615 1.0415 0.625 1.005 1 P 0 
P 4.61996004 1.70563996 6 P 0 8 0;1=1,3=1
P 0.625 1.005 7 P 0 8 0;1=2,3=1
L 4.65933002 1.70563996 4.68 1.68496998 1 P 0 
L 4.68 1.68496998 4.68 1.65476998 1 P 0 
L 4.68 1.65476998 4.685 1.64976998 1 P 0 
L 4.685 1.64976998 4.74476998 1.64976998 1 P 0 
L 4.74476998 1.64976998 4.75 1.655 1 P 0 
L 4.75 1.655 4.785 1.655 1 P 0 
L 4.785 1.655 4.8825 1.5575 1 P 0 
L 4.8825 1.5575 4.8825 1.5175 1 P 0 
L 4.8825 1.5175 4.8875 1.5125 1 P 0 
L 4.8875 1.5125 4.9275 1.5125 1 P 0 
L 4.9275 1.5125 4.9454 1.4946 1 P 0 
L 4.9454 1.4946 4.9454 1.46458996 1 P 0 
L 4.9454 1.46458996 4.9912 1.41878996 1 P 0 
L 4.9912 1.41878996 4.9912 1.29841998 1 P 0 
L 4.9912 1.29841998 4.9755 1.28271998 1 P 0 
L 4.9755 1.28271998 4.9755 1.19738002 1 P 0 
L 4.9755 1.19738002 4.95 1.17188002 1 P 0 
L 4.95 1.17188002 4.95 1.10121004 1 P 0 
L 4.95 1.10121004 4.86428996 1.0155 1 P 0 
L 4.86428996 1.0155 4.7305 1.0155 1 P 0 
L 4.7305 1.0155 4.695 0.98 1 P 0 
L 4.695 0.98 4.535 0.98 1 P 0 
L 4.535 0.98 4.5155 0.9605 1 P 0 
L 4.5155 0.9605 4.2132 0.9605 1 P 0 
L 4.2132 0.9605 4.1944 0.9793 1 P 0 
L 4.1944 0.9793 3.81101004 0.9793 1 P 0 
L 3.81101004 0.9793 3.74 0.90828996 1 P 0 
L 3.74 0.90828996 3.74 0.8725 1 P 0 
L 3.74 0.8725 3.735 0.8675 1 P 0 
L 3.735 0.8675 3.59408002 0.8675 1 P 0 
L 3.59408002 0.8675 3.57158002 0.89 1 P 0 
L 3.57158002 0.89 3.49511998 0.89 1 P 0 
L 3.49511998 0.89 3.47261998 0.9125 1 P 0 
L 3.47261998 0.9125 3.34751998 0.9125 1 P 0 
L 3.34751998 0.9125 2.96001998 1.3 1 P 0 
L 2.96001998 1.3 1.22 1.3 1 P 0 
L 1.22 1.3 1.025 1.105 1 P 0 
L 1.025 1.105 0.935 1.105 1 P 0 
P 4.65933002 1.70563996 6 P 0 8 0;1=1,3=1
P 0.935 1.105 7 P 0 8 0;1=0,3=1
L 0.955 1.92 0.935 1.92 1 P 0 
L 0.935 1.92 0.925 1.91 1 P 0 
L 0.925 1.91 0.895 1.91 1 P 0 
L 0.895 1.91 0.875 1.89 1 P 0 
L 0.875 1.89 0.875 1.86 1 P 0 
L 0.875 1.86 0.645 1.63 1 P 0 
L 0.645 1.63 0.645 1.295 1 P 0 
P 0.645 1.295 7 P 0 8 0;1=3,3=0
P 0.955 1.92 7 P 0 8 0;1=2,3=1
L 0.565 1.13 0.565 1.14183002 1 P 0 
L 0.565 1.14183002 0.61566998 1.1925 1 P 0 
L 0.61566998 1.1925 0.65066998 1.1925 1 P 0 
L 0.65066998 1.1925 0.67066998 1.2125 1 P 0 
L 0.67066998 1.2125 0.6775 1.2125 1 P 0 
L 0.6775 1.2125 0.7175 1.2525 1 P 0 
L 0.7175 1.2525 0.7175 1.40248996 1 P 0 
L 0.7175 1.40248996 0.705 1.41498996 1 P 0 
L 0.705 1.41498996 0.705 1.43 1 P 0 
L 0.705 1.43 0.765 1.49 1 P 0 
L 0.765 1.49 0.885 1.49 1 P 0 
P 0.565 1.13 7 P 0 8 0;1=3,3=0
L 0.885 1.49 0.89 1.485 1 P 0 
L 0.89 1.485 0.977 1.485 1 P 0 
L 0.977 1.485 1.01 1.518 1 P 0 
L 1.01 1.518 1.01 1.735 1 P 0 
L 1.01 1.735 0.99 1.755 1 P 0 
P 0.885 1.49 7 P 0 8 0;1=0,3=1
P 0.99 1.755 7 P 0 8 0;1=2,3=1
L 4.34436998 1.82373996 4.34373996 1.82373996 1 P 0 
L 4.34373996 1.82373996 4.31 1.79 1 P 0 
L 4.31 1.79 4.31 1.545 1 P 0 
L 4.31 1.545 4.29 1.525 1 P 0 
L 4.29 1.525 4.27276998 1.525 1 P 0 
L 4.27276998 1.525 4.27248002 1.52528996 1 P 0 
L 4.27248002 1.52528996 4.177 1.52528996 1 P 0 
L 4.177 1.52528996 4.167 1.51528996 1 P 0 
L 4.167 1.51528996 4.167 1.504 1 P 0 
L 4.167 1.504 4.1527 1.4897 1 P 0 
L 4.1527 1.4897 4.1397 1.4897 1 P 0 
L 4.1397 1.4897 4.126 1.476 1 P 0 
L 4.126 1.476 4.126 1.465 1 P 0 
L 4.126 1.465 4.112 1.451 1 P 0 
L 4.112 1.451 4.05601004 1.451 1 P 0 
L 4.05601004 1.451 4.04491998 1.43991004 1 P 0 
L 4.04491998 1.43991004 4.04491998 1.42361998 1 P 0 
L 4.04491998 1.42361998 4.03585 1.41455 1 P 0 
L 4.03585 1.41455 4.01955 1.41455 1 P 0 
L 4.01955 1.41455 4.00555 1.40055 1 P 0 
L 4.00555 1.40055 4.00555 1.38423996 1 P 0 
L 4.00555 1.38423996 3.99631004 1.375 1 P 0 
L 3.99631004 1.375 3.87231998 1.375 1 P 0 
L 3.87231998 1.375 3.83 1.33268002 1 P 0 
L 3.83 1.33268002 3.83 1.22128996 1 P 0 
L 3.83 1.22128996 3.73518002 1.12646998 1 P 0 
L 3.73518002 1.12646998 3.73518002 1.12018996 1 P 0 
L 3.73518002 1.12018996 3.7156 1.10061004 1 P 0 
L 3.7156 1.10061004 3.7156 1.08566998 1 P 0 
L 3.7156 1.08566998 3.70243002 1.0725 1 P 0 
L 3.70243002 1.0725 3.68748996 1.0725 1 P 0 
L 3.68748996 1.0725 3.68576998 1.07078002 1 P 0 
L 3.68576998 1.07078002 3.6741 1.07078002 1 P 0 
L 3.6741 1.07078002 3.64921998 1.0459 1 P 0 
L 3.64921998 1.0459 3.64921998 1.03423002 1 P 0 
L 3.64921998 1.03423002 3.61048996 0.9955 1 P 0 
L 3.61048996 0.9955 3.37768002 0.9955 1 P 0 
L 3.37768002 0.9955 2.99318002 1.38 1 P 0 
L 2.99318002 1.38 1.135 1.38 1 P 0 
L 1.135 1.38 1.08 1.325 1 P 0 
L 1.08 1.325 0.842 1.325 1 P 0 
L 0.842 1.325 0.75 1.417 1 P 0 
P 4.34436998 1.82373996 6 P 0 8 0;1=1,3=1
P 0.75 1.417 7 P 0 8 0;1=2,3=1
L 0.415 1.275 0.415 1.29498996 1 P 0 
L 0.415 1.29498996 0.43658996 1.31658002 1 P 0 
L 0.43658996 1.31658002 0.43658996 1.44158996 1 P 0 
L 0.43658996 1.44158996 0.455 1.46 1 P 0 
L 0.455 1.46 0.455 1.565 1 P 0 
L 0.455 1.565 0.49 1.6 1 P 0 
L 0.49 1.6 0.49 1.915 1 P 0 
L 0.49 1.915 0.45 1.955 1 P 0 
L 0.45 1.955 0.45 2.02 1 P 0 
L 0.45 2.02 0.42 2.05 1 P 0 
L 0.42 2.05 0.42 2.3 1 P 0 
L 0.42 2.3 0.47 2.35 1 P 0 
L 0.47 2.35 0.47 2.47501004 1 P 0 
L 0.47 2.47501004 0.51 2.51501004 1 P 0 
L 0.51 2.51501004 0.51 2.565 1 P 0 
L 0.51 2.565 0.46 2.615 1 P 0 
L 0.46 2.615 0.46 2.64243002 1 P 0 
L 0.46 2.64243002 0.45 2.65243002 1 P 0 
L 0.45 2.65243002 0.45 2.69695 1 P 0 
L 0.45 2.69695 0.2035 2.94345 1 P 0 
L 0.2035 2.94345 0.2035 3.12455 1 P 0 
L 0.2035 3.12455 0.207 3.12805 1 P 0 
L 0.207 3.12805 0.207 3.243 1 P 0 
L 0.207 3.243 0.145 3.305 1 P 0 
L 0.145 3.305 0.145 3.49878002 1 P 0 
L 0.145 3.49878002 0.19621998 3.55 1 P 0 
L 0.19621998 3.55 0.36 3.55 1 P 0 
L 0.36 3.55 0.518 3.708 1 P 0 
L 0.518 3.708 0.518 4.14011998 1 P 0 
L 0.518 4.14011998 0.59788002 4.22 1 P 0 
L 0.59788002 4.22 0.72583996 4.22 1 P 0 
L 0.72583996 4.22 0.7558 4.19003996 1 P 0 
P 0.415 1.275 7 P 0 8 0;1=2,3=1
P 0.7558 4.19003996 6 P 0 8 0;1=7,3=1
L 0.465 1.33 0.475 1.33 1 P 0 
L 0.475 1.33 0.515 1.37 1 P 0 
L 0.515 1.37 0.515 1.405 1 P 0 
L 0.515 1.405 0.58 1.47 1 P 0 
L 0.58 1.47 0.58 1.86 1 P 0 
L 0.58 1.86 0.505 1.935 1 P 0 
L 0.505 1.935 0.505 2.03 1 P 0 
L 0.505 2.03 0.4725 2.0625 1 P 0 
L 0.4725 2.0625 0.4725 2.1475 1 P 0 
L 0.4725 2.1475 0.485 2.16 1 P 0 
L 0.485 2.16 0.485 2.46878996 1 P 0 
L 0.485 2.46878996 0.525 2.50878996 1 P 0 
L 0.525 2.50878996 0.525 2.64316998 1 P 0 
L 0.525 2.64316998 0.41 2.75816998 1 P 0 
L 0.41 2.75816998 0.41 2.83498996 1 P 0 
L 0.41 2.83498996 0.30498996 2.94 1 P 0 
L 0.30498996 2.94 0.254 2.94 1 P 0 
L 0.254 2.94 0.2185 2.9755 1 P 0 
L 0.2185 2.9755 0.2185 3.11833002 1 P 0 
L 0.2185 3.11833002 0.222 3.12183002 1 P 0 
L 0.222 3.12183002 0.222 3.278 1 P 0 
L 0.222 3.278 0.165 3.335 1 P 0 
L 0.165 3.335 0.165 3.495 1 P 0 
L 0.165 3.495 0.205 3.535 1 P 0 
L 0.205 3.535 0.37 3.535 1 P 0 
L 0.37 3.535 0.508 3.673 1 P 0 
L 0.508 3.673 0.533 3.673 1 P 0 
L 0.533 3.673 0.55 3.69 1 P 0 
L 0.55 3.69 0.55 4.13 1 P 0 
L 0.55 4.13 0.587 4.167 1 P 0 
L 0.587 4.167 0.682 4.167 1 P 0 
L 0.682 4.167 0.705 4.19 1 P 0 
P 0.465 1.33 7 P 0 8 0;1=2,3=1
P 0.705 4.19 6 P 0 8 0;1=7,3=1
L 0.41408996 1.32591004 0.41408996 1.45408996 1 P 0 
L 0.41408996 1.45408996 0.44 1.48 1 P 0 
L 0.44 1.48 0.44 1.56 1 P 0 
L 0.44 1.56 0.405 1.595 1 P 0 
L 0.405 1.595 0.405 2.31 1 P 0 
L 0.405 2.31 0.455 2.36 1 P 0 
L 0.455 2.36 0.455 2.56183002 1 P 0 
L 0.455 2.56183002 0.445 2.57183002 1 P 0 
L 0.445 2.57183002 0.445 2.63621004 1 P 0 
L 0.445 2.63621004 0.435 2.64621004 1 P 0 
L 0.435 2.64621004 0.435 2.69073002 1 P 0 
L 0.435 2.69073002 0.26573002 2.86 1 P 0 
L 0.26573002 2.86 0.15146998 2.86 1 P 0 
L 0.15146998 2.86 0.132 2.87946998 1 P 0 
L 0.132 2.87946998 0.132 3.154 1 P 0 
L 0.132 3.154 0.17 3.192 1 P 0 
L 0.17 3.192 0.17 3.22 1 P 0 
L 0.17 3.22 0.115 3.275 1 P 0 
L 0.115 3.275 0.115 3.49 1 P 0 
L 0.115 3.49 0.19 3.565 1 P 0 
L 0.19 3.565 0.35 3.565 1 P 0 
L 0.35 3.565 0.503 3.718 1 P 0 
L 0.503 3.718 0.503 4.173 1 P 0 
L 0.503 4.173 0.57 4.24 1 P 0 
L 0.57 4.24 0.77 4.24 1 P 0 
L 0.77 4.24 0.805 4.205 1 P 0 
P 0.41408996 1.32591004 7 P 0 8 0;1=2,3=1
P 0.805 4.205 7 P 0 8 0;1=0,3=1
L 0.647 2.517 0.645 2.515 1 P 0 
L 0.645 2.515 0.645 2.29756004 1 P 0 
L 0.645 2.29756004 0.6475 2.29506004 1 P 0 
L 0.6475 2.29506004 0.6475 2.22466998 1 P 0 
L 0.6475 2.22466998 0.71716998 2.155 1 P 0 
L 0.71716998 2.155 0.955 2.155 1 P 0 
L 0.955 2.155 0.9625 2.1625 1 P 0 
L 0.9625 2.1625 1.0125 2.1625 1 P 0 
L 1.0125 2.1625 1.03 2.145 1 P 0 
L 1.03 2.145 1.03 1.89 1 P 0 
L 1.03 1.89 1 1.86 1 P 0 
L 1 1.86 0.91 1.86 1 P 0 
L 0.91 1.86 0.86 1.81 1 P 0 
L 0.86 1.81 0.86 1.74 1 P 0 
L 0.86 1.74 0.915 1.685 1 P 0 
L 0.915 1.685 0.915 1.576 1 P 0 
L 0.915 1.576 0.939 1.552 1 P 0 
P 0.647 2.517 7 P 0 8 0;1=3,3=0
P 0.939 1.552 7 P 0 8 0;1=2,3=1
L 0.326 1.487 0.375 1.536 1 P 0 
L 0.375 1.536 0.375 2.58256004 1 P 0 
L 0.375 2.58256004 0.38 2.58756004 1 P 0 
L 0.38 2.58756004 0.38 2.69378002 1 P 0 
L 0.38 2.69378002 0.29378002 2.78 1 P 0 
L 0.29378002 2.78 0.16 2.78 1 P 0 
L 0.16 2.78 0.15 2.79 1 P 0 
P 0.15 2.79 7 P 0 8 0;1=0,3=1
P 0.326 1.487 7 P 0 8 0;1=2,3=1
L 0.09 2.86 0.12 2.86 1 P 0 
L 0.12 2.86 0.18 2.8 1 P 0 
L 0.18 2.8 0.295 2.8 1 P 0 
L 0.295 2.8 0.42 2.675 1 P 0 
L 0.42 2.675 0.42 2.63998996 1 P 0 
L 0.42 2.63998996 0.43 2.62998996 1 P 0 
L 0.43 2.62998996 0.43 2.6 1 P 0 
L 0.43 2.6 0.4 2.57 1 P 0 
L 0.4 2.57 0.4 2.475 1 P 0 
L 0.4 2.475 0.39 2.465 1 P 0 
L 0.39 2.465 0.39 1.52978002 1 P 0 
L 0.39 1.52978002 0.385 1.52478002 1 P 0 
L 0.385 1.52478002 0.385 1.51898002 1 P 0 
L 0.385 1.51898002 0.416 1.48798002 1 P 0 
P 0.09 2.86 7 P 0 8 0;1=0,3=1
P 0.416 1.48798002 7 P 0 8 0;1=2,3=1
L 0.191 1.48798002 0.355 1.65198002 1 P 0 
L 0.355 1.65198002 0.355 2.58378002 1 P 0 
L 0.355 2.58378002 0.365 2.59378002 1 P 0 
L 0.365 2.59378002 0.365 2.67 1 P 0 
L 0.365 2.67 0.3275 2.7075 1 P 0 
L 0.3275 2.7075 0.28248996 2.7075 1 P 0 
L 0.28248996 2.7075 0.24998996 2.74 1 P 0 
L 0.24998996 2.74 0.165 2.74 1 P 0 
L 0.165 2.74 0.115 2.79 1 P 0 
L 0.115 2.79 0.09 2.79 1 P 0 
P 0.09 2.79 7 P 0 8 0;1=0,3=1
P 0.191 1.48798002 7 P 0 8 0;1=2,3=1
S P 0
OB 0.998669980315 2.765 I
OS 1.07 2.765
OS 1.106580019685 2.728419980315
OS 1.099080019685 2.720919980315
OC 1.092480019685 2.705 1.114997145669 2.704993110236 N
OS 1.092480019685 2.53248996063
OS 1.07 2.51
OS 0.916030019685 2.51
OC 0.875969980315 2.51 0.896 2.488997440945 N
OS 0.866030019685 2.51
OC 0.846 2.518019980315 0.846 2.488997440945 N
OC 0.826530019685 2.510519980315 0.846 2.488997933071 N
OS 0.82596003937 2.51
OS 0.820119980315 2.51
OS 0.820119980315 2.512930019685
OS 0.820830019685 2.513530019685
OC 0.8315 2.536480019685 0.801483562992 2.536480019685 N
OC 0.77146003937 2.536480019685 0.801480019685 2.536480019685 N
OC 0.77838996063 2.51728996063 0.801481692913 2.53647519685 N
OC 0.777819980315 2.511619980315 0.775313877953 2.514735531496 Y
OC 0.775969980315 2.51 0.795995964567 2.488996850394 N
OS 0.68088996063 2.51
OC 0.6769 2.51435 0.680885334646 2.514000590551 Y
OC 0.677019980315 2.517 0.647001476378 2.517031397638 N
OC 0.647 2.547019980315 0.647 2.517 N
OC 0.63775 2.54556003937 0.64699980315 2.516987795276 N
OC 0.632519980315 2.54936003937 0.636517814961 2.549363188976 Y
OS 0.632519980315 2.610169980315
OC 0.626219980315 2.62578996063 0.610006200787 2.610169980315 N
OS 0.626219980315 2.70791003937
OC 0.63116003937 2.7118 0.630218799213 2.707913582677 Y
OC 0.638 2.710980019685 0.638009645669 2.739998818898 N
OC 0.667019980315 2.74 0.638 2.74 N
OC 0.66038996063 2.75846003937 0.638005807087 2.74 N
OC 0.663480019685 2.765 0.663480314961 2.760999901575 Y
OS 0.730319980315 2.765
OC 0.733669980315 2.758819980315 0.730317519685 2.761000688976 Y
OC 0.72915 2.746169980315 0.75799734252 2.74299507874 N
OC 0.72455 2.74266003937 0.725175393701 2.746609645669 Y
OC 0.72 2.743019980315 0.719993602362 2.714000492126 N
OC 0.72 2.684980019685 0.72 2.714 N
OC 0.74885 2.710830019685 0.720000098425 2.714004035433 N
OC 0.75345 2.71433996063 0.752824606299 2.710390354331 Y
OC 0.758 2.713980019685 0.758006397638 2.742999507874 N
OC 0.787019980315 2.743 0.758 2.743 N
OC 0.782330019685 2.758819980315 0.757993503937 2.743 N
OC 0.785680019685 2.765 0.785682480315 2.761000688976 Y
OS 0.80921003937 2.765
OC 0.811119980315 2.75748996063 0.809208169291 2.761001673228 Y
OC 0.795980019685 2.732 0.825007775591 2.732 N
OC 0.854019980315 2.732 0.825 2.732 N
OC 0.838880019685 2.75748996063 0.824992224409 2.732 N
OC 0.84078996063 2.765 0.840791830709 2.761001673228 Y
OS 0.919330019685 2.765
OS 0.93375 2.750580019685
OC 0.949669980315 2.743980019685 0.949676870079 2.766497145669 N
OS 0.957969980315 2.743980019685
OC 0.9615 2.73811003937 0.957968602362 2.739982775591 Y
OC 0.957980019685 2.724 0.988001181102 2.724004822835 N
OC 0.965580019685 2.704030019685 0.988002165354 2.723994389764 N
OC 0.956980019685 2.683 0.986992814961 2.683 N
OC 1.017019980315 2.683 0.987 2.683 N
OC 1.009419980315 2.702969980315 0.986997834646 2.683005610236 N
OC 1.018019980315 2.724 0.988007185039 2.724 N
OC 0.99533996063 2.75311003937 0.987998523622 2.724000098425 N
OC 0.99348996063 2.759819980315 0.996315059055 2.756988877953 Y
OS 0.998669980315 2.765
OE
OB 1.011969980315 2.57978996063 H
OC 1.020019980315 2.60025 0.989994291339 2.600249901575 N
OC 0.959980019685 2.60025 0.99 2.60025 N
OC 0.963030019685 2.587069980315 0.989999114173 2.600253838583 N
OC 0.954980019685 2.56661003937 0.985005708661 2.56661003937 N
OC 1.015019980315 2.56661003937 0.985 2.56661003937 N
OC 1.011969980315 2.57978996063 0.985000885827 2.566606102362 N
OE
OB 0.754019980315 2.646 H
OC 0.754019980315 2.646 0.724 2.646 N
OE
OB 0.725019980315 2.578 H
OC 0.725019980315 2.578 0.695 2.578 N
OE
OB 0.77633996063 2.636880019685 H
OC 0.77478996063 2.62961003937 0.77411988189 2.633553149606 Y
OC 0.750619980315 2.601 0.779637795276 2.601 N
OC 0.77963996063 2.571980019685 0.77963996063 2.601 N
OC 0.80278996063 2.5835 0.77963996063 2.601000492126 N
OC 0.80903996063 2.58366003937 0.805978838583 2.581085826772 Y
OC 0.832 2.572980019685 0.831999901575 2.60299980315 N
OC 0.84113996063 2.57441003937 0.831985334646 2.60299773622 N
OC 0.84363996063 2.57316003937 0.841749015748 2.572503051181 Y
OC 0.872 2.552980019685 0.872 2.582997933071 N
OC 0.902019980315 2.583 0.872 2.583 N
OC 0.880169980315 2.61188996063 0.871995866142 2.583 N
OC 0.8782 2.61831003937 0.881260925197 2.615737007874 Y
OC 0.885019980315 2.637 0.856000295276 2.637 N
OC 0.826980019685 2.637 0.856 2.637 N
OC 0.82731003937 2.63265 0.855998917323 2.637014074803 N
OC 0.807630019685 2.620530019685 0.831998622047 2.602998917323 N
OC 0.80138996063 2.620219980315 0.804386220472 2.622866929134 Y
OC 0.795780019685 2.625119980315 0.779650590551 2.600992224409 N
OC 0.797330019685 2.63238996063 0.798000098425 2.628446850394 Y
OC 0.8215 2.661 0.792482185039 2.661 N
OC 0.76346003937 2.661 0.792480019685 2.661 N
OC 0.77633996063 2.636880019685 0.792484448819 2.661 N
OE
SE
P 0.869 2.672 7 P 0 8 0;1=2,3=1
P 0.871 2.713 6 P 0 8 0;1=4,3=1
P 0.686 2.74 6 P 0 8 0;1=8,3=1
P 0.64248002 2.58 7 P 0 8 0;1=2,3=1
P 0.736 2.525 6 P 0 8 0;1=8,3=1
L 6.01901998 2.001 5.87 1.85198002 1 P 0 
L 5.87 1.85198002 5.87 1.84 1 P 0 
P 6.01901998 2.001 6 P 0 8 0;1=7,3=1
P 5.87 1.84 7 P 0 8 0;1=3,3=0
L 3.18 2.685 3.18 2.6783 1 P 0 
L 3.18 2.6783 3.1675 2.66578996 1 P 0 
L 3.1675 2.66578996 3.1675 2.60201998 1 P 0 
L 3.1675 2.60201998 3.175 2.59451998 1 P 0 
L 3.175 2.59451998 3.175 2.235 1 P 0 
L 3.175 2.235 3.2325 2.1775 1 P 0 
L 3.2325 2.1775 3.2825 2.1775 1 P 0 
L 3.2825 2.1775 3.3 2.16 1 P 0 
L 3.3 2.16 3.3 2.11 1 P 0 
L 3.3 2.11 3.40118002 2.00881998 1 P 0 
L 3.40118002 2.00881998 3.40118002 1.79381998 1 P 0 
L 3.40118002 1.79381998 3.4275 1.7675 1 P 0 
L 3.4275 1.7675 3.5055 1.7675 1 P 0 
L 3.5055 1.7675 3.523 1.75 1 P 0 
P 3.18 2.685 6 P 0 8 0;1=4,3=1
P 3.523 1.75 6 P 0 8 0;1=8,3=1
L 4.712 1.157 4.712 1.19778002 1 P 0 
L 4.712 1.19778002 4.65061004 1.25916998 1 P 0 
L 4.65061004 1.25916998 4.48388996 1.25916998 1 P 0 
L 4.48388996 1.25916998 4.405 1.33806004 1 P 0 
L 4.405 1.33806004 4.405 1.49068002 1 P 0 
L 4.405 1.49068002 4.42311004 1.50878996 1 P 0 
P 4.712 1.157 7 P 0 8 0;1=3,3=0
P 4.42311004 1.50878996 6 P 0 8 0;1=1,3=1
L 4.38373996 1.46941998 4.365 1.45068002 0 P 0 
L 4.365 1.45068002 4.365 1.3 0 P 0 
L 4.365 1.3 4.3 1.235 1 P 0 
L 4.3 1.235 4.29 1.235 1 P 0 
P 4.29 1.235 7 P 0 8 0;1=3,3=0
P 4.38373996 1.46941998 6 P 0 8 0;1=1,3=1
L 4.34436998 1.50878996 4.34378996 1.50878996 1 P 0 
L 4.34378996 1.50878996 4.3 1.465 1 P 0 
L 4.3 1.465 4.3 1.305 1 P 0 
L 4.3 1.305 4.275 1.28 1 P 0 
L 4.275 1.28 4.195 1.28 1 P 0 
L 4.195 1.28 4.15 1.235 1 P 0 
P 4.15 1.235 7 P 0 8 0;1=3,3=0
P 4.34436998 1.50878996 6 P 0 8 0;1=1,3=1
L 4.185 1.17 4.185 1.24 1 P 0 
L 4.185 1.24 4.21 1.265 1 P 0 
L 4.21 1.265 4.28 1.265 1 P 0 
L 4.28 1.265 4.32 1.305 1 P 0 
L 4.32 1.305 4.32 1.44505 1 P 0 
L 4.32 1.44505 4.34436998 1.46941998 1 P 0 
P 4.185 1.17 7 P 0 8 0;1=3,3=0
P 4.34436998 1.46941998 6 P 0 8 0;1=1,3=1
L 4.38373996 1.3513 4.38373996 1.33626004 1 P 0 
L 4.38373996 1.33626004 4.405 1.315 1 P 0 
L 4.405 1.315 4.405 1.29365 1 P 0 
L 4.405 1.29365 4.45448002 1.24416998 1 P 0 
L 4.45448002 1.24416998 4.63083002 1.24416998 1 P 0 
L 4.63083002 1.24416998 4.665 1.21 1 P 0 
L 4.665 1.21 4.665 1.104 1 P 0 
P 4.665 1.104 7 P 0 8 0;1=3,3=0
P 4.38373996 1.3513 6 P 0 8 0;1=1,3=1
L 4.768 1.207 4.689 1.286 1 P 0 
L 4.689 1.286 4.5758 1.286 1 P 0 
L 4.5758 1.286 4.5604 1.3014 0 P 0 
L 4.5604 1.3014 4.5604 1.4772 0 P 0 
L 4.5604 1.4772 4.5479 1.4897 0 P 0 
L 4.5479 1.4897 4.44338996 1.4897 0 P 0 
L 4.44338996 1.4897 4.42311004 1.46941998 0 P 0 
P 4.768 1.207 7 P 0 8 0;1=3,3=0
P 4.42311004 1.46941998 6 P 0 8 0;1=1,3=1
L 4.42311004 1.43005 4.43811004 1.41505 0 P 0 
L 4.43811004 1.41505 4.43811004 1.3242 0 P 0 
L 4.43811004 1.3242 4.48931004 1.273 1 P 0 
L 4.48931004 1.273 4.658 1.273 1 P 0 
L 4.658 1.273 4.828 1.103 1 P 0 
P 4.828 1.103 7 P 0 8 0;1=3,3=0
P 4.42311004 1.43005 6 P 0 8 0;1=1,3=1
P 3.83128002 1.78371998 6 P 0 8 0;1=8,3=1
L 6.02558996 4.175 5.96498996 4.175 1 P 0 
L 5.96498996 4.175 5.88998996 4.25 1 P 0 
L 5.88998996 4.25 5.385 4.25 1 P 0 
L 5.385 4.25 5.3275 4.1925 1 P 0 
L 5.3275 4.1925 5.3275 4.0536 1 P 0 
L 5.3275 4.0536 5.3114 4.0375 1 P 0 
L 5.3114 4.0375 5.2275 4.0375 1 P 0 
L 5.2275 4.0375 5.07 3.88 1 P 0 
L 5.07 3.88 4.83621998 3.88 1 P 0 
L 4.83621998 3.88 4.43621998 3.48 1 P 0 
L 4.43621998 3.48 4.4 3.48 1 P 0 
L 4.4 3.48 4.275 3.355 1 P 0 
L 4.275 3.355 4.275 3.26 1 P 0 
L 4.275 3.26 4.18853996 3.17353996 1 P 0 
L 4.18853996 3.17353996 4.18853996 3.00646004 1 P 0 
L 4.18853996 3.00646004 4.14603996 2.96396004 1 P 0 
L 4.14603996 2.96396004 4.07396004 2.96396004 1 P 0 
L 4.07396004 2.96396004 4.0355 2.9255 1 P 0 
L 4.0355 2.9255 4.0355 2.75548996 1 P 0 
L 4.0355 2.75548996 4.00501004 2.725 1 P 0 
L 4.00501004 2.725 3.8609 2.725 1 P 0 
L 3.8609 2.725 3.7815 2.6456 1 P 0 
L 3.7815 2.6456 3.70438002 2.6456 1 P 0 
L 3.70438002 2.6456 3.57528002 2.5165 1 P 0 
L 3.57528002 2.5165 3.5342 2.5165 1 P 0 
L 3.5342 2.5165 3.4615 2.4438 1 P 0 
L 3.4615 2.4438 3.4615 2.2085 1 P 0 
L 3.4615 2.2085 3.485 2.185 1 P 0 
L 3.485 2.185 3.485 2.09 1 P 0 
L 3.485 2.09 3.585 1.99 1 P 0 
L 3.585 1.99 3.67303002 1.99 1 P 0 
L 3.67303002 1.99 3.83128002 1.83175 1 P 0 
L 3.83128002 1.83175 3.83128002 1.78371998 1 P 0 
P 6.02558996 4.175 7 P 0 8 0;1=0,3=1
L 6.1437 4.175 6.1437 4.1387 1 P 0 
L 6.1437 4.1387 6.12 4.115 1 P 0 
L 6.12 4.115 5.97835 4.115 1 P 0 
L 5.97835 4.115 5.96335 4.1 1 P 0 
L 5.96335 4.1 5.62 4.1 1 P 0 
L 5.62 4.1 5.595 4.125 1 P 0 
L 5.595 4.125 5.595 4.165 1 P 0 
L 5.595 4.165 5.555 4.205 1 P 0 
L 5.555 4.205 5.455 4.205 1 P 0 
L 5.455 4.205 5.4175 4.1675 1 P 0 
L 5.4175 4.1675 5.4175 4.0625 1 P 0 
L 5.4175 4.0625 5.365 4.01 1 P 0 
L 5.365 4.01 5.365 3.76121998 1 P 0 
L 5.365 3.76121998 5.20378002 3.6 1 P 0 
L 5.20378002 3.6 5.08 3.6 1 P 0 
L 5.08 3.6 5.02 3.66 1 P 0 
L 5.02 3.66 4.8139 3.66 1 P 0 
L 4.8139 3.66 4.7639 3.61 1 P 0 
L 4.7639 3.61 4.64243996 3.61 1 P 0 
L 4.64243996 3.61 4.55 3.51756004 1 P 0 
L 4.55 3.51756004 4.55 3.46715 1 P 0 
L 4.55 3.46715 4.475 3.39215 1 P 0 
L 4.475 3.39215 4.475 3.305 1 P 0 
L 4.475 3.305 4.36 3.19 1 P 0 
L 4.36 3.19 4.305 3.19 1 P 0 
L 4.305 3.19 4.25 3.135 1 P 0 
L 4.25 3.135 4.25 3.00426004 1 P 0 
L 4.25 3.00426004 4.1865 2.94076004 1 P 0 
L 4.1865 2.94076004 4.1865 2.94028002 1 P 0 
L 4.1865 2.94028002 4.1155 2.86928002 1 P 0 
L 4.1155 2.86928002 4.1155 2.7655 1 P 0 
L 4.1155 2.7655 4.03 2.68 1 P 0 
L 4.03 2.68 3.88173996 2.68 1 P 0 
L 3.88173996 2.68 3.80233996 2.6006 1 P 0 
L 3.80233996 2.6006 3.7244 2.6006 1 P 0 
L 3.7244 2.6006 3.68 2.5562 1 P 0 
L 3.68 2.5562 3.68 2.435 1 P 0 
L 3.68 2.435 3.7 2.415 1 P 0 
L 3.7 2.415 3.7 2.3 1 P 0 
L 3.7 2.3 3.675 2.275 1 P 0 
L 3.675 2.275 3.6 2.275 1 P 0 
L 3.6 2.275 3.5775 2.2525 1 P 0 
L 3.5775 2.2525 3.5775 2.10871998 1 P 0 
L 3.5775 2.10871998 3.62721998 2.059 1 P 0 
L 3.62721998 2.059 3.6677 2.059 1 P 0 
L 3.6677 2.059 3.86358996 1.86311004 1 P 0 
L 3.86358996 1.86311004 3.87193002 1.86311004 1 P 0 
P 6.1437 4.175 7 P 0 8 0;1=0,3=1
P 3.87193002 1.86311004 6 P 0 8 0;1=1,3=1
L 5.83 2.97 5.685 3.115 1 P 0 
L 5.685 3.115 5.23328996 3.115 1 P 0 
L 5.23328996 3.115 5.09 3.25828996 1 P 0 
L 5.09 3.25828996 5.09 3.32816998 1 P 0 
L 5.09 3.32816998 5.0225 3.39566998 1 P 0 
L 5.0225 3.39566998 5.0225 3.46751004 1 P 0 
L 5.0225 3.46751004 4.93001004 3.56 1 P 0 
L 4.93001004 3.56 4.74498996 3.56 1 P 0 
L 4.74498996 3.56 4.58 3.39501004 1 P 0 
L 4.58 3.39501004 4.58 3.29048996 1 P 0 
L 4.58 3.29048996 4.525 3.23548996 1 P 0 
L 4.525 3.23548996 4.525 3.18 1 P 0 
L 4.525 3.18 4.5125 3.1675 1 P 0 
L 4.5125 3.1675 4.46748996 3.1675 1 P 0 
L 4.46748996 3.1675 4.43 3.13001004 1 P 0 
L 4.43 3.13001004 4.43 3.045 1 P 0 
L 4.43 3.045 4.4125 3.0275 1 P 0 
L 4.4125 3.0275 4.4125 3.01066998 1 P 0 
L 4.4125 3.01066998 4.353 2.95116998 1 P 0 
L 4.353 2.95116998 4.353 2.90466998 1 P 0 
L 4.353 2.90466998 4.31 2.86166998 1 P 0 
L 4.31 2.86166998 4.31 2.80998996 1 P 0 
L 4.31 2.80998996 4.235 2.73498996 1 P 0 
L 4.235 2.73498996 4.235 2.67848996 1 P 0 
L 4.235 2.67848996 4.119 2.56248996 1 P 0 
L 4.119 2.56248996 4.119 2.28733996 1 P 0 
L 4.119 2.28733996 4.16403002 2.24231004 1 P 0 
L 4.16403002 2.24231004 4.16403002 2.07646004 1 P 0 
L 4.16403002 2.07646004 4.14753002 2.05996004 1 P 0 
P 4.14753002 2.05996004 6 P 0 8 0;1=1,3=1
P 5.83 2.97 7 P 0 8 0;1=2,3=1
L 3.12 2.565 3.155 2.53 1 P 0 
L 3.155 2.53 3.155 2.337 1 P 0 
L 3.155 2.337 3.119 2.301 1 P 0 
L 3.119 2.301 3.119 2.299 1 P 0 
P 3.12 2.565 7 P 0 8 0;1=2,3=1
P 3.119 2.299 7 P 0 8 0;1=0,3=1
L 3.125 2.254 3.09 2.289 1 P 0 
L 3.09 2.289 3.09 2.57 1 P 0 
L 3.09 2.57 3.145 2.625 1 P 0 
L 3.145 2.625 3.145 2.665 1 P 0 
L 3.145 2.665 3.12 2.69 1 P 0 
P 3.125 2.254 7 P 0 8 0;1=2,3=1
P 3.12 2.69 7 P 0 8 0;1=2,3=1
L 4.3 3.81 4.29 3.81 1 P 0 
L 4.29 3.81 4.215 3.885 1 P 0 
L 4.215 3.885 4.065 3.885 1 P 0 
L 4.065 3.885 3.995 3.955 1 P 0 
L 3.995 3.955 3.75 3.955 1 P 0 
L 3.75 3.955 3.685 3.89 1 P 0 
L 3.685 3.89 3.685 3.77 1 P 0 
L 3.685 3.77 3.5 3.585 1 P 0 
L 3.5 3.585 2.91 3.585 1 P 0 
L 2.91 3.585 2.77 3.725 1 P 0 
L 2.77 3.725 1.87328996 3.725 1 P 0 
L 1.87328996 3.725 1.82578996 3.6775 1 P 0 
L 1.82578996 3.6775 1.47066998 3.6775 1 P 0 
L 1.47066998 3.6775 1.45316998 3.695 1 P 0 
L 1.45316998 3.695 1.41 3.695 1 P 0 
L 1.41 3.695 1.3825 3.7225 1 P 0 
L 5.905 3.015 5.8741 2.9841 1 P 0 
L 5.8741 2.9841 5.8741 2.95771004 1 P 0 
L 5.8741 2.95771004 5.86388996 2.9475 1 P 0 
L 5.86388996 2.9475 5.82 2.9475 1 P 0 
L 5.82 2.9475 5.6725 3.095 1 P 0 
L 5.6725 3.095 5.38 3.095 1 P 0 
L 5.38 3.095 5.31 3.025 1 P 0 
L 5.31 3.025 5.31 2.98 1 P 0 
L 5.31 2.98 5.285 2.955 1 P 0 
L 5.285 2.955 5.26 2.955 1 P 0 
L 5.905 3.015 6.0592 3.015 1 P 0 
L 6.0592 3.015 6.235 2.8392 1 P 0 
L 6.235 2.8392 6.235 2.54998996 1 P 0 
L 6.235 2.54998996 6.315 2.46998996 1 P 0 
L 6.315 2.46998996 6.315 2.32501004 1 P 0 
L 6.315 2.32501004 6.29 2.30001004 1 P 0 
L 6.29 2.30001004 6.29 2.17501004 1 P 0 
L 6.29 2.17501004 6.305 2.16001004 1 P 0 
L 6.305 2.16001004 6.305 2.12545 1 P 0 
L 6.305 2.12545 6.25 2.07045 1 P 0 
L 6.25 2.07045 6.25 1.865 1 P 0 
L 6.25 1.865 6.46 1.655 1 P 0 
L 6.46 1.655 6.46 1.175 1 P 0 
L 6.46 1.175 6.435 1.15 1 P 0 
L 6.435 1.15 6.435 0.95 1 P 0 
L 6.435 0.95 6.285 0.8 1 P 0 
L 6.285 0.8 5.995 0.8 1 P 0 
L 5.995 0.8 5.8675 0.9275 1 P 0 
L 5.8675 0.9275 5.72251004 0.9275 1 P 0 
L 5.72251004 0.9275 5.69451004 0.9555 1 P 0 
L 5.69451004 0.9555 5.437 0.9555 1 P 0 
L 5.437 0.9555 5.4325 0.96 1 P 0 
L 5.4325 0.96 5.41 0.96 1 P 0 
P 4.3 3.81 7 P 0 8 0;1=0,3=1
P 1.3825 3.7225 6 P 0 8 0;1=8,3=1
P 5.905 3.015 6 P 0 8 0;1=7,3=1
P 5.41 0.96 7 P 0 8 0;1=3,3=0
P 5.26 2.955 7 P 0 8 0;1=2,3=1
L 3.35153002 2.17875 3.28028002 2.25 1 P 0 
L 3.28028002 2.25 3.22828996 2.25 1 P 0 
L 3.22828996 2.25 3.215 2.26328996 1 P 0 
L 3.215 2.26328996 3.215 2.6111 1 P 0 
L 3.215 2.6111 3.2075 2.6186 1 P 0 
L 3.2075 2.6186 3.2075 2.6425 1 P 0 
L 3.2075 2.6425 3.37 2.805 1 P 0 
L 3.37 2.805 3.37 2.86 1 P 0 
L 3.37 2.86 3.44 2.93 1 P 0 
L 3.44 2.93 3.44 2.95 1 P 0 
P 3.35153002 2.17875 7 P 0 8 0;1=2,3=1
P 3.44 2.95 6 P 0 8 0;1=4,3=1
L 3.3435 2.82 3.3435 2.8135 1 P 0 
L 3.3435 2.8135 3.30583002 2.77583002 1 P 0 
L 3.30583002 2.77583002 3.29875 2.77583002 1 P 0 
L 3.29875 2.77583002 3.26333996 2.81123996 1 P 0 
L 3.26333996 2.81123996 3.25626004 2.81123996 1 P 0 
L 3.25626004 2.81123996 3.24566004 2.80063996 1 P 0 
L 3.24566004 2.80063996 3.24566004 2.79356004 1 P 0 
L 3.24566004 2.79356004 3.28106998 2.75815 1 P 0 
L 3.28106998 2.75815 3.28106998 2.75106998 1 P 0 
L 3.28106998 2.75106998 3.27046998 2.74046998 1 P 0 
L 3.27046998 2.74046998 3.26338996 2.74046998 1 P 0 
L 3.26338996 2.74046998 3.22798002 2.77588002 1 P 0 
L 3.22798002 2.77588002 3.2209 2.77588002 1 P 0 
L 3.2209 2.77588002 3.2103 2.76528002 1 P 0 
L 3.2103 2.76528002 3.2103 2.7582 1 P 0 
L 3.2103 2.7582 3.24571004 2.72278996 1 P 0 
L 3.24571004 2.72278996 3.24571004 2.71571004 1 P 0 
L 3.24571004 2.71571004 3.23511004 2.70511004 1 P 0 
L 3.23511004 2.70511004 3.22803002 2.70511004 1 P 0 
L 3.22803002 2.70511004 3.19261998 2.74051998 1 P 0 
L 3.19261998 2.74051998 3.18553996 2.74051998 1 P 0 
L 3.18553996 2.74051998 3.17493996 2.72991998 1 P 0 
L 3.17493996 2.72991998 3.17493996 2.72283996 1 P 0 
L 3.17493996 2.72283996 3.21035 2.68743002 1 P 0 
L 3.21035 2.68743002 3.21035 2.68035 1 P 0 
L 3.21035 2.68035 3.1875 2.6575 1 P 0 
L 3.1875 2.6575 3.1875 2.61031004 1 P 0 
L 3.1875 2.61031004 3.195 2.60281004 1 P 0 
L 3.195 2.60281004 3.195 2.255 1 P 0 
L 3.195 2.255 3.22 2.23 1 P 0 
L 3.22 2.23 3.265 2.23 1 P 0 
L 3.265 2.23 3.27923002 2.21576998 1 P 0 
P 3.27923002 2.21576998 7 P 0 8 0;1=2,3=1
P 3.3435 2.82 6 P 0 8 0;1=4,3=1
L 3.106 3.35 3.074 3.318 5 P 0 
L 3.074 3.318 3.074 3.276 5 P 0 
L 3.074 3.276 3.09 3.26 5 P 0 
L 3.09 3.26 3.106 3.26 5 P 0 
P 3.106 3.26 7 P 0 8 0;1=2,3=1
P 3.106 3.35 6 P 0 8 0;1=8,3=1
L 3.98 3.365 3.97 3.355 5 P 0 
L 3.97 3.355 3.87 3.355 5 P 0 
L 3.87 3.355 3.855 3.37 5 P 0 
L 3.855 3.37 3.7 3.37 5 P 0 
P 3.98 3.365 7 P 0 8 0;1=2,3=1
P 3.7 3.37 7 P 0 8 0;1=2,3=1
P 3.55 3.37 7 P 0 8 0;1=2,3=1
P 4.175 3.37 7 P 0 8 0;1=2,3=1
L 4.175 3.37 4.15 3.345 5 P 0 
L 4.15 3.345 4.045 3.345 5 P 0 
L 4.045 3.345 4.025 3.365 5 P 0 
L 4.025 3.365 3.98 3.365 5 P 0 
L 3.414 3.235 3.505 3.235 5 P 0 
L 3.505 3.235 3.55 3.28 5 P 0 
L 3.55 3.28 3.555 3.275 5 P 0 
L 3.555 3.275 3.695 3.275 5 P 0 
L 3.695 3.275 3.71 3.26 5 P 0 
P 3.71 3.26 7 P 0 8 0;1=2,3=1
P 3.55 3.28 6 P 0 8 0;1=8,3=1
P 3.414 3.235 7 P 0 8 0;1=2,3=1
L 3.55 3.37 3.565 3.37 5 P 0 
L 3.565 3.37 3.58 3.355 5 P 0 
L 3.58 3.355 3.685 3.355 5 P 0 
L 3.685 3.355 3.7 3.37 5 P 0 
L 4.32 3.965 4.365 4.01 5 P 0 
L 4.365 4.01 4.365 4.15 5 P 0 
L 4.365 4.15 4.47 4.255 5 P 0 
L 4.47 4.255 5.095 4.255 5 P 0 
L 5.095 4.255 5.185 4.165 5 P 0 
L 5.185 4.165 5.221 4.165 5 P 0 
P 3.839 3.846 7 P 0 8 0;1=2,3=1
P 4.384 3.824 7 P 0 8 0;1=2,3=1
L 5.375 3.04 5.37036004 3.03536004 5 P 0 
L 5.37036004 3.03536004 5.37036004 3.01413996 5 P 0 
L 5.37036004 3.01413996 5.42 2.9645 5 P 0 
P 5.375 3.04 7 P 0 8 0;1=2,3=1
P 5.41 2.815 7 P 0 8 0;1=2,3=1
P 5.544 2.675 7 P 0 8 0;1=2,3=1
P 5.62 2.5487 7 P 0 8 0;1=2,3=1
P 5.42 2.9645 7 P 0 8 0;1=2,3=1
L 5.42 2.9645 5.4225 2.962 5 P 0 
L 5.4225 2.962 5.4225 2.8395 5 P 0 
L 5.4225 2.8395 5.41 2.827 5 P 0 
L 5.41 2.827 5.41 2.815 5 P 0 
L 5.62 2.5487 5.62 2.599 5 P 0 
L 5.62 2.599 5.544 2.675 5 P 0 
L 5.41 2.815 5.41 2.809 5 P 0 
L 5.41 2.809 5.544 2.675 5 P 0 
P 4.43 3.865 6 P 0 8 0;1=8,3=1
P 5.221 4.165 7 P 0 8 0;1=2,3=1
P 4.32 3.965 6 P 0 8 0;1=8,3=1
L 4.43 3.865 4.42 3.865 5 P 0 
L 4.42 3.865 4.32 3.965 5 P 0 
P 4.535 3.815 7 P 0 8 0;1=2,3=1
L 4.535 3.815 4.48 3.815 5 P 0 
L 4.48 3.815 4.43 3.865 5 P 0 
P 4.235 4.155 7 P 0 8 0;1=2,3=1
L 4.235 4.155 4.265 4.125 5 P 0 
L 4.265 4.125 4.265 4 5 P 0 
L 4.265 4 4.3 3.965 5 P 0 
L 4.3 3.965 4.32 3.965 5 P 0 
L 4.384 3.824 4.389 3.824 5 P 0 
L 4.389 3.824 4.43 3.865 5 P 0 
L 3.839 3.846 3.891 3.846 5 P 0 
L 3.891 3.846 3.91 3.865 5 P 0 
L 3.91 3.865 3.975 3.865 5 P 0 
L 3.975 3.865 4.01 3.83 5 P 0 
L 4.01 3.83 4.01 3.815 5 P 0 
L 4.01 3.815 4.055 3.77 5 P 0 
L 4.055 3.77 4.33 3.77 5 P 0 
L 4.33 3.77 4.384 3.824 5 P 0 
L 1.401 3.069 1.3845 3.0525 5 P 0 
L 1.3845 3.0525 1.38201998 3.0525 5 P 0 
L 1.38201998 3.0525 1.36251998 3.033 5 P 0 
L 1.36251998 3.033 1.183 3.033 5 P 0 
L 1.183 3.033 1.105 2.955 5 P 0 
L 1.105 2.955 0.96303996 2.955 5 P 0 
L 0.96303996 2.955 0.96053996 2.9525 5 P 0 
L 0.96053996 2.9525 0.9285 2.9525 5 P 0 
L 0.9285 2.9525 0.891 2.915 5 P 0 
L 0.891 2.915 0.78 2.915 5 P 0 
P 1.401 3.069 7 P 0 8 0;1=2,3=1
P 0.78 2.915 7 P 0 8 0;1=2,3=1
L 0.677 2.402 0.82 2.402 5 P 0 
L 0.82 2.402 0.857 2.365 5 P 0 
P 0.857 2.365 7 P 0 8 0;1=2,3=1
P 0.677 2.402 7 P 0 8 0;1=2,3=1
L 3.795 4.175 3.904 4.284 5 P 0 
L 3.904 4.284 5.329 4.284 5 P 0 
L 5.329 4.284 5.35 4.305 5 P 0 
L 5.35 4.305 6.13 4.305 5 P 0 
L 6.13 4.305 6.19 4.245 5 P 0 
L 6.19 4.245 6.19 4.13 5 P 0 
L 6.19 4.13 6.04 3.98 5 P 0 
L 5.55 4.02 5.58 4.05 5 P 0 
L 5.58 4.05 5.61303996 4.05 5 P 0 
L 5.61303996 4.05 5.66053996 4.0025 5 P 0 
L 5.66053996 4.0025 6.0175 4.0025 5 P 0 
L 6.0175 4.0025 6.04 3.98 5 P 0 
P 6.04 3.98 7 P 0 8 0;1=2,3=1
L 6.04 3.98 6 3.94 5 P 0 
L 6 3.94 5.78 3.94 5 P 0 
L 5.78 3.94 5.74 3.9 5 P 0 
L 5.74 3.9 5.74 3.76 5 P 0 
L 5.74 3.76 5.725 3.745 5 P 0 
L 5.725 3.745 5.725 3.565 5 P 0 
L 5.725 3.565 5.795 3.495 5 P 0 
L 5.795 3.495 5.795 3.277 5 P 0 
L 5.795 3.277 5.912 3.16 5 P 0 
L 5.912 3.16 6.377 3.16 5 P 0 
L 6.377 3.16 6.428 3.109 5 P 0 
L 6.428 3.109 6.428 2.558 5 P 0 
L 6.428 2.558 6.38 2.51 5 P 0 
L 6.38 2.51 6.38 2.3 5 P 0 
L 6.38 2.3 6.33 2.25 5 P 0 
L 6.33 2.25 6.33 2.11501004 5 P 0 
L 6.33 2.11501004 6.305 2.09001004 5 P 0 
L 6.305 2.09001004 6.305 1.95983996 5 P 0 
L 6.305 1.95983996 6.505 1.75983996 5 P 0 
L 6.505 1.75983996 6.505 0.97 5 P 0 
L 6.505 0.97 6.41 0.875 5 P 0 
L 6.41 0.875 6.41 0.865 5 P 0 
L 6.41 0.865 6.29 0.745 5 P 0 
L 6.29 0.745 6.005 0.745 5 P 0 
L 6.005 0.745 5.85 0.9 5 P 0 
L 5.85 0.9 5.69 0.9 5 P 0 
L 5.69 0.9 5.655 0.935 5 P 0 
L 5.655 0.935 5.507 0.935 5 P 0 
L 5.507 0.935 5.443 0.871 5 P 0 
P 5.443 0.871 7 P 0 8 0;1=2,3=1
P 3.795 4.175 7 P 0 8 0;1=2,3=1
P 5.55 4.02 7 P 0 8 0;1=2,3=1
L 1.385 3.875 1.38 3.87 1 P 0 
L 1.38 3.87 1.38 3.82 1 P 0 
L 1.38 3.82 1.355 3.795 1 P 0 
L 1.355 3.795 1.355 3.715 1 P 0 
L 1.355 3.715 1.4075 3.6625 1 P 0 
L 1.4075 3.6625 1.83201004 3.6625 1 P 0 
L 1.83201004 3.6625 1.87951004 3.71 1 P 0 
L 1.87951004 3.71 2.76 3.71 1 P 0 
L 2.76 3.71 2.9 3.57 1 P 0 
L 2.9 3.57 3.50621998 3.57 1 P 0 
L 3.50621998 3.57 3.7 3.76378002 1 P 0 
L 3.7 3.76378002 3.7 3.85 1 P 0 
L 3.7 3.85 3.79 3.94 1 P 0 
L 3.79 3.94 3.98541004 3.94 1 P 0 
L 3.98541004 3.94 4.05541004 3.87 1 P 0 
L 4.05541004 3.87 4.19 3.87 1 P 0 
L 4.19 3.87 4.25 3.81 1 P 0 
P 1.385 3.875 6 P 0 8 0;1=7,3=1
P 4.25 3.81 7 P 0 8 0;1=2,3=1
S P 0
OB 5.667119980315 2.42 I
OS 5.775 2.42
OS 5.805 2.39
OS 5.805 2.29
OS 5.785 2.27
OS 5.75 2.27
OS 5.72993996063 2.24993996063
OC 5.72386003937 2.25045 5.727116141732 2.252771555118 Y
OC 5.699430019685 2.263019980315 5.69943011811 2.232994980315 N
OS 5.69908996063 2.263019980315
OC 5.69516003937 2.267980019685 5.699041043307 2.267018110236 Y
OC 5.696019980315 2.275 5.666999114173 2.274992322835 N
OC 5.637980019685 2.275 5.667 2.275 N
OC 5.66666003937 2.245980019685 5.667001968504 2.275 N
OC 5.670480019685 2.240930019685 5.66662007874 2.241980019685 Y
OC 5.66941003937 2.233 5.699428248031 2.232986909449 N
OC 5.681980019685 2.208569980315 5.69943503937 2.232999901575 N
OC 5.68248996063 2.20248996063 5.679658464567 2.205313877953 Y
OS 5.675019980315 2.195019980315
OS 5.614980019685 2.195019980315
OS 5.552630019685 2.257369980315
OC 5.552569980315 2.26013996063 5.554043700787 2.258786220472 Y
OC 5.56023996063 2.27978996063 5.531234055118 2.27978996063 N
OC 5.545 2.305330019685 5.531219389764 2.279790059055 N
OS 5.545 2.37
OS 5.54911003937 2.37411003937
OS 5.549480019685 2.37426003937
OC 5.56573996063 2.390519980315 5.538 2.402 N
OS 5.56588996063 2.39088996063
OS 5.595 2.42
OS 5.640880019685 2.42
OC 5.667119980315 2.42 5.654 2.446989074803 N
OE
OB 5.624019980315 2.28 H
OC 5.624019980315 2.28 5.595 2.28 N
OE
SE
P 5.6695 2.2 7 P 0 8 0;1=2,3=1
P 5.771 2.279 6 P 0 8 0;1=7,3=1
P 5.789 2.366 7 P 0 8 0;1=2,3=1
P 5.6 2.4 7 P 0 8 0;1=2,3=1
L 5.44 2.183 5.44 2.305 5 P 0 
L 5.44 2.305 5.465 2.33 5 P 0 
L 5.465 2.33 5.465 2.405 5 P 0 
S P 0
OB 5.72345 2.215 I
OS 5.77 2.215
OS 5.775 2.21
OS 5.775 2.08
OS 5.765 2.07
OS 5.745119980315 2.07
OC 5.718880019685 2.07 5.732 2.043010925197 N
OS 5.700119980315 2.07
OC 5.687 2.073019980315 5.687 2.043010925197 N
OC 5.674269980315 2.07018996063 5.686994488189 2.042998720472 N
OS 5.673869980315 2.07
OS 5.662019980315 2.07
OS 5.66156003937 2.07025
OC 5.647 2.074019980315 5.646995472441 2.044001181102 N
OC 5.63198996063 2.07 5.646999901575 2.043987598425 N
OS 5.45738996063 2.07
OC 5.41261003937 2.07 5.435 2.049994389764 N
OS 5.365 2.07
OS 5.35 2.085
OS 5.35 2.165
OS 5.375 2.19
OS 5.58 2.19
OS 5.595 2.175
OS 5.652880019685 2.175
OC 5.686119980315 2.175 5.6695 2.200002362205 N
OS 5.7 2.175
OS 5.71 2.185
OS 5.71 2.2049
OC 5.72345 2.215 5.699420866142 2.232993602362 N
OE
OB 5.695019980315 2.129 H
OC 5.695019980315 2.129 5.666 2.129 N
OE
SE
L 5.458 2.165 5.44 2.183 5 P 0 
P 5.765 2.197 7 P 0 8 0;1=0,3=1
P 5.71 2.179 7 P 0 8 0;1=2,3=1
P 5.41 2.164 7 P 0 8 0;1=0,3=1
P 5.458 2.165 7 P 0 8 0;1=2,3=1
P 5.465 2.405 7 P 0 8 0;1=2,3=1
L 4.97 3.41 4.87 3.41 1 P 0 
L 4.87 3.41 4.835 3.375 1 P 0 
L 4.835 3.375 4.725 3.375 1 P 0 
L 4.725 3.375 4.66 3.31 1 P 0 
L 4.66 3.31 4.66 3.19 1 P 0 
L 4.66 3.19 4.59 3.12 1 P 0 
L 4.59 3.12 4.59 3.045 1 P 0 
L 4.59 3.045 4.515 2.97 1 P 0 
L 4.515 2.97 4.515 2.72498996 1 P 0 
L 4.515 2.72498996 4.5075 2.71748996 1 P 0 
L 4.5075 2.71748996 4.5075 2.45066998 1 P 0 
L 4.5075 2.45066998 4.54 2.41816998 1 P 0 
L 4.54 2.41816998 4.54 2.24501004 1 P 0 
L 4.54 2.24501004 4.4447 2.14971004 1 P 0 
L 4.4447 2.14971004 4.4447 2.0946 1 P 0 
L 4.4447 2.0946 4.4301 2.08 1 P 0 
L 4.4301 2.08 4.4182 2.08 1 P 0 
L 4.4182 2.08 4.405 2.0668 1 P 0 
L 4.405 2.0668 4.405 1.92373996 1 P 0 
L 4.405 1.92373996 4.38373996 1.90248002 1 P 0 
P 4.97 3.41 7 P 0 8 0;1=0,3=1
P 4.38373996 1.90248002 6 P 0 8 0;1=1,3=1
L 4.42311004 2.09933002 4.42311004 2.15811004 1 P 0 
L 4.42311004 2.15811004 4.515 2.25 1 P 0 
L 4.515 2.25 4.515 2.4 1 P 0 
L 4.515 2.4 4.4625 2.4525 1 P 0 
L 4.4625 2.4525 4.4625 2.52336004 1 P 0 
L 4.4625 2.52336004 4.4575 2.52836004 1 P 0 
L 4.4575 2.52836004 4.374 2.52836004 1 P 0 
L 4.374 2.52836004 4.369 2.53336004 1 P 0 
L 4.369 2.53336004 4.369 2.54836004 1 P 0 
L 4.369 2.54836004 4.374 2.55336004 1 P 0 
L 4.374 2.55336004 4.4575 2.55336004 1 P 0 
L 4.4575 2.55336004 4.4625 2.55836004 1 P 0 
L 4.4625 2.55836004 4.4625 2.57336004 1 P 0 
L 4.4625 2.57336004 4.4575 2.57836004 1 P 0 
L 4.4575 2.57836004 4.385 2.57836004 1 P 0 
L 4.385 2.57836004 4.378 2.58536004 1 P 0 
L 4.378 2.58536004 4.378 2.59636004 1 P 0 
L 4.378 2.59636004 4.385 2.60336004 1 P 0 
L 4.385 2.60336004 4.4575 2.60336004 1 P 0 
L 4.4575 2.60336004 4.4625 2.60836004 1 P 0 
L 4.4625 2.60836004 4.4625 2.7075 1 P 0 
L 4.4625 2.7075 4.495 2.74 1 P 0 
L 4.495 2.74 4.495 3.01816998 1 P 0 
L 4.495 3.01816998 4.5325 3.05566998 1 P 0 
L 4.5325 3.05566998 4.5325 3.07248996 1 P 0 
L 4.5325 3.07248996 4.57 3.10998996 1 P 0 
L 4.57 3.10998996 4.57 3.12828996 1 P 0 
L 4.57 3.12828996 4.64 3.19828996 1 P 0 
L 4.64 3.19828996 4.64 3.31828996 1 P 0 
L 4.64 3.31828996 4.73171004 3.41 1 P 0 
L 4.73171004 3.41 4.81 3.41 1 P 0 
P 4.81 3.41 7 P 0 8 0;1=2,3=1
P 4.42311004 2.09933002 6 P 0 8 0;1=5,3=1
P 3.445 1.815 7 P 0 8 0;1=2,3=1
L 4.58058996 1.90248002 4.56311004 1.885 1 P 0 
L 4.56311004 1.885 4.33501004 1.885 1 P 0 
L 4.33501004 1.885 4.32 1.86998996 1 P 0 
L 4.32 1.86998996 4.32 1.81273002 1 P 0 
L 4.32 1.81273002 4.295 1.78773002 1 P 0 
L 4.295 1.78773002 4.295 1.59496004 1 P 0 
L 4.295 1.59496004 4.27003996 1.57 1 P 0 
L 4.27003996 1.57 4.14743996 1.57 1 P 0 
L 4.14743996 1.57 4.12366004 1.54621998 1 P 0 
L 4.12366004 1.54621998 4.12366004 1.50166004 1 P 0 
L 4.12366004 1.50166004 4.11353002 1.49153002 1 P 0 
L 4.11353002 1.49153002 4.06896998 1.49153002 1 P 0 
L 4.06896998 1.49153002 4.05328996 1.47585 1 P 0 
L 4.05328996 1.47585 4.05328996 1.47136004 1 P 0 
L 4.05328996 1.47136004 4.02748002 1.44555 1 P 0 
L 4.02748002 1.44555 4.02298996 1.44555 1 P 0 
L 4.02298996 1.44555 4.00555 1.42811004 1 P 0 
L 4.00555 1.42811004 4.00555 1.42361998 1 P 0 
L 4.00555 1.42361998 3.9881 1.40616998 1 P 0 
L 3.9881 1.40616998 3.86381998 1.40616998 1 P 0 
L 3.86381998 1.40616998 3.841 1.42898996 1 P 0 
L 3.841 1.42898996 3.841 1.61 1 P 0 
L 3.841 1.61 3.6625 1.7885 1 P 0 
L 3.6625 1.7885 3.5615 1.7885 1 P 0 
L 3.5615 1.7885 3.535 1.815 1 P 0 
L 3.535 1.815 3.445 1.815 1 P 0 
P 4.58058996 1.90248002 6 P 0 8 0;1=1,3=1
L 4.54121998 1.6269 4.5431 1.6269 1 P 0 
L 4.5431 1.6269 4.56 1.61 1 P 0 
L 4.56 1.61 4.56 1.58 1 P 0 
L 4.56 1.58 4.57 1.57 1 P 0 
L 4.57 1.57 4.6265 1.57 1 P 0 
L 4.6265 1.57 4.64 1.5565 1 P 0 
L 4.64 1.5565 4.64 1.54 1 P 0 
L 4.64 1.54 4.65 1.53 1 P 0 
L 4.65 1.53 4.7402 1.53 1 P 0 
L 4.7402 1.53 4.7554 1.5148 1 P 0 
L 4.7554 1.5148 4.7554 1.4871 1 P 0 
L 4.7554 1.4871 4.8575 1.385 1 P 0 
L 4.8575 1.385 4.9097 1.385 1 P 0 
P 4.54121998 1.6269 6 P 0 8 0;1=1,3=1
P 4.9097 1.385 6 P 0 8 0;1=7,3=1
L 5.3 4.065 5.23 4.065 1 P 0 
L 5.23 4.065 5.06 3.895 1 P 0 
L 5.06 3.895 4.83 3.895 1 P 0 
L 4.83 3.895 4.435 3.5 1 P 0 
L 4.435 3.5 4.39 3.5 1 P 0 
L 4.39 3.5 4.24965 3.35965 1 P 0 
L 4.24965 3.35965 4.24965 3.26611998 1 P 0 
L 4.24965 3.26611998 4.16543002 3.1819 1 P 0 
L 4.16543002 3.1819 4.16543002 3.00456998 1 P 0 
L 4.16543002 3.00456998 4.14086004 2.98 1 P 0 
L 4.14086004 2.98 4.065 2.98 1 P 0 
L 4.065 2.98 4.0205 2.9355 1 P 0 
L 4.0205 2.9355 4.0205 2.76171004 1 P 0 
L 4.0205 2.76171004 3.99878996 2.74 1 P 0 
L 3.99878996 2.74 3.8499 2.74 1 P 0 
L 3.8499 2.74 3.7749 2.665 1 P 0 
L 3.7749 2.665 3.745 2.665 1 P 0 
L 3.745 2.665 3.7125 2.6975 1 P 0 
L 3.7125 2.6975 3.68566998 2.6975 1 P 0 
L 3.68566998 2.6975 3.6725 2.68433002 1 P 0 
L 3.6725 2.68433002 3.6725 2.66248996 1 P 0 
L 3.6725 2.66248996 3.6125 2.60248996 1 P 0 
L 3.6125 2.60248996 3.6125 2.60153002 1 P 0 
L 3.6125 2.60153002 3.59346998 2.5825 1 P 0 
L 3.59346998 2.5825 3.59251004 2.5825 1 P 0 
L 3.59251004 2.5825 3.54151004 2.5315 1 P 0 
L 3.54151004 2.5315 3.52798002 2.5315 1 P 0 
L 3.52798002 2.5315 3.4465 2.45001998 1 P 0 
L 3.4465 2.45001998 3.4465 2.21648996 1 P 0 
L 3.4465 2.21648996 3.4378 2.20778996 1 P 0 
L 3.4378 2.20778996 3.4378 2.16108996 1 P 0 
L 3.4378 2.16108996 3.465 2.13388996 1 P 0 
L 3.465 2.13388996 3.465 2.045 1 P 0 
L 3.465 2.045 3.427 2.007 1 P 0 
L 3.427 2.007 3.427 1.86498996 1 P 0 
L 3.427 1.86498996 3.44821004 1.84378002 1 P 0 
L 3.44821004 1.84378002 3.57036998 1.84378002 1 P 0 
L 3.57036998 1.84378002 3.57508996 1.8485 1 P 0 
L 3.57508996 1.8485 3.6315 1.8485 1 P 0 
L 3.6315 1.8485 3.7815 1.6985 1 P 0 
L 3.7815 1.6985 3.8185 1.6985 1 P 0 
L 3.8185 1.6985 3.8425 1.7225 1 P 0 
L 3.8425 1.7225 3.9375 1.7225 1 P 0 
L 3.9375 1.7225 3.955 1.74 1 P 0 
L 3.955 1.74 4.0738 1.74 1 P 0 
L 4.0738 1.74 4.10816004 1.70563996 1 P 0 
P 5.3 4.065 7 P 0 8 0;1=3,3=0
P 4.10816004 1.70563996 6 P 0 8 0;1=1,3=1
L 4.485 2.375 4.46 2.35 1 P 0 
L 4.46 2.35 4.46 2.225 1 P 0 
L 4.46 2.225 4.405 2.17 1 P 0 
L 4.405 2.17 4.405 2.1256 1 P 0 
L 4.405 2.1256 4.405 2.09 0 P 0 
L 4.405 2.09 4.38373996 2.06873996 0 P 0 
L 4.38373996 2.06873996 4.38373996 2.05996004 0 P 0 
P 4.38373996 2.05996004 6 P 0 8 0;1=1,3=1
P 4.485 2.375 7 P 0 8 0;1=0,3=1
L 4.9097 1.335 4.87568002 1.335 1 P 0 
L 4.87568002 1.335 4.7617 1.449 1 P 0 
L 4.7617 1.449 4.654 1.449 1 P 0 
L 4.654 1.449 4.64 1.463 1 P 0 
L 4.64 1.463 4.64 1.515 1 P 0 
L 4.64 1.515 4.62653002 1.52846998 1 P 0 
L 4.62653002 1.52846998 4.57008996 1.52846998 1 P 0 
L 4.57008996 1.52846998 4.56 1.53856004 1 P 0 
L 4.56 1.53856004 4.56 1.565 1 P 0 
L 4.56 1.565 4.54121998 1.58378002 1 P 0 
L 4.54121998 1.58378002 4.54121998 1.58753002 1 P 0 
P 4.54121998 1.58753002 6 P 0 8 0;1=1,3=1
P 4.9097 1.335 6 P 0 8 0;1=7,3=1
L 4.365 2.375 4.3015 2.3115 1 P 0 
L 4.3015 2.3115 4.3015 1.82023002 1 P 0 
L 4.3015 1.82023002 4.26563996 1.78436998 1 P 0 
P 4.26563996 1.78436998 6 P 0 8 0;1=1,3=1
P 4.365 2.375 7 P 0 8 0;1=0,3=1
P 3.465 1.74 7 P 0 8 0;1=2,3=1
L 3.465 1.74 3.455 1.73 1 P 0 
L 3.455 1.73 3.455 1.52 1 P 0 
L 3.455 1.52 3.53 1.445 1 P 0 
L 3.53 1.445 3.57 1.445 1 P 0 
L 3.57 1.445 3.62 1.395 1 P 0 
L 3.62 1.395 3.72 1.395 1 P 0 
L 3.72 1.395 3.79 1.325 1 P 0 
L 3.79 1.325 3.79 1.235 1 P 0 
L 3.79 1.235 3.635 1.08 1 P 0 
L 3.635 1.08 3.635 1.055 1 P 0 
L 3.635 1.055 3.595 1.015 1 P 0 
L 3.595 1.015 3.465 1.015 1 P 0 
L 3.465 1.015 3.45 1.03 1 P 0 
L 3.45 1.03 3.44 1.03 1 P 0 
P 3.44 1.03 7 P 0 8 0;1=0,3=1
S P 0
OB 1.565 4.19 I
OS 1.695 4.19
OS 1.715 4.17
OS 1.715 3.795
OS 1.69 3.77
OS 1.565 3.77
OS 1.54 3.795
OS 1.54 3.86196003937
OC 1.540019980315 3.863 1.511000688976 3.863037401575 N
OC 1.54 3.86403996063 1.511000688976 3.862962598425 N
OS 1.54 3.876369980315
OS 1.54155 3.876730019685
OC 1.543769980315 3.87733996063 1.534978149606 3.904994488189 N
OC 1.548980019685 3.873580019685 1.544980708661 3.873527952756 Y
OC 1.579 3.843980019685 1.579 3.874002952756 N
OC 1.579 3.904019980315 1.579 3.874 N
OC 1.56928996063 3.90241003937 1.578989173228 3.873998228346 N
OC 1.564 3.90605 1.567996259843 3.906193799213 Y
OC 1.55368996063 3.9272 1.534999311024 3.905000885827 N
OC 1.560519980315 3.9459 1.531505413386 3.9459 N
OC 1.546219980315 3.97091003937 1.531499409449 3.945900098425 N
OC 1.54495 3.97661003937 1.54825226378 3.974354330709 Y
OC 1.550019980315 3.993 1.520992716535 3.993 N
OC 1.54 4.01493996063 1.520989862205 3.993 N
OS 1.54 4.047769980315
OC 1.54 4.078230019685 1.515313582677 4.063 N
OS 1.54 4.09371003937
OC 1.547019980315 4.113 1.517006889764 4.113 N
OC 1.54043996063 4.13176003937 1.516987007874 4.113 N
OS 1.54 4.13231003937
OS 1.54 4.14023996063
OC 1.551019980315 4.163 1.522006496063 4.162999901575 N
OC 1.54933996063 4.172730019685 1.522003543307 4.163 N
OS 1.548919980315 4.173919980315
OS 1.565 4.19
OE
OB 1.700019980315 4.056 H
OC 1.700019980315 4.056 1.671 4.056 N
OE
OB 1.615019980315 4.052 H
OC 1.615019980315 4.052 1.585 4.052 N
OE
SE
P 1.6055 4.134 7 P 0 8 0;1=2,3=1
P 1.60581998 4.1 7 P 0 8 0;1=2,3=1
P 1.606 4.174 6 P 0 8 0;1=7,3=1
P 1.636 3.786 7 P 0 8 0;1=2,3=1
P 1.591 3.826 7 P 0 8 0;1=2,3=1
P 1.633 3.829 6 P 0 8 0;1=7,3=1
S P 0
OB 3.285 4.251 I
OS 3.415 4.251
OS 3.44 4.226
OS 3.44 4.18238996063
OC 3.429980019685 4.16 3.460005610236 4.16 N
OC 3.439369980315 4.13818996063 3.460003838583 4.159999901575 N
OS 3.44 4.1376
OS 3.44 4.133
OC 3.436119980315 4.12901003937 3.436001279528 4.133006988189 Y
OC 3.436119980315 4.06898996063 3.437002952756 4.099 N
OC 3.44 4.065 3.436001279528 4.064993011811 Y
OS 3.44 3.91306003937
OC 3.439980019685 3.912 3.469999311024 3.911964370079 N
OC 3.44 3.91093996063 3.469999311024 3.912035629921 N
OS 3.44 3.81
OS 3.420030019685 3.790030019685
OS 3.419230019685 3.79001003937
OC 3.40386003937 3.78531003937 3.420003051181 3.760000590551 N
OS 3.403369980315 3.785
OS 3.401630019685 3.785
OS 3.40113996063 3.78531003937
OC 3.385 3.790019980315 3.385000098425 3.760011122047 N
OC 3.368380019685 3.785 3.385 3.759997637795 N
OS 3.331619980315 3.785
OC 3.298380019685 3.785 3.315 3.759997637795 N
OS 3.28 3.785
OS 3.26 3.805
OS 3.26 3.842769980315
OS 3.26143996063 3.84318996063
OC 3.283019980315 3.872 3.252998818898 3.872 N
OC 3.27436003937 3.89308996063 3.253009350394 3.872 N
OC 3.27436003937 3.89591003937 3.275781988189 3.8945 Y
OC 3.27436003937 3.93808996063 3.253009350394 3.917 N
OC 3.27436003937 3.94091003937 3.275781988189 3.9395 Y
OC 3.283019980315 3.962 3.253009350394 3.962 N
OC 3.26143996063 3.99081003937 3.252998818898 3.962 N
OS 3.26 3.991230019685
OS 3.26 4.01393996063
OC 3.260019980315 4.015 3.230000688976 4.015035629921 N
OC 3.26 4.01606003937 3.230000688976 4.014964370079 N
OS 3.26 4.079480019685
OC 3.278019980315 4.107 3.247995866142 4.107 N
OC 3.26936003937 4.12808996063 3.248009350394 4.107 N
OC 3.26936003937 4.13091003937 3.270781988189 4.1295 Y
OC 3.278019980315 4.152 3.248009350394 4.152 N
OC 3.26 4.179519980315 3.247995866142 4.152 N
OS 3.26 4.226
OS 3.285 4.251
OE
OB 3.435019980315 3.916 H
OC 3.435019980315 3.916 3.405 3.916 N
OE
SE
L 3.43 4.02 3.52 4.02 5 P 0 
L 3.52 4.02 3.562 4.062 5 P 0 
L 3.562 4.062 3.607 4.062 5 P 0 
P 3.408 4.152 7 P 0 8 0;1=2,3=1
P 3.363 4.192 7 P 0 8 0;1=2,3=1
P 3.363 4.152 7 P 0 8 0;1=2,3=1
P 3.363 4.232 7 P 0 8 0;1=0,3=1
P 3.393 3.877 7 P 0 8 0;1=2,3=1
P 3.393 3.84 7 P 0 8 0;1=2,3=1
P 3.392 3.803 7 P 0 8 0;1=2,3=1
P 3.607 4.062 7 P 0 8 0;1=2,3=1
P 2.135 0.54 7 P 0 8 0;1=2,3=1
L 3.36 0.6106 3.3556 0.615 5 P 0 
L 3.3556 0.615 3.12 0.615 5 P 0 
L 3.12 0.615 3.075 0.57 5 P 0 
L 3.075 0.57 2.89891004 0.57 5 P 0 
L 2.89891004 0.57 2.88391004 0.585 5 P 0 
L 2.88391004 0.585 2.575 0.585 5 P 0 
L 2.575 0.585 2.525 0.535 5 P 0 
L 2.525 0.535 2.14 0.535 5 P 0 
L 2.14 0.535 2.135 0.54 5 P 0 
P 3.36 0.6106 7 P 0 8 0;1=2,3=1
L 0.68 2.355 0.69 2.365 5 P 0 
L 0.69 2.365 0.7187 2.365 5 P 0 
L 0.7187 2.365 0.8292 2.2545 5 P 0 
L 0.8292 2.2545 0.8888 2.2545 5 P 0 
L 0.8888 2.2545 0.9228 2.2885 5 P 0 
L 0.9228 2.2885 0.9228 2.3728 5 P 0 
L 0.9228 2.3728 0.96 2.41 5 P 0 
L 1.41 3.795 1.41 3.745 5 P 0 
L 1.41 3.745 1.425 3.73 5 P 0 
L 1.425 3.73 1.66 3.73 5 P 0 
L 1.66 3.73 1.675 3.715 5 P 0 
L 1.675 3.715 1.8 3.715 5 P 0 
L 1.8 3.715 1.835 3.75 5 P 0 
L 1.835 3.75 2.795 3.75 5 P 0 
L 2.795 3.75 2.915 3.63 5 P 0 
L 2.915 3.63 3.25 3.63 5 P 0 
P 0.96 2.41 7 P 0 8 0;1=2,3=1
P 0.68 2.355 7 P 0 8 0;1=2,3=1
P 1.41 3.795 7 P 0 8 0;1=2,3=1
L 3.48418002 3.613 3.645 3.77381998 5 P 0 
L 3.645 3.77381998 3.645 4.135 5 P 0 
P 3.25 3.63 7 P 0 8 0;1=2,3=1
P 3.48418002 3.613 7 P 0 8 0;1=2,3=1
P 3.645 4.135 7 P 0 8 0;1=2,3=1
P 1.8062 0.7789 6 P 0 8 0;1=7,3=1
L 3.073 0.613 2.52751004 0.613 1 P 0 
L 2.52751004 0.613 2.47451004 0.56 1 P 0 
L 2.47451004 0.56 2.14938996 0.56 1 P 0 
L 2.14938996 0.56 2.1369 0.57248996 1 P 0 
L 2.1369 0.57248996 2.10201004 0.57248996 1 P 0 
L 2.10201004 0.57248996 2.0495 0.625 1 P 0 
L 2.0495 0.625 1.92838996 0.625 1 P 0 
L 1.92838996 0.625 1.8062 0.74718996 1 P 0 
L 1.8062 0.74718996 1.8062 0.7789 1 P 0 
P 3.073 0.613 6 P 0 8 0;1=7,3=1
P 3.49 0.825 6 P 0 8 0;1=7,3=1
L 2.65966998 0.93443002 2.72716998 0.86693002 1 P 0 
L 2.72716998 0.86693002 2.90693002 0.86693002 1 P 0 
L 2.90693002 0.86693002 3.0096 0.9696 1 P 0 
L 3.0096 0.9696 3.14781998 0.9696 1 P 0 
L 3.14781998 0.9696 3.30991998 0.8075 1 P 0 
L 3.30991998 0.8075 3.4725 0.8075 1 P 0 
L 3.4725 0.8075 3.49 0.825 1 P 0 
P 2.65966998 0.93443002 9 P 0 8 0;1=14,3=0
L 5.33 0.995 5.33 1.05331998 1 P 0 
L 5.33 1.05331998 5.335 1.05831998 1 P 0 
L 5.335 1.05831998 5.3933 1.05831998 1 P 0 
L 5.3933 1.05831998 5.3983 1.06331998 1 P 0 
L 5.3983 1.06331998 5.3983 1.07831998 1 P 0 
L 5.3983 1.07831998 5.3933 1.08331998 1 P 0 
L 5.3933 1.08331998 5.335 1.08331998 1 P 0 
L 5.335 1.08331998 5.33 1.08831998 1 P 0 
L 5.33 1.08831998 5.33 1.10331998 1 P 0 
L 5.33 1.10331998 5.335 1.10831998 1 P 0 
L 5.335 1.10831998 5.3765 1.10831998 1 P 0 
L 5.3765 1.10831998 5.3815 1.11331998 1 P 0 
L 5.3815 1.11331998 5.3815 1.12831998 1 P 0 
L 5.3815 1.12831998 5.3765 1.13331998 1 P 0 
L 5.3765 1.13331998 5.335 1.13331998 1 P 0 
L 5.335 1.13331998 5.33 1.13831998 1 P 0 
L 5.33 1.13831998 5.33 1.15 1 P 0 
L 5.33 1.15 5.21 1.27 1 P 0 
L 5.21 1.27 5.21 1.63816998 1 P 0 
L 5.21 1.63816998 5.07 1.77816998 1 P 0 
L 5.07 1.77816998 5.07 1.885 1 P 0 
P 5.07 1.885 7 P 0 8 0;1=2,3=1
P 5.33 0.995 6 P 0 8 0;1=8,3=1
P 3.54 0.825 7 P 0 8 0;1=2,3=1
L 5.33 0.95 5.3085 0.9715 1 P 0 
L 5.3085 0.9715 5.3085 1.1365 1 P 0 
L 5.3085 1.1365 5.19 1.255 1 P 0 
L 5.19 1.255 5.19 1.62988002 1 P 0 
L 5.19 1.62988002 5.0475 1.77238002 1 P 0 
L 5.0475 1.77238002 5.0475 1.9025 1 P 0 
L 5.0475 1.9025 5.07 1.925 1 P 0 
P 5.07 1.925 7 P 0 8 0;1=2,3=1
P 5.33 0.95 6 P 0 8 0;1=8,3=1
L 2.53966998 0.93443002 2.54256998 0.93443002 1 P 0 
L 2.54256998 0.93443002 2.63006998 0.84693002 1 P 0 
L 2.63006998 0.84693002 2.92193002 0.84693002 1 P 0 
L 2.92193002 0.84693002 3.0223 0.9473 1 P 0 
L 3.0223 0.9473 3.14183002 0.9473 1 P 0 
L 3.14183002 0.9473 3.30163002 0.7875 1 P 0 
L 3.30163002 0.7875 3.4875 0.7875 1 P 0 
L 3.4875 0.7875 3.525 0.825 1 P 0 
L 3.525 0.825 3.54 0.825 1 P 0 
P 2.53966998 0.93443002 9 P 0 8 0;1=14,3=0
P 2.77866998 0.93443002 9 P 0 8 0;1=14,3=0
L 2.77866998 0.93443002 2.92443002 0.93443002 1 P 0 
L 2.92443002 0.93443002 2.99 1 1 P 0 
L 2.99 1 3.14571004 1 1 P 0 
L 3.14571004 1 3.31821004 0.8275 1 P 0 
L 3.31821004 0.8275 3.44433002 0.8275 1 P 0 
L 3.44433002 0.8275 3.46683002 0.85 1 P 0 
L 3.46683002 0.85 3.555 0.85 1 P 0 
L 3.555 0.85 3.615 0.79 1 P 0 
L 3.615 0.79 3.6935 0.79 1 P 0 
L 3.6935 0.79 3.78 0.7035 1 P 0 
L 3.78 0.7035 4.1269 0.7035 1 P 0 
L 4.1269 0.7035 4.1484 0.725 1 P 0 
L 4.1484 0.725 4.185 0.725 1 P 0 
L 4.185 0.725 4.212 0.752 1 P 0 
L 4.212 0.752 4.258 0.752 1 P 0 
L 4.258 0.752 4.2801 0.7299 1 P 0 
L 4.2801 0.7299 4.4599 0.7299 1 P 0 
L 4.4599 0.7299 4.51 0.78 1 P 0 
L 4.51 0.78 4.51 0.865 1 P 0 
L 4.51 0.865 4.59 0.945 1 P 0 
L 4.59 0.945 4.69 0.945 1 P 0 
L 4.69 0.945 4.7405 0.9955 1 P 0 
L 4.7405 0.9955 4.87258002 0.9955 1 P 0 
L 4.87258002 0.9955 4.97 1.09291998 1 P 0 
L 4.97 1.09291998 4.97 1.16358996 1 P 0 
L 4.97 1.16358996 4.9955 1.18908996 1 P 0 
L 4.9955 1.18908996 4.9955 1.27443002 1 P 0 
L 4.9955 1.27443002 5.0112 1.29013002 1 P 0 
L 5.0112 1.29013002 5.0112 1.42708002 1 P 0 
L 5.0112 1.42708002 5.0052 1.43308002 1 P 0 
L 5.0052 1.43308002 5.0052 1.5048 1 P 0 
L 5.0052 1.5048 4.97 1.54 1 P 0 
P 4.97 1.54 7 P 0 8 0;1=3,3=0
L 1.26066998 1.04043002 1.4374 0.8637 1 P 0 
L 1.4374 0.8637 1.81261004 0.8637 1 P 0 
L 1.81261004 0.8637 1.86 0.81631004 1 P 0 
L 1.86 0.81631004 1.86 0.77 1 P 0 
L 1.86 0.77 1.927 0.703 1 P 0 
L 1.927 0.703 2.0559 0.703 1 P 0 
L 2.0559 0.703 2.1282 0.6307 1 P 0 
L 2.1282 0.6307 2.2593 0.6307 1 P 0 
L 2.2593 0.6307 2.285 0.605 1 P 0 
L 2.285 0.605 2.45828996 0.605 1 P 0 
L 2.45828996 0.605 2.51828996 0.665 1 P 0 
L 2.51828996 0.665 2.9 0.665 1 P 0 
L 2.9 0.665 2.906 0.671 1 P 0 
L 2.906 0.671 3.22938996 0.671 1 P 0 
L 3.22938996 0.671 3.23288996 0.6675 1 P 0 
L 3.23288996 0.6675 3.64626004 0.6675 1 P 0 
L 3.64626004 0.6675 3.73026004 0.5835 1 P 0 
L 3.73026004 0.5835 4.82008002 0.5835 1 P 0 
L 4.82008002 0.5835 5.115 0.87841998 1 P 0 
L 5.115 0.87841998 5.115 0.935 1 P 0 
L 5.115 0.935 5.175 0.995 1 P 0 
L 5.175 0.995 5.175 1.2026 1 P 0 
L 5.175 1.2026 5.145 1.2326 1 P 0 
L 5.145 1.2326 5.145 1.40816998 1 P 0 
L 5.145 1.40816998 5.1225 1.43066998 1 P 0 
L 5.1225 1.43066998 5.1225 1.6408 1 P 0 
L 5.1225 1.6408 4.9825 1.7808 1 P 0 
L 4.9825 1.7808 4.9825 1.8531 1 P 0 
L 4.9825 1.8531 4.9806 1.855 1 P 0 
P 4.9806 1.855 7 P 0 8 0;1=0,3=1
P 1.26066998 1.04043002 9 P 0 8 0;1=14,3=0
L 3.275 2.32 3.275 2.36 1 P 0 
L 3.275 2.36 3.255 2.38 1 P 0 
L 3.255 2.38 3.255 2.52858996 1 P 0 
L 3.255 2.52858996 3.2645 2.53808996 1 P 0 
L 3.2645 2.53808996 3.2645 2.55591004 1 P 0 
L 3.2645 2.55591004 3.235 2.58541004 1 P 0 
L 3.235 2.58541004 3.235 2.63 1 P 0 
P 3.235 2.63 7 P 0 8 0;1=3,3=0
P 3.275 2.32 6 P 0 8 0;1=4,3=1
L 3.24 2.275 3.275 2.275 1 P 0 
L 3.275 2.275 3.31 2.31 1 P 0 
L 3.31 2.31 3.31 2.425 1 P 0 
L 3.31 2.425 3.3 2.435 1 P 0 
L 3.3 2.435 3.3 2.555 1 P 0 
L 3.3 2.555 3.31 2.565 1 P 0 
L 3.31 2.565 3.31 2.605 1 P 0 
L 3.31 2.605 3.305 2.61 1 P 0 
L 3.305 2.61 3.305 2.65 1 P 0 
P 3.24 2.275 7 P 0 8 0;1=0,3=1
P 3.305 2.65 7 P 0 8 0;1=3,3=0
L 3.375 2.65 3.36 2.635 1 P 0 
L 3.36 2.635 3.36 2.51 1 P 0 
L 3.36 2.51 3.326 2.476 1 P 0 
L 3.326 2.476 3.326 2.466 1 P 0 
P 3.375 2.65 7 P 0 8 0;1=3,3=0
P 3.326 2.466 6 P 0 8 0;1=4,3=1
L 5.08 1.105 5.04828996 1.105 1 P 0 
L 5.04828996 1.105 4.89578996 0.9525 1 P 0 
L 4.89578996 0.9525 4.7625 0.9525 1 P 0 
L 4.7625 0.9525 4.64 0.83 1 P 0 
L 4.64 0.83 4.591 0.83 1 P 0 
L 4.591 0.83 4.55 0.789 1 P 0 
L 4.55 0.789 4.55 0.76 1 P 0 
L 4.55 0.76 4.51791998 0.72791998 1 P 0 
L 4.51791998 0.72791998 4.51791998 0.72083996 1 P 0 
L 4.51791998 0.72083996 4.53833996 0.70041998 1 P 0 
L 4.53833996 0.70041998 4.53833996 0.69333996 1 P 0 
L 4.53833996 0.69333996 4.52773996 0.68273996 1 P 0 
L 4.52773996 0.68273996 4.52066004 0.68273996 1 P 0 
L 4.52066004 0.68273996 4.50023996 0.70316004 1 P 0 
L 4.50023996 0.70316004 4.49316004 0.70316004 1 P 0 
L 4.49316004 0.70316004 4.4716 0.6816 1 P 0 
L 4.4716 0.6816 4.16158002 0.6816 1 P 0 
L 4.16158002 0.6816 4.14348002 0.6635 1 P 0 
L 4.14348002 0.6635 3.76341998 0.6635 1 P 0 
L 3.76341998 0.6635 3.67941998 0.7475 1 P 0 
L 3.67941998 0.7475 3.26605 0.7475 1 P 0 
L 3.26605 0.7475 3.23955 0.774 1 P 0 
L 3.23955 0.774 3.10293002 0.774 1 P 0 
L 3.10293002 0.774 3.07 0.80693002 1 P 0 
L 3.07 0.80693002 2.39806998 0.80693002 1 P 0 
L 2.39806998 0.80693002 2.3665 0.8385 1 P 0 
L 2.3665 0.8385 2.1654 0.8385 1 P 0 
L 2.1654 0.8385 2.1481 0.8212 1 P 0 
L 2.1481 0.8212 2.1481 0.7881 1 P 0 
P 2.1481 0.7881 6 P 0 8 0;1=7,3=1
P 5.08 1.105 7 P 0 8 0;1=2,3=1
L 5.132 0.66 5.225 0.753 1 P 0 
L 5.225 0.753 5.225 1.02496998 1 P 0 
L 5.225 1.02496998 5.23 1.02996998 1 P 0 
L 5.23 1.02996998 5.24 1.02996998 1 P 0 
L 5.24 1.02996998 5.245 1.03496998 1 P 0 
L 5.245 1.03496998 5.245 1.04996998 1 P 0 
L 5.245 1.04996998 5.24 1.05496998 1 P 0 
L 5.24 1.05496998 5.23 1.05496998 1 P 0 
L 5.23 1.05496998 5.225 1.05996998 1 P 0 
L 5.225 1.05996998 5.225 1.07496998 1 P 0 
L 5.225 1.07496998 5.23 1.07996998 1 P 0 
L 5.23 1.07996998 5.24 1.07996998 1 P 0 
L 5.24 1.07996998 5.245 1.08496998 1 P 0 
L 5.245 1.08496998 5.245 1.09996998 1 P 0 
L 5.245 1.09996998 5.24 1.10496998 1 P 0 
L 5.24 1.10496998 5.23 1.10496998 1 P 0 
L 5.23 1.10496998 5.225 1.10996998 1 P 0 
L 5.225 1.10996998 5.225 1.145 1 P 0 
P 5.225 1.145 7 P 0 8 0;1=2,3=1
P 5.132 0.66 7 P 0 8 0;1=2,3=1
L 2.03 0.75 2.03 0.84921004 1 P 0 
L 2.03 0.84921004 2.04578996 0.865 1 P 0 
L 2.04578996 0.865 2.37 0.865 1 P 0 
L 2.37 0.865 2.40806998 0.82693002 1 P 0 
L 2.40806998 0.82693002 3.08506998 0.82693002 1 P 0 
L 3.08506998 0.82693002 3.118 0.794 1 P 0 
L 3.118 0.794 3.24783996 0.794 1 P 0 
L 3.24783996 0.794 3.27433996 0.7675 1 P 0 
L 3.27433996 0.7675 3.68771004 0.7675 1 P 0 
L 3.68771004 0.7675 3.77171004 0.6835 1 P 0 
L 3.77171004 0.6835 4.13518996 0.6835 1 P 0 
L 4.13518996 0.6835 4.15668996 0.705 1 P 0 
L 4.15668996 0.705 4.46328996 0.705 1 P 0 
L 4.46328996 0.705 4.53 0.77171004 1 P 0 
L 4.53 0.77171004 4.53 0.84183002 1 P 0 
L 4.53 0.84183002 4.58066998 0.8925 1 P 0 
L 4.58066998 0.8925 4.6675 0.8925 1 P 0 
L 4.6675 0.8925 4.75 0.975 1 P 0 
L 4.75 0.975 4.89 0.975 1 P 0 
L 4.89 0.975 5.07 1.155 1 P 0 
L 5.07 1.155 5.08 1.155 1 P 0 
P 2.03 0.75 6 P 0 8 0;1=7,3=1
P 5.08 1.155 7 P 0 8 0;1=2,3=1
L 2.0788 0.7874 2.0913 0.7999 1 P 0 
L 2.0913 0.7999 2.1043 0.7999 1 P 0 
L 2.1043 0.7999 2.1429 0.7613 1 P 0 
L 2.1429 0.7613 2.21811004 0.7613 1 P 0 
L 2.21811004 0.7613 2.27521004 0.8184 1 P 0 
L 2.27521004 0.8184 2.29561004 0.8184 1 P 0 
L 2.29561004 0.8184 2.32708002 0.78693002 1 P 0 
L 2.32708002 0.78693002 3.056 0.78693002 1 P 0 
L 3.056 0.78693002 3.09193002 0.751 1 P 0 
L 3.09193002 0.751 3.23426004 0.751 1 P 0 
L 3.23426004 0.751 3.25776004 0.7275 1 P 0 
L 3.25776004 0.7275 3.67113002 0.7275 1 P 0 
L 3.67113002 0.7275 3.75513002 0.6435 1 P 0 
L 3.75513002 0.6435 4.15176998 0.6435 1 P 0 
L 4.15176998 0.6435 4.16986998 0.6616 1 P 0 
L 4.16986998 0.6616 4.55561004 0.6616 1 P 0 
L 4.55561004 0.6616 4.57 0.67598996 1 P 0 
L 4.57 0.67598996 4.57 0.68896004 1 P 0 
L 4.57 0.68896004 4.575 0.69396004 1 P 0 
L 4.575 0.69396004 4.753 0.69396004 1 P 0 
L 4.753 0.69396004 4.758 0.69896004 1 P 0 
L 4.758 0.69896004 4.758 0.71396004 1 P 0 
L 4.758 0.71396004 4.753 0.71896004 1 P 0 
L 4.753 0.71896004 4.575 0.71896004 1 P 0 
L 4.575 0.71896004 4.57 0.72396004 1 P 0 
L 4.57 0.72396004 4.57 0.777 1 P 0 
L 4.57 0.777 4.603 0.81 1 P 0 
L 4.603 0.81 4.64828996 0.81 1 P 0 
L 4.64828996 0.81 4.70828996 0.87 1 P 0 
L 4.70828996 0.87 4.84158002 0.87 1 P 0 
L 4.84158002 0.87 4.86255 0.89096998 1 P 0 
L 4.86255 0.89096998 4.86963002 0.89096998 1 P 0 
L 4.86963002 0.89096998 4.89026004 0.87033996 1 P 0 
L 4.89026004 0.87033996 4.89733996 0.87033996 1 P 0 
L 4.89733996 0.87033996 4.90793996 0.88093996 1 P 0 
L 4.90793996 0.88093996 4.90793996 0.88801998 1 P 0 
L 4.90793996 0.88801998 4.88731004 0.90865 1 P 0 
L 4.88731004 0.90865 4.88731004 0.91573002 1 P 0 
L 4.88731004 0.91573002 4.89791004 0.92633002 1 P 0 
L 4.89791004 0.92633002 4.90498996 0.92633002 1 P 0 
L 4.90498996 0.92633002 4.92561998 0.9057 1 P 0 
L 4.92561998 0.9057 4.9327 0.9057 1 P 0 
L 4.9327 0.9057 4.9433 0.9163 1 P 0 
L 4.9433 0.9163 4.9433 0.92338002 1 P 0 
L 4.9433 0.92338002 4.92266998 0.94401004 1 P 0 
L 4.92266998 0.94401004 4.92266998 0.95108996 1 P 0 
L 4.92266998 0.95108996 4.93326998 0.96168996 1 P 0 
L 4.93326998 0.96168996 4.94035 0.96168996 1 P 0 
L 4.94035 0.96168996 4.96098002 0.94106004 1 P 0 
L 4.96098002 0.94106004 4.96806004 0.94106004 1 P 0 
L 4.96806004 0.94106004 4.97866004 0.95166004 1 P 0 
L 4.97866004 0.95166004 4.97866004 0.95873996 1 P 0 
L 4.97866004 0.95873996 4.95803002 0.97936998 1 P 0 
L 4.95803002 0.97936998 4.95803002 0.98645 1 P 0 
L 4.95803002 0.98645 5.02658002 1.055 1 P 0 
L 5.02658002 1.055 5.08 1.055 1 P 0 
P 5.08 1.055 7 P 0 8 0;1=2,3=1
P 2.0788 0.7874 6 P 0 8 0;1=7,3=1
L 2.633 0.522 2.608 0.522 1 P 0 
L 2.608 0.522 2.601 0.515 1 P 0 
L 2.601 0.515 2.43 0.515 1 P 0 
L 2.43 0.515 2.40418002 0.48918002 1 P 0 
L 2.40418002 0.48918002 2.29581998 0.48918002 1 P 0 
P 2.29581998 0.48918002 7 P 0 8 0;1=3,3=0
P 2.633 0.522 6 P 0 8 0;1=8,3=1
L 3.455 0.87 3.4325 0.8475 1 P 0 
L 3.4325 0.8475 3.3265 0.8475 1 P 0 
L 3.3265 0.8475 2.934 1.24 1 P 0 
L 2.934 1.24 1.275 1.24 1 P 0 
L 1.275 1.24 0.99 0.955 1 P 0 
L 0.99 0.955 0.945 0.955 1 P 0 
L 0.945 0.955 0.9225 0.9775 1 P 0 
P 3.455 0.87 7 P 0 8 0;1=2,3=1
P 0.9225 0.9775 7 P 0 8 0;1=2,3=1
L 0.965 0.98 0.97 0.985 1 P 0 
L 0.97 0.985 0.99001004 0.985 1 P 0 
L 0.99001004 0.985 1.26501004 1.26 1 P 0 
L 1.26501004 1.26 2.94243996 1.26 1 P 0 
L 2.94243996 1.26 3.33243996 0.87 1 P 0 
L 3.33243996 0.87 3.405 0.87 1 P 0 
P 3.405 0.87 7 P 0 8 0;1=2,3=1
P 0.965 0.98 7 P 0 8 0;1=2,3=1
L 5.865 1.125 5.865 1.1982 1 P 0 
L 5.865 1.1982 5.86 1.2032 1 P 0 
L 5.86 1.2032 5.835 1.2032 1 P 0 
L 5.835 1.2032 5.83 1.2082 1 P 0 
L 5.83 1.2082 5.83 1.2232 1 P 0 
L 5.83 1.2232 5.835 1.2282 1 P 0 
L 5.835 1.2282 5.86 1.2282 1 P 0 
L 5.86 1.2282 5.865 1.2332 1 P 0 
L 5.865 1.2332 5.865 1.2482 1 P 0 
L 5.865 1.2482 5.86 1.2532 1 P 0 
L 5.86 1.2532 5.835 1.2532 1 P 0 
L 5.835 1.2532 5.83 1.2582 1 P 0 
L 5.83 1.2582 5.83 1.2732 1 P 0 
L 5.83 1.2732 5.835 1.2782 1 P 0 
L 5.835 1.2782 5.86 1.2782 1 P 0 
L 5.86 1.2782 5.865 1.2832 1 P 0 
L 5.865 1.2832 5.865 1.29171004 1 P 0 
L 5.865 1.29171004 5.81 1.34671004 1 P 0 
L 5.81 1.34671004 5.575 1.34671004 1 P 0 
L 5.575 1.34671004 5.52171004 1.4 1 P 0 
L 5.52171004 1.4 5.31671004 1.4 1 P 0 
L 5.31671004 1.4 5.245 1.47171004 1 P 0 
L 5.245 1.47171004 5.245 1.63146004 1 P 0 
L 5.245 1.63146004 5.1 1.77646004 1 P 0 
L 5.1 1.77646004 5.1 1.93 1 P 0 
L 5.1 1.93 5.03 2 1 P 0 
L 5.03 2 4.895 2 1 P 0 
L 4.895 2 4.88 2.015 1 P 0 
L 4.88 2.015 4.88 2.065 1 P 0 
L 4.88 2.065 4.85 2.095 1 P 0 
L 4.85 2.095 4.805 2.095 1 P 0 
L 4.805 2.095 4.79 2.11 1 P 0 
L 4.79 2.11 4.79 2.14 1 P 0 
L 4.79 2.14 4.8025 2.1525 1 P 0 
L 4.8025 2.1525 4.8025 2.25748996 1 P 0 
L 4.8025 2.25748996 4.78498996 2.275 1 P 0 
L 4.78498996 2.275 4.7 2.275 1 P 0 
L 4.7 2.275 4.6625 2.3125 1 P 0 
L 4.6625 2.3125 4.6625 2.5525 1 P 0 
L 4.6625 2.5525 4.595 2.62 1 P 0 
L 4.025 3.08 4.005 3.1 1 P 0 
L 4.005 3.1 3.88328996 3.1 1 P 0 
L 3.88328996 3.1 3.82828996 3.155 1 P 0 
L 3.82828996 3.155 3.49 3.155 1 P 0 
L 3.49 3.155 3.47 3.175 1 P 0 
L 3.47 3.175 3.35 3.175 1 P 0 
L 3.35 3.175 3.34 3.165 1 P 0 
L 3.34 3.165 3.095 3.165 1 P 0 
L 3.095 3.165 3.05 3.21 1 P 0 
L 3.05 3.21 2.87998996 3.21 1 P 0 
L 2.87998996 3.21 2.68998996 3.4 1 P 0 
L 2.68998996 3.4 2.355 3.4 1 P 0 
L 2.355 3.4 2.32 3.435 1 P 0 
L 2.32 3.435 2.22483002 3.435 1 P 0 
L 2.22483002 3.435 2.19933002 3.4605 1 P 0 
L 2.19933002 3.4605 2.10433002 3.4605 1 P 0 
L 2.10433002 3.4605 2.05933002 3.4155 1 P 0 
L 2.05933002 3.4155 1.7605 3.4155 1 P 0 
L 1.7605 3.4155 1.69 3.345 1 P 0 
L 1.69 3.345 1.515 3.345 1 P 0 
L 1.515 3.345 1.447 3.277 1 P 0 
L 1.447 3.277 1.447 3.17998996 1 P 0 
L 1.447 3.17998996 1.36201004 3.095 1 P 0 
L 1.36201004 3.095 1.33 3.095 1 P 0 
L 1.33 3.095 1.303 3.122 1 P 0 
L 1.303 3.122 1.002 3.122 1 P 0 
L 1.002 3.122 0.959 3.079 1 P 0 
L 0.959 3.079 0.86171004 3.079 1 P 0 
L 0.86171004 3.079 0.83871004 3.056 1 P 0 
L 0.83871004 3.056 0.783 3.056 1 P 0 
L 0.783 3.056 0.769 3.07 1 P 0 
L 0.769 3.07 0.62 3.07 1 P 0 
P 4.595 2.62 7 P 0 8 0;1=2,3=1
P 4.025 3.08 7 P 0 8 0;1=2,3=1
P 0.62 3.07 7 P 0 8 0;1=2,3=1
P 5.865 1.125 7 P 0 8 0;1=0,3=1
L 5.865 1.07 5.89 1.095 1 P 0 
L 5.89 1.095 5.89 1.295 1 P 0 
L 5.89 1.295 5.815 1.37 1 P 0 
L 5.815 1.37 5.58 1.37 1 P 0 
L 5.58 1.37 5.53 1.42 1 P 0 
L 5.53 1.42 5.325 1.42 1 P 0 
L 5.325 1.42 5.265 1.48 1 P 0 
L 5.265 1.48 5.265 1.63975 1 P 0 
L 5.265 1.63975 5.12 1.78475 1 P 0 
L 5.12 1.78475 5.12 1.93828996 1 P 0 
L 5.12 1.93828996 5.03828996 2.02 1 P 0 
L 5.03828996 2.02 4.915 2.02 1 P 0 
L 4.915 2.02 4.9 2.035 1 P 0 
L 4.9 2.035 4.9 2.08498996 1 P 0 
L 4.9 2.08498996 4.8225 2.16248996 1 P 0 
L 4.8225 2.16248996 4.8225 2.26578002 1 P 0 
L 4.8225 2.26578002 4.79328002 2.295 1 P 0 
L 4.79328002 2.295 4.76 2.295 1 P 0 
L 4.76 2.295 4.685 2.37 1 P 0 
L 4.685 2.37 4.685 2.565 1 P 0 
L 4.685 2.565 4.605 2.645 1 P 0 
L 4.605 2.645 4.58 2.645 1 P 0 
L 4.58 2.645 4.57 2.635 1 P 0 
L 4.57 2.635 4.57 2.585 1 P 0 
P 5.865 1.07 7 P 0 8 0;1=0,3=1
L 4.02 3.03 4.02 3.04 1 P 0 
L 4.02 3.04 3.985 3.075 1 P 0 
L 3.985 3.075 3.88 3.075 1 P 0 
L 3.88 3.075 3.82 3.135 1 P 0 
L 3.82 3.135 3.42 3.135 1 P 0 
L 3.42 3.135 3.4125 3.1275 1 P 0 
L 3.4125 3.1275 3.37066998 3.1275 1 P 0 
L 3.37066998 3.1275 3.35316998 3.145 1 P 0 
L 3.35316998 3.145 2.8717 3.145 1 P 0 
L 2.8717 3.145 2.6417 3.375 1 P 0 
L 2.6417 3.375 2.345 3.375 1 P 0 
L 2.345 3.375 2.3095 3.4105 1 P 0 
L 2.3095 3.4105 2.10433002 3.4105 1 P 0 
L 2.10433002 3.4105 2.05933002 3.3655 1 P 0 
L 2.05933002 3.3655 2.04066998 3.3655 1 P 0 
L 2.04066998 3.3655 2.01066998 3.3955 1 P 0 
L 2.01066998 3.3955 1.76878996 3.3955 1 P 0 
L 1.76878996 3.3955 1.69828996 3.325 1 P 0 
L 1.69828996 3.325 1.546 3.325 1 P 0 
L 1.546 3.325 1.467 3.246 1 P 0 
L 1.467 3.246 1.467 3.1717 1 P 0 
L 1.467 3.1717 1.3703 3.075 1 P 0 
L 1.3703 3.075 1.32171004 3.075 1 P 0 
L 1.32171004 3.075 1.29671004 3.1 1 P 0 
L 1.29671004 3.1 1.018 3.1 1 P 0 
L 1.018 3.1 0.977 3.059 1 P 0 
L 0.977 3.059 0.87 3.059 1 P 0 
L 0.87 3.059 0.847 3.036 1 P 0 
L 0.847 3.036 0.77471004 3.036 1 P 0 
L 0.77471004 3.036 0.76671004 3.044 1 P 0 
L 0.76671004 3.044 0.7215 3.044 1 P 0 
L 0.7215 3.044 0.645 2.9675 1 P 0 
P 4.57 2.585 7 P 0 8 0;1=2,3=1
P 4.02 3.03 7 P 0 8 0;1=2,3=1
P 0.645 2.9675 7 P 0 8 0;1=2,3=1
L 5.48828996 4.16328996 5.46 4.135 1 P 0 
L 5.46 4.135 5.46 3.805 1 P 0 
L 5.46 3.805 5.225 3.57 1 P 0 
L 5.225 3.57 5.055 3.57 1 P 0 
L 5.055 3.57 5.005 3.62 1 P 0 
L 5.005 3.62 4.81633996 3.62 1 P 0 
L 4.81633996 3.62 4.77633996 3.58 1 P 0 
L 4.77633996 3.58 4.735 3.58 1 P 0 
L 4.735 3.58 4.56 3.405 1 P 0 
L 4.56 3.405 4.56 3.29878002 1 P 0 
L 4.56 3.29878002 4.5 3.23878002 1 P 0 
L 4.5 3.23878002 4.5 3.195 1 P 0 
L 4.5 3.195 4.495 3.19 1 P 0 
L 4.495 3.19 4.43121998 3.19 1 P 0 
L 4.43121998 3.19 4.405 3.16378002 1 P 0 
L 4.405 3.16378002 4.405 3.08816998 1 P 0 
L 4.405 3.08816998 4.36076004 3.04393002 1 P 0 
L 4.36076004 3.04393002 4.33211004 3.04393002 1 P 0 
L 4.33211004 3.04393002 4.2165 2.92831998 1 P 0 
L 4.2165 2.92831998 4.2165 2.92783996 1 P 0 
L 4.2165 2.92783996 4.15 2.86133996 1 P 0 
L 4.15 2.86133996 4.15 2.73783002 1 P 0 
L 4.15 2.73783002 4.0005 2.58833002 1 P 0 
L 4.0005 2.58833002 4.0005 2.575 1 P 0 
L 4.0005 2.575 3.9955 2.57 1 P 0 
L 3.9955 2.57 3.80998996 2.57 1 P 0 
L 3.80998996 2.57 3.76998996 2.53 1 P 0 
L 3.76998996 2.53 3.76783002 2.53 1 P 0 
L 3.76783002 2.53 3.76733002 2.5295 1 P 0 
L 3.76733002 2.5295 3.75451004 2.5295 1 P 0 
L 3.75451004 2.5295 3.7125 2.48748996 1 P 0 
L 3.7125 2.48748996 3.7125 2.4575 1 P 0 
L 3.7125 2.4575 3.77 2.4 1 P 0 
L 3.77 2.4 3.77 2.295 1 P 0 
L 3.77 2.295 3.72 2.245 1 P 0 
L 3.72 2.245 3.6275 2.245 1 P 0 
L 3.6275 2.245 3.6075 2.225 1 P 0 
L 3.6075 2.225 3.6075 2.1225 1 P 0 
L 3.6075 2.1225 3.638 2.092 1 P 0 
L 3.638 2.092 3.67715 2.092 1 P 0 
L 3.67715 2.092 3.84456998 1.92458002 1 P 0 
L 3.84456998 1.92458002 3.96795 1.92458002 1 P 0 
L 3.96795 1.92458002 3.99005 1.90248002 1 P 0 
P 5.48828996 4.16328996 7 P 0 8 0;1=0,3=1
P 3.99005 1.90248002 6 P 0 8 0;1=1,3=1
L 3.99005 1.86311004 3.97086004 1.8823 1 P 0 
L 3.97086004 1.8823 3.9227 1.8823 1 P 0 
L 3.9227 1.8823 3.89353002 1.91146998 1 P 0 
L 3.89353002 1.91146998 3.83646004 1.91146998 1 P 0 
L 3.83646004 1.91146998 3.67193002 2.076 1 P 0 
L 3.67193002 2.076 3.64 2.076 1 P 0 
L 3.64 2.076 3.639 2.077 1 P 0 
L 3.639 2.077 3.63178002 2.077 1 P 0 
L 3.63178002 2.077 3.5925 2.11628002 1 P 0 
L 3.5925 2.11628002 3.5925 2.23121998 1 P 0 
L 3.5925 2.23121998 3.62128002 2.26 1 P 0 
L 3.62128002 2.26 3.69683002 2.26 1 P 0 
L 3.69683002 2.26 3.75 2.31316998 1 P 0 
L 3.75 2.31316998 3.75 2.39878002 1 P 0 
L 3.75 2.39878002 3.695 2.45378002 1 P 0 
L 3.695 2.45378002 3.695 2.54 1 P 0 
L 3.695 2.54 3.74 2.585 1 P 0 
L 3.74 2.585 3.8194 2.585 1 P 0 
L 3.8194 2.585 3.8644 2.63 1 P 0 
L 3.8644 2.63 4.01 2.63 1 P 0 
L 4.01 2.63 4.135 2.755 1 P 0 
L 4.135 2.755 4.135 2.86756004 1 P 0 
L 4.135 2.86756004 4.2015 2.93406004 1 P 0 
L 4.2015 2.93406004 4.2015 2.93453996 1 P 0 
L 4.2015 2.93453996 4.29348002 3.02651998 1 P 0 
L 4.29348002 3.02651998 4.29348002 3.04848002 1 P 0 
L 4.29348002 3.04848002 4.38 3.135 1 P 0 
L 4.38 3.135 4.38 3.18 1 P 0 
L 4.38 3.18 4.48 3.28 1 P 0 
L 4.48 3.28 4.52 3.28 1 P 0 
L 4.52 3.28 4.54 3.3 1 P 0 
L 4.54 3.3 4.54 3.43593002 1 P 0 
L 4.54 3.43593002 4.565 3.46093002 1 P 0 
L 4.565 3.46093002 4.565 3.51133996 1 P 0 
L 4.565 3.51133996 4.64866004 3.595 1 P 0 
L 4.64866004 3.595 4.77011998 3.595 1 P 0 
L 4.77011998 3.595 4.81511998 3.64 1 P 0 
L 4.81511998 3.64 5.01 3.64 1 P 0 
L 5.01 3.64 5.065 3.585 1 P 0 
L 5.065 3.585 5.21 3.585 1 P 0 
L 5.21 3.585 5.3835 3.7585 1 P 0 
L 5.3835 3.7585 5.3835 3.9985 1 P 0 
L 5.3835 3.9985 5.435 4.05 1 P 0 
L 5.435 4.05 5.435 4.16 1 P 0 
L 5.435 4.16 5.465 4.19 1 P 0 
L 5.465 4.19 5.53815 4.19 1 P 0 
L 5.53815 4.19 5.55315 4.175 1 P 0 
P 5.55315 4.175 7 P 0 8 0;1=0,3=1
P 3.99005 1.86311004 6 P 0 8 0;1=1,3=1
L 3.95066998 1.82373996 3.93875 1.82373996 1 P 0 
L 3.93875 1.82373996 3.91961004 1.8046 1 P 0 
L 3.91961004 1.8046 3.87966004 1.8046 1 P 0 
L 3.87966004 1.8046 3.67048996 2.01376998 1 P 0 
L 3.67048996 2.01376998 3.58245 2.01376998 1 P 0 
L 3.58245 2.01376998 3.5 2.09621998 1 P 0 
L 3.5 2.09621998 3.5 2.19121998 1 P 0 
L 3.5 2.19121998 3.4765 2.21471998 1 P 0 
L 3.4765 2.21471998 3.4765 2.43758002 1 P 0 
L 3.4765 2.43758002 3.54041998 2.5015 1 P 0 
L 3.54041998 2.5015 3.5815 2.5015 1 P 0 
L 3.5815 2.5015 3.7106 2.6306 1 P 0 
L 3.7106 2.6306 3.7899 2.6306 1 P 0 
L 3.7899 2.6306 3.8693 2.71 1 P 0 
L 3.8693 2.71 4.01123002 2.71 1 P 0 
L 4.01123002 2.71 4.0505 2.74926998 1 P 0 
L 4.0505 2.74926998 4.0505 2.9105 1 P 0 
L 4.0505 2.9105 4.085 2.945 1 P 0 
L 4.085 2.945 4.1483 2.945 1 P 0 
L 4.1483 2.945 4.21165 3.00835 1 P 0 
L 4.21165 3.00835 4.21165 3.16165 1 P 0 
L 4.21165 3.16165 4.3 3.25 1 P 0 
L 4.3 3.25 4.3 3.35041004 1 P 0 
L 4.3 3.35041004 4.40208996 3.4525 1 P 0 
L 4.40208996 3.4525 4.49291004 3.4525 1 P 0 
L 4.49291004 3.4525 4.52 3.47958996 1 P 0 
L 4.52 3.47958996 4.52 3.53 1 P 0 
L 4.52 3.53 4.66228996 3.67228996 1 P 0 
L 4.66228996 3.67228996 4.7127 3.67228996 1 P 0 
L 4.7127 3.67228996 4.89041004 3.85 1 P 0 
L 4.89041004 3.85 5.205 3.85 1 P 0 
L 5.205 3.85 5.21 3.855 1 P 0 
L 5.21 3.855 5.21 3.93783002 1 P 0 
L 5.21 3.93783002 5.29466998 4.0225 1 P 0 
L 5.29466998 4.0225 5.31761998 4.0225 1 P 0 
L 5.31761998 4.0225 5.3435 4.04838002 1 P 0 
L 5.3435 4.04838002 5.3435 4.1735 1 P 0 
L 5.3435 4.1735 5.405 4.235 1 P 0 
L 5.405 4.235 5.61126004 4.235 1 P 0 
L 5.61126004 4.235 5.67126004 4.175 1 P 0 
P 5.67126004 4.175 7 P 0 8 0;1=0,3=1
P 3.95066998 1.82373996 6 P 0 8 0;1=1,3=1
L 5.78936998 4.175 5.72566998 4.175 1 P 0 
L 5.72566998 4.175 5.70066998 4.15 1 P 0 
L 5.70066998 4.15 5.66 4.15 1 P 0 
L 5.66 4.15 5.59 4.22 1 P 0 
L 5.59 4.22 5.425 4.22 1 P 0 
L 5.425 4.22 5.36 4.155 1 P 0 
L 5.36 4.155 5.36 4.035 1 P 0 
L 5.36 4.035 5.35 4.025 1 P 0 
L 5.35 4.025 5.35 3.76743996 1 P 0 
L 5.35 3.76743996 5.19756004 3.615 1 P 0 
L 5.19756004 3.615 5.095 3.615 1 P 0 
L 5.095 3.615 5.0325 3.6775 1 P 0 
L 5.0325 3.6775 4.73913002 3.6775 1 P 0 
L 4.73913002 3.6775 4.71891998 3.65728996 1 P 0 
L 4.71891998 3.65728996 4.66851004 3.65728996 1 P 0 
L 4.66851004 3.65728996 4.535 3.52378002 1 P 0 
L 4.535 3.52378002 4.535 3.47336998 1 P 0 
L 4.535 3.47336998 4.455 3.39336998 1 P 0 
L 4.455 3.39336998 4.455 3.315 1 P 0 
L 4.455 3.315 4.37 3.23 1 P 0 
L 4.37 3.23 4.31 3.23 1 P 0 
L 4.31 3.23 4.23226004 3.15226004 1 P 0 
L 4.23226004 3.15226004 4.23226004 3.00773996 1 P 0 
L 4.23226004 3.00773996 4.1715 2.94698002 1 P 0 
L 4.1715 2.94698002 4.1715 2.9465 1 P 0 
L 4.1715 2.9465 4.115 2.89 1 P 0 
L 4.115 2.89 4.085 2.89 1 P 0 
L 4.085 2.89 4.0655 2.8705 1 P 0 
L 4.0655 2.8705 4.0655 2.74305 1 P 0 
L 4.0655 2.74305 4.065 2.74255 1 P 0 
L 4.065 2.74255 4.065 2.74 1 P 0 
L 4.065 2.74 4.02 2.695 1 P 0 
L 4.02 2.695 3.87551998 2.695 1 P 0 
L 3.87551998 2.695 3.79611998 2.6156 1 P 0 
L 3.79611998 2.6156 3.71818002 2.6156 1 P 0 
L 3.71818002 2.6156 3.63878996 2.53621004 1 P 0 
L 3.63878996 2.53621004 3.63878996 2.48378996 1 P 0 
L 3.63878996 2.48378996 3.63 2.475 1 P 0 
L 3.63 2.475 3.63 2.3 1 P 0 
L 3.63 2.3 3.62 2.29 1 P 0 
L 3.62 2.29 3.535 2.29 1 P 0 
L 3.535 2.29 3.52 2.275 1 P 0 
L 3.52 2.275 3.52 2.11 1 P 0 
L 3.52 2.11 3.586 2.044 1 P 0 
L 3.586 2.044 3.66148002 2.044 1 P 0 
L 3.66148002 2.044 3.88173996 1.82373996 1 P 0 
L 3.88173996 1.82373996 3.9113 1.82373996 1 P 0 
P 5.78936998 4.175 7 P 0 8 0;1=0,3=1
P 3.9113 1.82373996 6 P 0 8 0;1=1,3=1
P 3.545 0.6092 7 P 0 8 0;1=2,3=1
L 1.395 0.625 1.425 0.595 1 P 0 
L 1.425 0.595 1.495 0.595 1 P 0 
L 1.495 0.595 1.5125 0.6125 1 P 0 
L 1.5125 0.6125 1.7525 0.6125 1 P 0 
L 1.7525 0.6125 1.8 0.66 1 P 0 
L 1.8 0.66 1.835 0.66 1 P 0 
L 1.835 0.66 1.92 0.575 1 P 0 
L 1.92 0.575 1.9707 0.575 1 P 0 
L 1.9707 0.575 2.1007 0.445 1 P 0 
L 2.1007 0.445 2.245 0.445 1 P 0 
L 2.245 0.445 2.26 0.43 1 P 0 
L 2.26 0.43 2.47 0.43 1 P 0 
L 2.47 0.43 2.505 0.465 1 P 0 
L 2.505 0.465 2.845 0.465 1 P 0 
L 2.845 0.465 2.89621004 0.51621004 1 P 0 
L 2.89621004 0.51621004 3.0962 0.51621004 1 P 0 
L 3.0962 0.51621004 3.14398996 0.564 1 P 0 
L 3.14398996 0.564 3.4998 0.564 1 P 0 
L 3.4998 0.564 3.545 0.6092 1 P 0 
P 1.395 0.625 6 P 0 8 0;1=7,3=1
P 3.495 0.61 7 P 0 8 0;1=2,3=1
L 1.485 0.625 1.5 0.64 1 P 0 
L 1.5 0.64 1.7499 0.64 1 P 0 
L 1.7499 0.64 1.79 0.6801 1 P 0 
L 1.79 0.6801 1.845 0.6801 1 P 0 
L 1.845 0.6801 1.9256 0.5995 1 P 0 
L 1.9256 0.5995 1.97448996 0.5995 1 P 0 
L 1.97448996 0.5995 2.10898996 0.465 1 P 0 
L 2.10898996 0.465 2.255 0.465 1 P 0 
L 2.255 0.465 2.27 0.45 1 P 0 
L 2.27 0.45 2.46 0.45 1 P 0 
L 2.46 0.45 2.495 0.485 1 P 0 
L 2.495 0.485 2.829 0.485 1 P 0 
L 2.829 0.485 2.8825 0.5385 1 P 0 
L 2.8825 0.5385 3.0815 0.5385 1 P 0 
L 3.0815 0.5385 3.13 0.587 1 P 0 
L 3.13 0.587 3.472 0.587 1 P 0 
L 3.472 0.587 3.495 0.61 1 P 0 
P 1.485 0.625 6 P 0 8 0;1=7,3=1
L 3.80999961 -1.25 3.80999961 -1.33 2 P 0 ;0,2=23,4=0.000000
L 3.80999961 -1.33 3.8500003 -1.33 2 P 0 ;0,2=23,4=0.000000
L 3.90999902 -1.25 3.90199892 -1.25266614 2 P 0 ;0,2=23,4=0.000000
L 3.90199892 -1.25266614 3.8960002 -1.25933386 2 P 0 ;0,2=23,4=0.000000
L 3.8960002 -1.25933386 3.89199921 -1.26733209 2 P 0 ;0,2=23,4=0.000000
L 3.89199921 -1.26733209 3.8889999 -1.27800138 2 P 0 ;0,2=23,4=0.000000
L 3.8889999 -1.27800138 3.8880001 -1.29000128 2 P 0 ;0,2=23,4=0.000000
L 3.8880001 -1.29000128 3.8889999 -1.30200118 2 P 0 ;0,2=23,4=0.000000
L 3.8889999 -1.30200118 3.89199921 -1.31266801 2 P 0 ;0,2=23,4=0.000000
L 3.89199921 -1.31266801 3.8960002 -1.3206687 2 P 0 ;0,2=23,4=0.000000
L 3.8960002 -1.3206687 3.90199892 -1.32733396 2 P 0 ;0,2=23,4=0.000000
L 3.90199892 -1.32733396 3.90999902 -1.33 2 P 0 ;0,2=23,4=0.000000
L 3.90999902 -1.33 3.91799911 -1.32733396 2 P 0 ;0,2=23,4=0.000000
L 3.91799911 -1.32733396 3.9239997 -1.3206687 2 P 0 ;0,2=23,4=0.000000
L 3.9239997 -1.3206687 3.92800069 -1.31266801 2 P 0 ;0,2=23,4=0.000000
L 3.92800069 -1.31266801 3.931 -1.30200118 2 P 0 ;0,2=23,4=0.000000
L 3.931 -1.30200118 3.9319998 -1.29000128 2 P 0 ;0,2=23,4=0.000000
L 3.9319998 -1.29000128 3.931 -1.27800138 2 P 0 ;0,2=23,4=0.000000
L 3.931 -1.27800138 3.92800069 -1.26733209 2 P 0 ;0,2=23,4=0.000000
L 3.92800069 -1.26733209 3.9239997 -1.25933386 2 P 0 ;0,2=23,4=0.000000
L 3.9239997 -1.25933386 3.91799911 -1.25266614 2 P 0 ;0,2=23,4=0.000000
L 3.91799911 -1.25266614 3.90999902 -1.25 2 P 0 ;0,2=23,4=0.000000
L 3.9680001 -1.31400098 3.97399882 -1.32333484 2 P 0 ;0,2=23,4=0.000000
L 3.97399882 -1.32333484 3.98199892 -1.32866703 2 P 0 ;0,2=23,4=0.000000
L 3.98199892 -1.32866703 3.99100069 -1.33 2 P 0 ;0,2=23,4=0.000000
L 3.99100069 -1.33 3.99900079 -1.32866703 2 P 0 ;0,2=23,4=0.000000
L 3.99900079 -1.32866703 4.00700089 -1.32200177 2 P 0 ;0,2=23,4=0.000000
L 4.00700089 -1.32200177 4.0119998 -1.31400098 2 P 0 ;0,2=23,4=0.000000
L 4.0119998 -1.31400098 4.01299961 -1.3060003 2 P 0 ;0,2=23,4=0.000000
L 4.01299961 -1.3060003 4.011 -1.296669 2 P 0 ;0,2=23,4=0.000000
L 4.011 -1.296669 4.0039997 -1.29000128 2 P 0 ;0,2=23,4=0.000000
L 4.0039997 -1.29000128 3.99699941 -1.28733278 2 P 0 ;0,2=23,4=0.000000
L 3.99699941 -1.28733278 3.98799951 -1.28733278 2 P 0 ;0,2=23,4=0.000000
L 3.99699941 -1.28733278 4.0029999 -1.28333356 2 P 0 ;0,2=23,4=0.000000
L 4.0029999 -1.28333356 4.00800069 -1.27666831 2 P 0 ;0,2=23,4=0.000000
L 4.00800069 -1.27666831 4.0100003 -1.26866762 2 P 0 ;0,2=23,4=0.000000
L 4.0100003 -1.26866762 4.00800069 -1.26066683 2 P 0 ;0,2=23,4=0.000000
L 4.00800069 -1.26066683 4.0029999 -1.25400167 2 P 0 ;0,2=23,4=0.000000
L 4.0029999 -1.25400167 3.994 -1.25 2 P 0 ;0,2=23,4=0.000000
L 3.994 -1.25 3.9850001 -1.25133307 2 P 0 ;0,2=23,4=0.000000
L 3.9850001 -1.25133307 3.9760002 -1.25666772 2 P 0 ;0,2=23,4=0.000000
L 4.04 -1.35666585 4.1 -1.35666585 2 P 0 ;0,2=23,4=0.000000
L 4.1289999 -1.31933563 4.137 -1.32600089 2 P 0 ;0,2=23,4=0.000000
L 4.137 -1.32600089 4.1459999 -1.33 2 P 0 ;0,2=23,4=0.000000
L 4.1459999 -1.33 4.154 -1.33 2 P 0 ;0,2=23,4=0.000000
L 4.154 -1.33 4.1620001 -1.32600089 2 P 0 ;0,2=23,4=0.000000
L 4.1620001 -1.32600089 4.16800069 -1.31933563 2 P 0 ;0,2=23,4=0.000000
L 4.16800069 -1.31933563 4.171 -1.30999941 2 P 0 ;0,2=23,4=0.000000
L 4.171 -1.30999941 4.16900049 -1.30066811 2 P 0 ;0,2=23,4=0.000000
L 4.16900049 -1.30066811 4.1639997 -1.29266732 2 P 0 ;0,2=23,4=0.000000
L 4.1639997 -1.29266732 4.1549998 -1.28733278 2 P 0 ;0,2=23,4=0.000000
L 4.1549998 -1.28733278 4.14300049 -1.28466663 2 P 0 ;0,2=23,4=0.000000
L 4.14300049 -1.28466663 4.1360002 -1.27933445 2 P 0 ;0,2=23,4=0.000000
L 4.1360002 -1.27933445 4.13299902 -1.27000069 2 P 0 ;0,2=23,4=0.000000
L 4.13299902 -1.27000069 4.13500039 -1.26066683 2 P 0 ;0,2=23,4=0.000000
L 4.13500039 -1.26066683 4.13999931 -1.25400167 2 P 0 ;0,2=23,4=0.000000
L 4.13999931 -1.25400167 4.1469997 -1.25 2 P 0 ;0,2=23,4=0.000000
L 4.1469997 -1.25 4.154 -1.25 2 P 0 ;0,2=23,4=0.000000
L 4.154 -1.25 4.16100039 -1.25266614 2 P 0 ;0,2=23,4=0.000000
L 4.16100039 -1.25266614 4.16700089 -1.25933386 2 P 0 ;0,2=23,4=0.000000
L 4.2179998 -1.25 4.24199833 -1.25 2 P 0 ;0,2=23,4=0.000000
L 4.22999902 -1.25 4.22999902 -1.33 2 P 0 ;0,2=23,4=0.000000
L 4.2179998 -1.33 4.24199833 -1.33 2 P 0 ;0,2=23,4=0.000000
L 4.31599961 -1.29000128 4.33600079 -1.29000128 2 P 0 ;0,2=23,4=0.000000
L 4.33600079 -1.29000128 4.33600079 -1.31400098 2 P 0 ;0,2=23,4=0.000000
L 4.33600079 -1.31400098 4.3300003 -1.32200177 2 P 0 ;0,2=23,4=0.000000
L 4.3300003 -1.32200177 4.3229999 -1.32733396 2 P 0 ;0,2=23,4=0.000000
L 4.3229999 -1.32733396 4.3130002 -1.33 2 P 0 ;0,2=23,4=0.000000
L 4.3130002 -1.33 4.30300049 -1.32733396 2 P 0 ;0,2=23,4=0.000000
L 4.30300049 -1.32733396 4.2960002 -1.32200177 2 P 0 ;0,2=23,4=0.000000
L 4.2960002 -1.32200177 4.28999961 -1.31400098 2 P 0 ;0,2=23,4=0.000000
L 4.28999961 -1.31400098 4.28599862 -1.30466722 2 P 0 ;0,2=23,4=0.000000
L 4.28599862 -1.30466722 4.28399911 -1.29400039 2 P 0 ;0,2=23,4=0.000000
L 4.28399911 -1.29400039 4.28399911 -1.28466663 2 P 0 ;0,2=23,4=0.000000
L 4.28399911 -1.28466663 4.28599862 -1.27666831 2 P 0 ;0,2=23,4=0.000000
L 4.28599862 -1.27666831 4.28999961 -1.26733209 2 P 0 ;0,2=23,4=0.000000
L 4.28999961 -1.26733209 4.2960002 -1.25933386 2 P 0 ;0,2=23,4=0.000000
L 4.2960002 -1.25933386 4.30199892 -1.25400167 2 P 0 ;0,2=23,4=0.000000
L 4.30199892 -1.25400167 4.30999902 -1.25 2 P 0 ;0,2=23,4=0.000000
L 4.30999902 -1.25 4.31699941 -1.25 2 P 0 ;0,2=23,4=0.000000
L 4.31699941 -1.25 4.32499951 -1.25266614 2 P 0 ;0,2=23,4=0.000000
L 4.32499951 -1.25266614 4.331 -1.25800079 2 P 0 ;0,2=23,4=0.000000
L 4.38999902 -1.33 4.38999902 -1.25 2 P 0 ;0,2=23,4=0.000000
L 4.38999902 -1.25 4.3779998 -1.26599911 2 P 0 ;0,2=23,4=0.000000
L 4.3779998 -1.33 4.40199833 -1.33 2 P 0 ;0,2=23,4=0.000000
L 3.16 -0.655 3.16 -1.58 4 P 0 ;0
L 1.36 -0.655 1.36 -1.58 4 P 0 ;0
L 1.36 -1.58 5.06 -1.58 4 P 0 ;0
L 5.06 -1.58 5.06 -0.655 4 P 0 ;0
L 5.06 -0.655 1.36 -0.655 4 P 0 ;0
A 1.559 -1.33655 1.559 -1.33655 1.55268002 -1.33655 2 P 0 N;0
A 1.54775 -1.205 1.54775 -1.205 1.53883002 -1.205 2 P 0 N;0
A 1.54763996 -0.99775 1.54763996 -0.99775 1.53871998 -0.99775 2 P 0 N;0
A 1.54063996 -1.10118002 1.54063996 -1.10118002 1.52603996 -1.10118002 2 P 0 N;0
A 1.49695 -1.10118002 1.49695 -1.10118002 1.48656998 -1.10118002 2 P 0 N;0
A 1.45963996 -1.10118002 1.45963996 -1.10118002 1.4533 -1.10118002 2 P 0 N;0
A 1.52135 -0.98681004 1.52135 -0.98681004 1.51503002 -0.98681004 2 P 0 N;0
A 1.79433002 -1.43586998 1.79433002 -1.43586998 1.78798996 -1.43586998 2 P 0 N;0
A 1.79841004 -1.40261004 1.79841004 -1.40261004 1.78798996 -1.40261004 2 P 0 N;0
A 1.80255 -1.36311004 1.80255 -1.36311004 1.78798996 -1.36311004 2 P 0 N;0
A 1.80668996 -1.31528002 1.80668996 -1.31528002 1.78798996 -1.31528002 2 P 0 N;0
A 1.68013002 -1.37456004 1.68013002 -1.37456004 1.67378996 -1.37456004 2 P 0 N;0
A 1.69321998 -1.35033002 1.69321998 -1.35033002 1.6843 -1.35033002 2 P 0 N;0
A 1.7108 -1.31738996 1.7108 -1.31738996 1.69798002 -1.31738996 2 P 0 N;0
A 1.89666998 -1.31511004 1.89666998 -1.31511004 1.88383996 -1.31511004 2 P 0 N;0
A 1.88198996 -1.16876004 1.88198996 -1.16876004 1.85558996 -1.16876004 2 P 0 N;0
A 1.87928002 -1.27801998 1.87928002 -1.27801998 1.86343996 -1.27801998 2 P 0 N;0
A 1.86176998 -1.23075 1.86176998 -1.23075 1.84206004 -1.23075 2 P 0 N;0
A 1.80978996 -1.25916998 1.80978996 -1.25916998 1.78798996 -1.25916998 2 P 0 N;0
A 1.74681004 -1.16876004 1.74681004 -1.16876004 1.72041004 -1.16876004 2 P 0 N;0
A 1.67813002 -1.15513002 1.67813002 -1.15513002 1.65841998 -1.15513002 2 P 0 N;0
A 1.73018002 -1.27816004 1.73018002 -1.27816004 1.71433996 -1.27816004 2 P 0 N;0
A 1.75373002 -1.23081004 1.75373002 -1.23081004 1.73405 -1.23081004 2 P 0 N;0
A 1.65531004 -1.25255 1.65531004 -1.25255 1.63661998 -1.25255 2 P 0 N;0
A 1.69808996 -1.21291998 1.69808996 -1.21291998 1.67628996 -1.21291998 2 P 0 N;0
A 1.81438996 -1.1968 1.81438996 -1.1968 1.78798996 -1.1968 2 P 0 N;0
A 1.6269 -1.1749 1.6269 -1.1749 1.61106004 -1.1749 2 P 0 N;0
A 1.58461004 -1.19126004 1.58461004 -1.19126004 1.57178002 -1.19126004 2 P 0 N;0
A 1.5853 -1.31428002 1.5853 -1.31428002 1.57488996 -1.31428002 2 P 0 N;0
A 1.61735 -1.28638996 1.61735 -1.28638996 1.60276998 -1.28638996 2 P 0 N;0
A 1.88198996 -1.03361004 1.88198996 -1.03361004 1.85558996 -1.03361004 2 P 0 N;0
A 1.71881004 -1.10118002 1.71881004 -1.10118002 1.69238996 -1.10118002 2 P 0 N;0
A 1.65183002 -1.10118002 1.65183002 -1.10118002 1.63003002 -1.10118002 2 P 0 N;0
A 1.67801998 -1.04738996 1.67801998 -1.04738996 1.65831004 -1.04738996 2 P 0 N;0
A 1.74681004 -1.03361004 1.74681004 -1.03361004 1.72041004 -1.03361004 2 P 0 N;0
A 1.69811998 -0.98951004 1.69811998 -0.98951004 1.67631998 -0.98951004 2 P 0 N;0
A 1.81438996 -1.00556004 1.81438996 -1.00556004 1.78798996 -1.00556004 2 P 0 N;0
A 1.59258002 -1.10118002 1.59258002 -1.10118002 1.5739 -1.10118002 2 P 0 N;0
A 1.58451004 -1.01148996 1.58451004 -1.01148996 1.57168002 -1.01148996 2 P 0 N;0
A 1.62681004 -1.02773996 1.62681004 -1.02773996 1.61096998 -1.02773996 2 P 0 N;0
A 1.92148002 -1.21285 1.92148002 -1.21285 1.89968002 -1.21285 2 P 0 N;0
A 1.92148002 -0.98951004 1.92148002 -0.98951004 1.89968002 -0.98951004 2 P 0 N;0
A 1.80978996 -0.9432 1.80978996 -0.9432 1.78798996 -0.9432 2 P 0 N;0
A 1.80668996 -0.88708002 1.80668996 -0.88708002 1.78798996 -0.88708002 2 P 0 N;0
A 1.80255 -0.83923996 1.80255 -0.83923996 1.78798996 -0.83923996 2 P 0 N;0
A 1.8919 -0.88538002 1.8919 -0.88538002 1.87906998 -0.88538002 2 P 0 N;0
A 1.87838996 -0.92456998 1.87838996 -0.92456998 1.86255 -0.92456998 2 P 0 N;0
A 1.65531004 -0.94981004 1.65531004 -0.94981004 1.63661998 -0.94981004 2 P 0 N;0
A 1.73123002 -0.92378002 1.73123002 -0.92378002 1.71538996 -0.92378002 2 P 0 N;0
A 1.71216998 -0.88443996 1.71216998 -0.88443996 1.69935 -0.88443996 2 P 0 N;0
A 1.86225 -0.97178002 1.86225 -0.97178002 1.84253996 -0.97178002 2 P 0 N;0
A 1.75451998 -0.97123996 1.75451998 -0.97123996 1.73483996 -0.97123996 2 P 0 N;0
A 1.61741998 -0.91601004 1.61741998 -0.91601004 1.60283996 -0.91601004 2 P 0 N;0
A 1.5853 -0.88808996 1.5853 -0.88808996 1.57488996 -0.88808996 2 P 0 N;0
A 1.79841004 -0.79975 1.79841004 -0.79975 1.78798996 -0.79975 2 P 0 N;0
A 1.79433002 -0.76648002 1.79433002 -0.76648002 1.78798996 -0.76648002 2 P 0 N;0
A 1.92135 -1.36781004 1.92135 -1.36781004 1.91503996 -1.36781004 2 P 0 N;0
A 1.91096004 -1.34658002 1.91096004 -1.34658002 1.90203996 -1.34658002 2 P 0 N;0
A 2.19078996 -1.1806 2.26591004 -1.16473002 2.21741014 -1.12088169 2 P 0 N;0
A 2.15903002 -1.1402 2.19078996 -1.18061004 2.22093406 -1.12423278 2 P 0 N;0
A 2.05721004 -1.16178996 2.08853002 -1.16658996 2.08281614 -1.09929134 2 P 0 N;0
A 2.00546998 -1.13951998 2.03345 -1.17196004 2.07793927 -1.10530069 2 P 0 N;0
A 2.03346004 -1.17195 2.0847 -1.18461004 2.07891181 -1.09801299 2 P 0 N;0
A 2.0847 -1.18461998 2.14261004 -1.15663002 2.07348435 -1.08751378 2 P 0 N;0
A 2.08853996 -1.16658002 2.13313002 -1.14451998 2.06368967 -1.06025512 2 P 0 N;0
A 1.95808002 -1.25255 1.95808002 -1.25255 1.93938996 -1.25255 2 P 0 N;0
A 1.98775 -1.28635 1.98775 -1.28635 1.97316998 -1.28635 2 P 0 N;0
A 2.27411998 -1.11835 2.15906004 -1.11835 2.21658996 -1.11611998 2 P 0 N;0
L 2.25188002 -1.11418002 2.1807 -1.11418002 2 P 0 ;0
L 2.1807 -1.11418002 2.1807 -1.11398996 2 P 8191 ;0
A 2.25188996 -1.11398996 2.18071004 -1.11398996 2.2163 -1.1124 2 P 0 N;0
A 2.08028996 -1.03428996 2.02048996 -1.08258996 2.0798126 -1.09486801 2 P 0 N;0
A 2.13151998 -1.05146004 2.0803 -1.0343 2.0802999 -1.11932195 2 P 0 N;0
A 2.1315 -1.05146998 2.14175 -1.03951004 2.1356003 -1.04461171 2 P 0 N;0
A 2.14175 -1.03951004 2.08283002 -1.01613002 2.07772461 -1.11492805 2 P 0 N;0
A 2.08283996 -1.01611998 2.00698002 -1.05835 2.08064724 -1.10143169 2 P 0 N;0
L 2.27413002 -1.12868996 2.18073996 -1.12868996 2 P 0 ;0
A 2.18075 -1.12868996 2.19083002 -1.15751998 2.22417795 -1.12968307 2 P 0 N;0
A 2.19083002 -1.15753002 2.25311004 -1.15211004 2.21927195 -1.12381791 2 P 0 N;0
L 2.15903996 -1.1402 2.15903996 -1.11835 2 P 8191 ;0
A 2.02048996 -1.0826 2.05721998 -1.16181004 2.09087933 -1.0980811 2 P 0 N;0
A 2.00698996 -1.05836004 2.00546998 -1.13953002 2.09672953 -1.10063967 2 P 0 N;0
A 2.14258996 -1.15661004 2.13313996 -1.14453002 2.13544892 -1.15246004 2 P 0 N;0
A 1.95808002 -0.94981004 1.95808002 -0.94981004 1.93938996 -0.94981004 2 P 0 N;0
A 1.90183996 -0.8525 1.90183996 -0.8525 1.89291004 -0.8525 2 P 0 N;0
A 1.91108002 -0.82726998 1.91108002 -0.82726998 1.90473996 -0.82726998 2 P 0 N;0
L 2.32081004 -1.02041004 2.32081004 -1.17625 2 P 0 ;0
A 2.49568002 -1.15528996 2.47898002 -1.16443002 2.4882003 -1.1614502 2 P 0 N;0
A 2.47896998 -1.16443996 2.50283002 -1.18086004 2.51649242 -1.13546152 2 P 0 N;0
A 2.50281998 -1.18086998 2.54318002 -1.1834 2.52887392 -1.08843022 2 P 0 N;0
A 2.52306998 -1.16761004 2.52848996 -1.16771998 2.52673258 -1.12070098 2 P 0 N;0
A 2.49566004 -1.15528996 2.52306998 -1.1676 2.5255122 -1.12549094 2 P 0 N;0
A 2.37851998 -1.15753002 2.4408 -1.15211004 2.40696191 -1.12381791 2 P 0 N;0
A 2.45358002 -1.16471998 2.44078996 -1.1521 2.44541191 -1.16020689 2 P 0 N;0
A 2.37848002 -1.1806 2.4536 -1.16473002 2.4051001 -1.12088169 2 P 0 N;0
A 2.34673002 -1.1402 2.37848996 -1.18061004 2.40863406 -1.12423278 2 P 0 N;0
A 2.2659 -1.16471998 2.25311004 -1.1521 2.25773199 -1.16020689 2 P 0 N;0
A 2.3006 -1.17626004 2.3208 -1.17626004 2.3107 -1.17386841 2 P 0 N;0
L 2.30058996 -1.17625 2.30058996 -1.02033996 2 P 0 ;0
A 2.50836998 -1.10106004 2.54306004 -1.11513002 2.56106673 -1.02093386 2 P 0 N;0
A 2.51081004 -1.07948002 2.50836998 -1.10103996 2.51886093 -1.09130915 2 P 0 N;0
A 2.53611004 -1.07688996 2.5108 -1.07948996 2.52742205 -1.11680827 2 P 0 N;0
A 2.56883996 -1.07368002 2.50178002 -1.06358996 2.5273123 -1.12178858 2 P 0 N;0
A 2.50178996 -1.06358996 2.48536998 -1.08248996 2.52926211 -1.10403986 2 P 0 N;0
L 2.48536998 -1.0825 2.48536998 -1.09748002 2 P 8191 ;0
A 2.48536998 -1.09748002 2.49956004 -1.12031004 2.51189104 -1.09682067 2 P 0 N;0
A 2.46181004 -1.11835 2.34675 -1.11835 2.40428002 -1.11611998 2 P 0 N;0
L 2.43956998 -1.11418002 2.36841004 -1.11418002 2 P 0 ;0
L 2.36841004 -1.11418002 2.36841004 -1.11398996 2 P 8191 ;0
A 2.43958002 -1.11398996 2.3684 -1.11398996 2.40398996 -1.1124 2 P 0 N;0
L 2.43956998 -1.11398996 2.43956998 -1.11418002 2 P 8191 ;0
A 2.49955 -1.1203 2.52723002 -1.12985 2.58163209 -0.92727982 2 P 0 N;0
A 2.55001998 -1.14328002 2.52723002 -1.12986004 2.51462185 -1.17733228 2 P 0 N;0
L 2.46181004 -1.12868996 2.36843996 -1.12868996 2 P 0 ;0
A 2.36843996 -1.12868996 2.37851998 -1.15751998 2.41186801 -1.12968307 2 P 0 N;0
L 2.34675 -1.1402 2.34675 -1.11835 2 P 8191 ;0
L 2.46181004 -1.11835 2.46181004 -1.12868996 2 P 8191 ;0
L 2.25188002 -1.11398996 2.25188002 -1.11418002 2 P 8191 ;0
A 2.3208 -1.02041004 2.3006 -1.02033996 2.31069163 -1.02276978 2 P 0 N;0
L 2.27413002 -1.11835 2.27413002 -1.12868996 2 P 8191 ;0
A 2.52848996 -1.16771004 2.54891998 -1.15895 2.52774557 -1.13777087 2 P 0 N;0
A 2.55608002 -1.08618002 2.53611998 -1.07688996 2.5249185 -1.12704419 2 P 0 N;0
L 2.71926004 -1.06796998 2.71926004 -1.17483996 2 P 0 ;0
A 2.78888996 -1.16296998 2.81508002 -1.16676998 2.8083499 -1.12100167 2 P 0 N;0
A 2.8151 -1.16675 2.83966004 -1.15211998 2.80521398 -1.12222392 2 P 0 N;0
A 2.85201004 -1.16508002 2.83966004 -1.15211004 2.84505768 -1.15933514 2 P 0 N;0
L 2.85201004 -1.16508002 2.84523996 -1.17161004 2 P 8191 ;0
A 2.81425 -1.1835 2.84525 -1.17161004 2.81425 -1.13714291 2 P 0 N;0
L 2.81425 -1.1835 2.79571004 -1.1835 2 P 8191 ;0
A 2.75886998 -1.16443002 2.79571998 -1.18351998 2.80278976 -1.12476142 2 P 0 N;0
A 2.74528996 -1.13568002 2.75888002 -1.16443002 2.80246565 -1.12624016 2 P 0 N;0
A 2.54316998 -1.1834 2.56906004 -1.1647 2.5305814 -1.13869892 2 P 0 N;0
A 2.56906004 -1.1647 2.57053996 -1.13728002 2.53763041 -1.14925374 2 P 0 N;0
A 2.65463996 -1.18351998 2.66863996 -1.17373996 2.65440246 -1.16826969 2 P 0 N;0
L 2.65463002 -1.1835 2.64165 -1.1835 2 P 8191 ;0
A 2.60955 -1.16043002 2.64163996 -1.18351004 2.63911063 -1.15317815 2 P 0 N;0
A 2.62978002 -1.15461998 2.66001998 -1.16328996 2.6502374 -1.14033868 2 P 0 N;0
A 2.66863996 -1.17375 2.66001998 -1.16328996 2.66100344 -1.17126132 2 P 0 N;0
A 2.6962 -1.17483996 2.71926004 -1.17483996 2.70773002 -1.17286427 2 P 0 N;0
L 2.69618996 -1.17483996 2.69618996 -1.06796998 2 P 0 ;0
A 2.83833002 -1.09275 2.82661998 -1.08201998 2.74555758 -1.18224094 2 P 0 N;0
A 2.82661998 -1.08198996 2.80036998 -1.07538996 2.80348839 -1.11848878 2 P 0 N;0
A 2.80036004 -1.07541998 2.76848996 -1.09933002 2.80700217 -1.1174685 2 P 0 N;0
A 2.76848996 -1.09931998 2.76446004 -1.12066004 2.82315728 -1.120694 2 P 0 N;0
A 2.74998002 -1.09273996 2.74528996 -1.11838996 2.8498563 -1.12425591 2 P 0 N;0
A 2.7954 -1.05776998 2.74998996 -1.09273996 2.80799961 -1.12109961 2 P 0 N;0
L 2.79541004 -1.05776998 2.80918996 -1.05776998 2 P 8191 ;0
A 2.85401998 -1.08106004 2.80918996 -1.05776998 2.80626024 -1.1181998 2 P 0 N;0
A 2.83833002 -1.09273996 2.85403002 -1.08106004 2.84418386 -1.08421683 2 P 0 N;0
L 2.76445 -1.12066004 2.76445 -1.12943002 2 P 8191 ;0
A 2.76446004 -1.12943002 2.76836998 -1.14305 2.80607844 -1.12485364 2 P 0 N;0
A 2.76836998 -1.14305 2.78891004 -1.16296998 2.80906152 -1.12164144 2 P 0 N;0
L 2.74528996 -1.13566004 2.74528996 -1.11838996 2 P 8191 ;0
A 2.55606004 -1.0862 2.56885 -1.07366998 2.56205354 -1.0795252 2 P 0 N;0
L 2.60953996 -1.07953996 2.59981998 -1.07953996 2 P 8191 ;0
A 2.5993 -1.05931998 2.59981004 -1.07955 2.6022813 -1.06936624 2 P 0 N;0
L 2.5993 -1.05931998 2.60953996 -1.05931998 2 P 8191 ;0
L 2.60953996 -1.05931998 2.60953996 -1.03491998 2 P 8191 ;0
A 2.62971998 -1.03418002 2.60953996 -1.03491004 2.61966791 -1.03559478 2 P 0 N;0
L 2.62971004 -1.03418996 2.62978002 -1.05931998 2 P 8191 ;0
L 2.62978002 -1.05931998 2.66008002 -1.05931998 2 P 8191 ;0
A 2.66003996 -1.07955 2.66008002 -1.05931998 2.65827421 -1.0694314 2 P 0 N;0
L 2.66003002 -1.07953996 2.62978002 -1.07953996 2 P 8191 ;0
A 2.71926004 -1.06796998 2.6962 -1.06796998 2.70773002 -1.0720561 2 P 0 N;0
A 2.71968996 -1.02341998 2.71968996 -1.02341998 2.70775 -1.02341998 2 P 0 N;0
A 2.57053996 -1.13728996 2.54306998 -1.11513002 2.53584449 -1.15219301 2 P 0 N;0
A 2.54891998 -1.15895 2.55001004 -1.14328002 2.54127923 -1.15054557 2 P 0 N;0
L 2.60953996 -1.16041004 2.60953996 -1.07953996 2 P 0 ;0
L 2.62978002 -1.07953996 2.62978002 -1.15463002 2 P 0 ;0
L 2.98495 -1.09393996 2.98495 -1.17625 2 P 0 ;0
A 2.96473996 -1.17626998 2.98493996 -1.17626998 2.97483996 -1.17442303 2 P 0 N;0
L 2.96473002 -1.17625 2.96473002 -1.17226004 2 P 8191 ;0
A 2.94165 -1.1835 2.96471004 -1.17226004 2.93076516 -1.1318935 2 P 0 N;0
L 2.94165 -1.1835 2.90701004 -1.1835 2 P 8191 ;0
A 2.90671004 -1.10841998 2.90703002 -1.18351004 2.9153065 -1.14592904 2 P 0 N;0
A 2.91853002 -1.12288996 2.91853002 -1.16618996 2.92048209 -1.14453996 2 P 0 N;0
L 2.91853002 -1.1662 2.94456004 -1.1662 2 P 8191 ;0
A 2.94456998 -1.16618996 2.94456998 -1.12288996 2.94406004 -1.14453996 2 P 0 N;0
A 2.96473002 -1.09686004 2.94741998 -1.07955 2.94874833 -1.09553169 2 P 0 N;0
L 2.9474 -1.07953996 2.90986998 -1.07953996 2 P 8191 ;0
A 2.90986998 -1.07953996 2.89821004 -1.0852 2.92433445 -1.12417766 2 P 0 N;0
A 2.89111998 -1.07086004 2.8982 -1.0852 2.8969689 -1.07688996 2 P 0 N;0
A 2.91561998 -1.05931998 2.89111998 -1.07085 2.92146033 -1.103525 2 P 0 N;0
L 2.91563002 -1.05931998 2.95031004 -1.05931998 2 P 8191 ;0
A 2.98496004 -1.09393996 2.95031004 -1.05933002 2.9453438 -1.09895197 2 P 0 N;0
A 2.92878996 -1.10535 2.9067 -1.10841998 2.93158484 -1.20646998 2 P 0 N;0
A 2.96471998 -1.10841004 2.92878002 -1.10536004 2.93215738 -1.27883829 2 P 0 N;0
L 2.96473002 -1.10841004 2.96473002 -1.09686004 2 P 8191 ;0
L 2.94456004 -1.12288002 2.91853002 -1.12288002 2 P 8191 ;0
L 3.04731004 -1.06001004 3.04191998 -1.07631998 2 P 8191 ;0
L 3.04191998 -1.07631998 3.03648002 -1.06001004 2 P 8191 ;0
L 3.03648002 -1.06001004 3.03243002 -1.06001004 2 P 8191 ;0
L 3.03243002 -1.06001004 3.02698002 -1.08543996 2 P 8191 ;0
L 3.02698002 -1.08543996 3.03226004 -1.08543996 2 P 8191 ;0
L 3.03226004 -1.08543996 3.03501004 -1.06886998 2 P 8191 ;0
L 3.03501004 -1.06886998 3.04086004 -1.08543996 2 P 8191 ;0
L 3.04086004 -1.08543996 3.04308996 -1.08543996 2 P 8191 ;0
L 3.04308996 -1.08543996 3.04888996 -1.06871004 2 P 8191 ;0
L 3.04888996 -1.06871004 3.05171004 -1.08543996 2 P 8191 ;0
L 3.05171004 -1.08543996 3.05713002 -1.08543996 2 P 8191 ;0
L 3.05713002 -1.08543996 3.05163996 -1.06001004 2 P 8191 ;0
L 3.05163996 -1.06001004 3.04731004 -1.06001004 2 P 8191 ;0
L 3.01066998 -1.06508002 3.00223002 -1.06508002 2 P 8191 ;0
L 3.00223002 -1.06508002 3.00223002 -1.06001004 2 P 8191 ;0
L 3.00223002 -1.06001004 3.02461004 -1.06001004 2 P 8191 ;0
L 3.02461004 -1.06001004 3.02461004 -1.06508002 2 P 8191 ;0
L 3.02461004 -1.06508002 3.01615 -1.06508002 2 P 8191 ;0
L 3.01615 -1.06508002 3.01615 -1.08533996 2 P 8191 ;0
L 3.01615 -1.08533996 3.01066998 -1.08533996 2 P 8191 ;0
L 3.01066998 -1.08533996 3.01066998 -1.06508002 2 P 8191 ;0
L 3.36933297 -0.955 3.36933297 -0.88 1 P 0 ;0,2=27,4=0.000000
L 3.36933297 -0.88 3.39173337 -0.88 1 P 0 ;0,2=27,4=0.000000
L 3.39173337 -0.88 3.3992001 -0.88375157 1 P 0 ;0,2=27,4=0.000000
L 3.3992001 -0.88375157 3.40480059 -0.8924997 1 P 0 ;0,2=27,4=0.000000
L 3.40480059 -0.8924997 3.40666693 -0.9024998 1 P 0 ;0,2=27,4=0.000000
L 3.40666693 -0.9024998 3.40480059 -0.9125 1 P 0 ;0,2=27,4=0.000000
L 3.40480059 -0.9125 3.40013327 -0.92000069 1 P 0 ;0,2=27,4=0.000000
L 3.40013327 -0.92000069 3.39173337 -0.92375217 1 P 0 ;0,2=27,4=0.000000
L 3.39173337 -0.92375217 3.36933297 -0.92375217 1 P 0 ;0,2=27,4=0.000000
L 3.44619931 -0.95749941 3.47980059 -0.88 1 P 0 ;0,2=27,4=0.000000
L 3.51653356 -0.955 3.51653356 -0.88 1 P 0 ;0,2=27,4=0.000000
L 3.51653356 -0.88 3.55946634 -0.955 1 P 0 ;0,2=27,4=0.000000
L 3.55946634 -0.955 3.55946634 -0.88 1 P 0 ;0,2=27,4=0.000000
L 3.68799911 -0.95749941 3.68613287 -0.9562497 1 P 0 ;0,2=27,4=0.000000
L 3.68613287 -0.9562497 3.68613287 -0.9537503 1 P 0 ;0,2=27,4=0.000000
L 3.68613287 -0.9537503 3.68799911 -0.95250059 1 P 0 ;0,2=27,4=0.000000
L 3.68799911 -0.95250059 3.68986703 -0.9537503 1 P 0 ;0,2=27,4=0.000000
L 3.68986703 -0.9537503 3.68986703 -0.9562497 1 P 0 ;0,2=27,4=0.000000
L 3.68986703 -0.9562497 3.68799911 -0.95749941 1 P 0 ;0,2=27,4=0.000000
L 3.68799911 -0.92375217 3.68613287 -0.9225001 1 P 0 ;0,2=27,4=0.000000
L 3.68613287 -0.9225001 3.68613287 -0.92000069 1 P 0 ;0,2=27,4=0.000000
L 3.68613287 -0.92000069 3.68799911 -0.91875089 1 P 0 ;0,2=27,4=0.000000
L 3.68799911 -0.91875089 3.68986703 -0.92000069 1 P 0 ;0,2=27,4=0.000000
L 3.68986703 -0.92000069 3.68986703 -0.9225001 1 P 0 ;0,2=27,4=0.000000
L 3.68986703 -0.9225001 3.68799911 -0.92375217 1 P 0 ;0,2=27,4=0.000000
L 3.81933297 -0.955 3.81933297 -0.88 1 P 0 ;0,2=27,4=0.000000
L 3.81933297 -0.88 3.84266644 -0.88 1 P 0 ;0,2=27,4=0.000000
L 3.84266644 -0.88 3.85013327 -0.88375157 1 P 0 ;0,2=27,4=0.000000
L 3.85013327 -0.88375157 3.85480059 -0.88875049 1 P 0 ;0,2=27,4=0.000000
L 3.85480059 -0.88875049 3.85666693 -0.89875059 1 P 0 ;0,2=27,4=0.000000
L 3.85666693 -0.89875059 3.85480059 -0.90875079 1 P 0 ;0,2=27,4=0.000000
L 3.85480059 -0.90875079 3.8492001 -0.91499941 1 P 0 ;0,2=27,4=0.000000
L 3.8492001 -0.91499941 3.84266644 -0.91875089 1 P 0 ;0,2=27,4=0.000000
L 3.84266644 -0.91875089 3.81933297 -0.91875089 1 P 0 ;0,2=27,4=0.000000
L 3.84266644 -0.91875089 3.85666693 -0.955 1 P 0 ;0,2=27,4=0.000000
L 3.9242001 -0.955 3.9242001 -0.88 1 P 0 ;0,2=27,4=0.000000
L 3.9242001 -0.88 3.88966565 -0.93375 1 P 0 ;0,2=27,4=0.000000
L 3.88966565 -0.93375 3.93633425 -0.93375 1 P 0 ;0,2=27,4=0.000000
L 3.98799911 -0.88 3.98053228 -0.88249951 1 P 0 ;0,2=27,4=0.000000
L 3.98053228 -0.88249951 3.97493346 -0.88875049 1 P 0 ;0,2=27,4=0.000000
L 3.97493346 -0.88875049 3.97119931 -0.89624882 1 P 0 ;0,2=27,4=0.000000
L 3.97119931 -0.89624882 3.9683999 -0.90625128 1 P 0 ;0,2=27,4=0.000000
L 3.9683999 -0.90625128 3.96746673 -0.91750118 1 P 0 ;0,2=27,4=0.000000
L 3.96746673 -0.91750118 3.9683999 -0.92875108 1 P 0 ;0,2=27,4=0.000000
L 3.9683999 -0.92875108 3.97119931 -0.93875128 1 P 0 ;0,2=27,4=0.000000
L 3.97119931 -0.93875128 3.97493346 -0.94625187 1 P 0 ;0,2=27,4=0.000000
L 3.97493346 -0.94625187 3.98053228 -0.95250059 1 P 0 ;0,2=27,4=0.000000
L 3.98053228 -0.95250059 3.98799911 -0.955 1 P 0 ;0,2=27,4=0.000000
L 3.98799911 -0.955 3.99546585 -0.95250059 1 P 0 ;0,2=27,4=0.000000
L 3.99546585 -0.95250059 4.00106644 -0.94625187 1 P 0 ;0,2=27,4=0.000000
L 4.00106644 -0.94625187 4.00480059 -0.93875128 1 P 0 ;0,2=27,4=0.000000
L 4.00480059 -0.93875128 4.0076 -0.92875108 1 P 0 ;0,2=27,4=0.000000
L 4.0076 -0.92875108 4.00853317 -0.91750118 1 P 0 ;0,2=27,4=0.000000
L 4.00853317 -0.91750118 4.0076 -0.90625128 1 P 0 ;0,2=27,4=0.000000
L 4.0076 -0.90625128 4.00480059 -0.89624882 1 P 0 ;0,2=27,4=0.000000
L 4.00480059 -0.89624882 4.00106644 -0.88875049 1 P 0 ;0,2=27,4=0.000000
L 4.00106644 -0.88875049 3.99546585 -0.88249951 1 P 0 ;0,2=27,4=0.000000
L 3.99546585 -0.88249951 3.98799911 -0.88 1 P 0 ;0,2=27,4=0.000000
L 4.06299911 -0.88 4.05553228 -0.88249951 1 P 0 ;0,2=27,4=0.000000
L 4.05553228 -0.88249951 4.04993346 -0.88875049 1 P 0 ;0,2=27,4=0.000000
L 4.04993346 -0.88875049 4.04619931 -0.89624882 1 P 0 ;0,2=27,4=0.000000
L 4.04619931 -0.89624882 4.0433999 -0.90625128 1 P 0 ;0,2=27,4=0.000000
L 4.0433999 -0.90625128 4.04246673 -0.91750118 1 P 0 ;0,2=27,4=0.000000
L 4.04246673 -0.91750118 4.0433999 -0.92875108 1 P 0 ;0,2=27,4=0.000000
L 4.0433999 -0.92875108 4.04619931 -0.93875128 1 P 0 ;0,2=27,4=0.000000
L 4.04619931 -0.93875128 4.04993346 -0.94625187 1 P 0 ;0,2=27,4=0.000000
L 4.04993346 -0.94625187 4.05553228 -0.95250059 1 P 0 ;0,2=27,4=0.000000
L 4.05553228 -0.95250059 4.06299911 -0.955 1 P 0 ;0,2=27,4=0.000000
L 4.06299911 -0.955 4.07046585 -0.95250059 1 P 0 ;0,2=27,4=0.000000
L 4.07046585 -0.95250059 4.07606644 -0.94625187 1 P 0 ;0,2=27,4=0.000000
L 4.07606644 -0.94625187 4.07980059 -0.93875128 1 P 0 ;0,2=27,4=0.000000
L 4.07980059 -0.93875128 4.0826 -0.92875108 1 P 0 ;0,2=27,4=0.000000
L 4.0826 -0.92875108 4.08353317 -0.91750118 1 P 0 ;0,2=27,4=0.000000
L 4.08353317 -0.91750118 4.0826 -0.90625128 1 P 0 ;0,2=27,4=0.000000
L 4.0826 -0.90625128 4.07980059 -0.89624882 1 P 0 ;0,2=27,4=0.000000
L 4.07980059 -0.89624882 4.07606644 -0.88875049 1 P 0 ;0,2=27,4=0.000000
L 4.07606644 -0.88875049 4.07046585 -0.88249951 1 P 0 ;0,2=27,4=0.000000
L 4.07046585 -0.88249951 4.06299911 -0.88 1 P 0 ;0,2=27,4=0.000000
L 4.12026614 -0.92375217 4.1267998 -0.91499941 1 P 0 ;0,2=27,4=0.000000
L 4.1267998 -0.91499941 4.1324003 -0.91000049 1 P 0 ;0,2=27,4=0.000000
L 4.1324003 -0.91000049 4.13986703 -0.90750108 1 P 0 ;0,2=27,4=0.000000
L 4.13986703 -0.90750108 4.14640069 -0.91000049 1 P 0 ;0,2=27,4=0.000000
L 4.14640069 -0.91000049 4.15106644 -0.91499941 1 P 0 ;0,2=27,4=0.000000
L 4.15106644 -0.91499941 4.15480059 -0.9225001 1 P 0 ;0,2=27,4=0.000000
L 4.15480059 -0.9225001 4.15573376 -0.93125059 1 P 0 ;0,2=27,4=0.000000
L 4.15573376 -0.93125059 4.15480059 -0.93875128 1 P 0 ;0,2=27,4=0.000000
L 4.15480059 -0.93875128 4.15106644 -0.94625187 1 P 0 ;0,2=27,4=0.000000
L 4.15106644 -0.94625187 4.14546585 -0.95250059 1 P 0 ;0,2=27,4=0.000000
L 4.14546585 -0.95250059 4.13893396 -0.955 1 P 0 ;0,2=27,4=0.000000
L 4.13893396 -0.955 4.13146713 -0.95250059 1 P 0 ;0,2=27,4=0.000000
L 4.13146713 -0.95250059 4.12493346 -0.94500217 1 P 0 ;0,2=27,4=0.000000
L 4.12493346 -0.94500217 4.12119931 -0.93375 1 P 0 ;0,2=27,4=0.000000
L 4.12119931 -0.93375 4.12026614 -0.92125039 1 P 0 ;0,2=27,4=0.000000
L 4.12026614 -0.92125039 4.12213238 -0.90500157 1 P 0 ;0,2=27,4=0.000000
L 4.12213238 -0.90500157 4.12493346 -0.89624882 1 P 0 ;0,2=27,4=0.000000
L 4.12493346 -0.89624882 4.12959921 -0.88750069 1 P 0 ;0,2=27,4=0.000000
L 4.12959921 -0.88750069 4.13613287 -0.8812498 1 P 0 ;0,2=27,4=0.000000
L 4.13613287 -0.8812498 4.14266644 -0.88 1 P 0 ;0,2=27,4=0.000000
L 4.14266644 -0.88 4.1492001 -0.88249951 1 P 0 ;0,2=27,4=0.000000
L 4.1492001 -0.88249951 4.15386752 -0.88875049 1 P 0 ;0,2=27,4=0.000000
L 4.20086663 -0.93000079 4.22513327 -0.93000079 1 P 0 ;0,2=27,4=0.000000
L 4.29546585 -0.91499941 4.2992001 -0.9112502 1 P 0 ;0,2=27,4=0.000000
L 4.2992001 -0.9112502 4.30199951 -0.90500157 1 P 0 ;0,2=27,4=0.000000
L 4.30199951 -0.90500157 4.30386752 -0.89624882 1 P 0 ;0,2=27,4=0.000000
L 4.30386752 -0.89624882 4.30199951 -0.88875049 1 P 0 ;0,2=27,4=0.000000
L 4.30199951 -0.88875049 4.29826703 -0.88375157 1 P 0 ;0,2=27,4=0.000000
L 4.29826703 -0.88375157 4.29173337 -0.88 1 P 0 ;0,2=27,4=0.000000
L 4.29173337 -0.88 4.26653356 -0.88 1 P 0 ;0,2=27,4=0.000000
L 4.26653356 -0.88 4.26653356 -0.955 1 P 0 ;0,2=27,4=0.000000
L 4.26653356 -0.955 4.29733386 -0.955 1 P 0 ;0,2=27,4=0.000000
L 4.29733386 -0.955 4.30386752 -0.95000108 1 P 0 ;0,2=27,4=0.000000
L 4.30386752 -0.95000108 4.3076 -0.94250039 1 P 0 ;0,2=27,4=0.000000
L 4.3076 -0.94250039 4.30946634 -0.93375 1 P 0 ;0,2=27,4=0.000000
L 4.30946634 -0.93375 4.3076 -0.92500187 1 P 0 ;0,2=27,4=0.000000
L 4.3076 -0.92500187 4.30199951 -0.91750118 1 P 0 ;0,2=27,4=0.000000
L 4.30199951 -0.91750118 4.29546585 -0.91499941 1 P 0 ;0,2=27,4=0.000000
L 4.29546585 -0.91499941 4.26653356 -0.91499941 1 P 0 ;0,2=27,4=0.000000
L 4.36299911 -0.88 4.35553228 -0.88249951 1 P 0 ;0,2=27,4=0.000000
L 4.35553228 -0.88249951 4.34993346 -0.88875049 1 P 0 ;0,2=27,4=0.000000
L 4.34993346 -0.88875049 4.34619931 -0.89624882 1 P 0 ;0,2=27,4=0.000000
L 4.34619931 -0.89624882 4.3433999 -0.90625128 1 P 0 ;0,2=27,4=0.000000
L 4.3433999 -0.90625128 4.34246673 -0.91750118 1 P 0 ;0,2=27,4=0.000000
L 4.34246673 -0.91750118 4.3433999 -0.92875108 1 P 0 ;0,2=27,4=0.000000
L 4.3433999 -0.92875108 4.34619931 -0.93875128 1 P 0 ;0,2=27,4=0.000000
L 4.34619931 -0.93875128 4.34993346 -0.94625187 1 P 0 ;0,2=27,4=0.000000
L 4.34993346 -0.94625187 4.35553228 -0.95250059 1 P 0 ;0,2=27,4=0.000000
L 4.35553228 -0.95250059 4.36299911 -0.955 1 P 0 ;0,2=27,4=0.000000
L 4.36299911 -0.955 4.37046585 -0.95250059 1 P 0 ;0,2=27,4=0.000000
L 4.37046585 -0.95250059 4.37606644 -0.94625187 1 P 0 ;0,2=27,4=0.000000
L 4.37606644 -0.94625187 4.37980059 -0.93875128 1 P 0 ;0,2=27,4=0.000000
L 4.37980059 -0.93875128 4.3826 -0.92875108 1 P 0 ;0,2=27,4=0.000000
L 4.3826 -0.92875108 4.38353317 -0.91750118 1 P 0 ;0,2=27,4=0.000000
L 4.38353317 -0.91750118 4.3826 -0.90625128 1 P 0 ;0,2=27,4=0.000000
L 4.3826 -0.90625128 4.37980059 -0.89624882 1 P 0 ;0,2=27,4=0.000000
L 4.37980059 -0.89624882 4.37606644 -0.88875049 1 P 0 ;0,2=27,4=0.000000
L 4.37606644 -0.88875049 4.37046585 -0.88249951 1 P 0 ;0,2=27,4=0.000000
L 4.37046585 -0.88249951 4.36299911 -0.88 1 P 0 ;0,2=27,4=0.000000
L 4.43799911 -0.88 4.43053228 -0.88249951 1 P 0 ;0,2=27,4=0.000000
L 4.43053228 -0.88249951 4.42493346 -0.88875049 1 P 0 ;0,2=27,4=0.000000
L 4.42493346 -0.88875049 4.42119931 -0.89624882 1 P 0 ;0,2=27,4=0.000000
L 4.42119931 -0.89624882 4.4183999 -0.90625128 1 P 0 ;0,2=27,4=0.000000
L 4.4183999 -0.90625128 4.41746673 -0.91750118 1 P 0 ;0,2=27,4=0.000000
L 4.41746673 -0.91750118 4.4183999 -0.92875108 1 P 0 ;0,2=27,4=0.000000
L 4.4183999 -0.92875108 4.42119931 -0.93875128 1 P 0 ;0,2=27,4=0.000000
L 4.42119931 -0.93875128 4.42493346 -0.94625187 1 P 0 ;0,2=27,4=0.000000
L 4.42493346 -0.94625187 4.43053228 -0.95250059 1 P 0 ;0,2=27,4=0.000000
L 4.43053228 -0.95250059 4.43799911 -0.955 1 P 0 ;0,2=27,4=0.000000
L 4.43799911 -0.955 4.44546585 -0.95250059 1 P 0 ;0,2=27,4=0.000000
L 4.44546585 -0.95250059 4.45106644 -0.94625187 1 P 0 ;0,2=27,4=0.000000
L 4.45106644 -0.94625187 4.45480059 -0.93875128 1 P 0 ;0,2=27,4=0.000000
L 4.45480059 -0.93875128 4.4576 -0.92875108 1 P 0 ;0,2=27,4=0.000000
L 4.4576 -0.92875108 4.45853317 -0.91750118 1 P 0 ;0,2=27,4=0.000000
L 4.45853317 -0.91750118 4.4576 -0.90625128 1 P 0 ;0,2=27,4=0.000000
L 4.4576 -0.90625128 4.45480059 -0.89624882 1 P 0 ;0,2=27,4=0.000000
L 4.45480059 -0.89624882 4.45106644 -0.88875049 1 P 0 ;0,2=27,4=0.000000
L 4.45106644 -0.88875049 4.44546585 -0.88249951 1 P 0 ;0,2=27,4=0.000000
L 4.44546585 -0.88249951 4.43799911 -0.88 1 P 0 ;0,2=27,4=0.000000
L 4.51299911 -0.88 4.50553228 -0.88249951 1 P 0 ;0,2=27,4=0.000000
L 4.50553228 -0.88249951 4.49993346 -0.88875049 1 P 0 ;0,2=27,4=0.000000
L 4.49993346 -0.88875049 4.49619931 -0.89624882 1 P 0 ;0,2=27,4=0.000000
L 4.49619931 -0.89624882 4.4933999 -0.90625128 1 P 0 ;0,2=27,4=0.000000
L 4.4933999 -0.90625128 4.49246673 -0.91750118 1 P 0 ;0,2=27,4=0.000000
L 4.49246673 -0.91750118 4.4933999 -0.92875108 1 P 0 ;0,2=27,4=0.000000
L 4.4933999 -0.92875108 4.49619931 -0.93875128 1 P 0 ;0,2=27,4=0.000000
L 4.49619931 -0.93875128 4.49993346 -0.94625187 1 P 0 ;0,2=27,4=0.000000
L 4.49993346 -0.94625187 4.50553228 -0.95250059 1 P 0 ;0,2=27,4=0.000000
L 4.50553228 -0.95250059 4.51299911 -0.955 1 P 0 ;0,2=27,4=0.000000
L 4.51299911 -0.955 4.52046585 -0.95250059 1 P 0 ;0,2=27,4=0.000000
L 4.52046585 -0.95250059 4.52606644 -0.94625187 1 P 0 ;0,2=27,4=0.000000
L 4.52606644 -0.94625187 4.52980059 -0.93875128 1 P 0 ;0,2=27,4=0.000000
L 4.52980059 -0.93875128 4.5326 -0.92875108 1 P 0 ;0,2=27,4=0.000000
L 4.5326 -0.92875108 4.53353317 -0.91750118 1 P 0 ;0,2=27,4=0.000000
L 4.53353317 -0.91750118 4.5326 -0.90625128 1 P 0 ;0,2=27,4=0.000000
L 4.5326 -0.90625128 4.52980059 -0.89624882 1 P 0 ;0,2=27,4=0.000000
L 4.52980059 -0.89624882 4.52606644 -0.88875049 1 P 0 ;0,2=27,4=0.000000
L 4.52606644 -0.88875049 4.52046585 -0.88249951 1 P 0 ;0,2=27,4=0.000000
L 4.52046585 -0.88249951 4.51299911 -0.88 1 P 0 ;0,2=27,4=0.000000
L 4.58799911 -0.955 4.58799911 -0.88 1 P 0 ;0,2=27,4=0.000000
L 4.58799911 -0.88 4.5767998 -0.89499911 1 P 0 ;0,2=27,4=0.000000
L 4.5767998 -0.955 4.59919843 -0.955 1 P 0 ;0,2=27,4=0.000000
L 4.65086663 -0.93000079 4.67513327 -0.93000079 1 P 0 ;0,2=27,4=0.000000
L 4.73799911 -0.88 4.73053228 -0.88249951 1 P 0 ;0,2=27,4=0.000000
L 4.73053228 -0.88249951 4.72493346 -0.88875049 1 P 0 ;0,2=27,4=0.000000
L 4.72493346 -0.88875049 4.72119931 -0.89624882 1 P 0 ;0,2=27,4=0.000000
L 4.72119931 -0.89624882 4.7183999 -0.90625128 1 P 0 ;0,2=27,4=0.000000
L 4.7183999 -0.90625128 4.71746673 -0.91750118 1 P 0 ;0,2=27,4=0.000000
L 4.71746673 -0.91750118 4.7183999 -0.92875108 1 P 0 ;0,2=27,4=0.000000
L 4.7183999 -0.92875108 4.72119931 -0.93875128 1 P 0 ;0,2=27,4=0.000000
L 4.72119931 -0.93875128 4.72493346 -0.94625187 1 P 0 ;0,2=27,4=0.000000
L 4.72493346 -0.94625187 4.73053228 -0.95250059 1 P 0 ;0,2=27,4=0.000000
L 4.73053228 -0.95250059 4.73799911 -0.955 1 P 0 ;0,2=27,4=0.000000
L 4.73799911 -0.955 4.74546585 -0.95250059 1 P 0 ;0,2=27,4=0.000000
L 4.74546585 -0.95250059 4.75106644 -0.94625187 1 P 0 ;0,2=27,4=0.000000
L 4.75106644 -0.94625187 4.75480059 -0.93875128 1 P 0 ;0,2=27,4=0.000000
L 4.75480059 -0.93875128 4.7576 -0.92875108 1 P 0 ;0,2=27,4=0.000000
L 4.7576 -0.92875108 4.75853317 -0.91750118 1 P 0 ;0,2=27,4=0.000000
L 4.75853317 -0.91750118 4.7576 -0.90625128 1 P 0 ;0,2=27,4=0.000000
L 4.7576 -0.90625128 4.75480059 -0.89624882 1 P 0 ;0,2=27,4=0.000000
L 4.75480059 -0.89624882 4.75106644 -0.88875049 1 P 0 ;0,2=27,4=0.000000
L 4.75106644 -0.88875049 4.74546585 -0.88249951 1 P 0 ;0,2=27,4=0.000000
L 4.74546585 -0.88249951 4.73799911 -0.88 1 P 0 ;0,2=27,4=0.000000
L 4.79526614 -0.8924997 4.80086663 -0.88500128 1 P 0 ;0,2=27,4=0.000000
L 4.80086663 -0.88500128 4.8074003 -0.8812498 1 P 0 ;0,2=27,4=0.000000
L 4.8074003 -0.8812498 4.81486703 -0.88 1 P 0 ;0,2=27,4=0.000000
L 4.81486703 -0.88 4.8242001 -0.88249951 1 P 0 ;0,2=27,4=0.000000
L 4.8242001 -0.88249951 4.83073376 -0.88875049 1 P 0 ;0,2=27,4=0.000000
L 4.83073376 -0.88875049 4.8326 -0.89624882 1 P 0 ;0,2=27,4=0.000000
L 4.8326 -0.89624882 4.83166693 -0.90375187 1 P 0 ;0,2=27,4=0.000000
L 4.83166693 -0.90375187 4.82793268 -0.91000049 1 P 0 ;0,2=27,4=0.000000
L 4.82793268 -0.91000049 4.80926654 -0.9225001 1 P 0 ;0,2=27,4=0.000000
L 4.80926654 -0.9225001 4.80086663 -0.93125059 1 P 0 ;0,2=27,4=0.000000
L 4.80086663 -0.93125059 4.79526614 -0.94375246 1 P 0 ;0,2=27,4=0.000000
L 4.79526614 -0.94375246 4.7933999 -0.955 1 P 0 ;0,2=27,4=0.000000
L 4.7933999 -0.955 4.8326 -0.955 1 P 0 ;0,2=27,4=0.000000
L 3.36746673 -1.205 3.36746673 -1.13 1 P 0 ;0,2=28,4=0.000000
L 3.36746673 -1.13 3.38613287 -1.13 1 P 0 ;0,2=28,4=0.000000
L 3.38613287 -1.13 3.39359961 -1.13375157 1 P 0 ;0,2=28,4=0.000000
L 3.39359961 -1.13375157 3.3992001 -1.13875049 1 P 0 ;0,2=28,4=0.000000
L 3.3992001 -1.13875049 3.40386752 -1.14624882 1 P 0 ;0,2=28,4=0.000000
L 3.40386752 -1.14624882 3.4076 -1.15500157 1 P 0 ;0,2=28,4=0.000000
L 3.4076 -1.15500157 3.40853317 -1.16750118 1 P 0 ;0,2=28,4=0.000000
L 3.40853317 -1.16750118 3.4076 -1.18000079 1 P 0 ;0,2=28,4=0.000000
L 3.4076 -1.18000079 3.40386752 -1.18875128 1 P 0 ;0,2=28,4=0.000000
L 3.40386752 -1.18875128 3.3992001 -1.19625187 1 P 0 ;0,2=28,4=0.000000
L 3.3992001 -1.19625187 3.39359961 -1.20125089 1 P 0 ;0,2=28,4=0.000000
L 3.39359961 -1.20125089 3.38613287 -1.205 1 P 0 ;0,2=28,4=0.000000
L 3.38613287 -1.205 3.36746673 -1.205 1 P 0 ;0,2=28,4=0.000000
L 3.47980059 -1.205 3.47980059 -1.15500157 1 P 0 ;0,2=28,4=0.000000
L 3.47980059 -1.1637497 3.47606644 -1.15875079 1 P 0 ;0,2=28,4=0.000000
L 3.47606644 -1.15875079 3.47046585 -1.15625128 1 P 0 ;0,2=28,4=0.000000
L 3.47046585 -1.15625128 3.46393396 -1.15500157 1 P 0 ;0,2=28,4=0.000000
L 3.46393396 -1.15500157 3.4574003 -1.15750108 1 P 0 ;0,2=28,4=0.000000
L 3.4574003 -1.15750108 3.4517998 -1.1625 1 P 0 ;0,2=28,4=0.000000
L 3.4517998 -1.1625 3.44806555 -1.17000069 1 P 0 ;0,2=28,4=0.000000
L 3.44806555 -1.17000069 3.44619931 -1.18000079 1 P 0 ;0,2=28,4=0.000000
L 3.44619931 -1.18000079 3.44806555 -1.19000098 1 P 0 ;0,2=28,4=0.000000
L 3.44806555 -1.19000098 3.4517998 -1.19750167 1 P 0 ;0,2=28,4=0.000000
L 3.4517998 -1.19750167 3.4574003 -1.20250059 1 P 0 ;0,2=28,4=0.000000
L 3.4574003 -1.20250059 3.46393396 -1.205 1 P 0 ;0,2=28,4=0.000000
L 3.46393396 -1.205 3.47046585 -1.2037503 1 P 0 ;0,2=28,4=0.000000
L 3.47046585 -1.2037503 3.47606644 -1.20000108 1 P 0 ;0,2=28,4=0.000000
L 3.47606644 -1.20000108 3.47980059 -1.19500217 1 P 0 ;0,2=28,4=0.000000
L 3.53799911 -1.13 3.53799911 -1.205 1 P 0 ;0,2=28,4=0.000000
L 3.52493346 -1.15500157 3.55106644 -1.15500157 1 P 0 ;0,2=28,4=0.000000
L 3.59900039 -1.17125039 3.62886752 -1.17125039 1 P 0 ;0,2=28,4=0.000000
L 3.62886752 -1.17125039 3.62606644 -1.1625 1 P 0 ;0,2=28,4=0.000000
L 3.62606644 -1.1625 3.62140069 -1.15750108 1 P 0 ;0,2=28,4=0.000000
L 3.62140069 -1.15750108 3.61486703 -1.15500157 1 P 0 ;0,2=28,4=0.000000
L 3.61486703 -1.15500157 3.60833346 -1.15625128 1 P 0 ;0,2=28,4=0.000000
L 3.60833346 -1.15625128 3.60273287 -1.16000049 1 P 0 ;0,2=28,4=0.000000
L 3.60273287 -1.16000049 3.59900039 -1.16875089 1 P 0 ;0,2=28,4=0.000000
L 3.59900039 -1.16875089 3.59713238 -1.17625157 1 P 0 ;0,2=28,4=0.000000
L 3.59713238 -1.17625157 3.59713238 -1.18375 1 P 0 ;0,2=28,4=0.000000
L 3.59713238 -1.18375 3.59900039 -1.19125069 1 P 0 ;0,2=28,4=0.000000
L 3.59900039 -1.19125069 3.60366604 -1.19875138 1 P 0 ;0,2=28,4=0.000000
L 3.60366604 -1.19875138 3.60926654 -1.2037503 1 P 0 ;0,2=28,4=0.000000
L 3.60926654 -1.2037503 3.6158002 -1.205 1 P 0 ;0,2=28,4=0.000000
L 3.6158002 -1.205 3.62233386 -1.20250059 1 P 0 ;0,2=28,4=0.000000
L 3.62233386 -1.20250059 3.62886752 -1.19500217 1 P 0 ;0,2=28,4=0.000000
L 3.68799911 -1.20749941 3.68613287 -1.2062497 1 P 0 ;0,2=28,4=0.000000
L 3.68613287 -1.2062497 3.68613287 -1.2037503 1 P 0 ;0,2=28,4=0.000000
L 3.68613287 -1.2037503 3.68799911 -1.20250059 1 P 0 ;0,2=28,4=0.000000
L 3.68799911 -1.20250059 3.68986703 -1.2037503 1 P 0 ;0,2=28,4=0.000000
L 3.68986703 -1.2037503 3.68986703 -1.2062497 1 P 0 ;0,2=28,4=0.000000
L 3.68986703 -1.2062497 3.68799911 -1.20749941 1 P 0 ;0,2=28,4=0.000000
L 3.68799911 -1.17375217 3.68613287 -1.1725001 1 P 0 ;0,2=28,4=0.000000
L 3.68613287 -1.1725001 3.68613287 -1.17000069 1 P 0 ;0,2=28,4=0.000000
L 3.68613287 -1.17000069 3.68799911 -1.16875089 1 P 0 ;0,2=28,4=0.000000
L 3.68799911 -1.16875089 3.68986703 -1.17000069 1 P 0 ;0,2=28,4=0.000000
L 3.68986703 -1.17000069 3.68986703 -1.1725001 1 P 0 ;0,2=28,4=0.000000
L 3.68986703 -1.1725001 3.68799911 -1.17375217 1 P 0 ;0,2=28,4=0.000000
L 3.82026614 -1.1424997 3.82586663 -1.13500128 1 P 0 ;0,2=28,4=0.000000
L 3.82586663 -1.13500128 3.8324003 -1.1312498 1 P 0 ;0,2=28,4=0.000000
L 3.8324003 -1.1312498 3.83986703 -1.13 1 P 0 ;0,2=28,4=0.000000
L 3.83986703 -1.13 3.8492001 -1.13249951 1 P 0 ;0,2=28,4=0.000000
L 3.8492001 -1.13249951 3.85573376 -1.13875049 1 P 0 ;0,2=28,4=0.000000
L 3.85573376 -1.13875049 3.8576 -1.14624882 1 P 0 ;0,2=28,4=0.000000
L 3.8576 -1.14624882 3.85666693 -1.15375187 1 P 0 ;0,2=28,4=0.000000
L 3.85666693 -1.15375187 3.85293268 -1.16000049 1 P 0 ;0,2=28,4=0.000000
L 3.85293268 -1.16000049 3.83426654 -1.1725001 1 P 0 ;0,2=28,4=0.000000
L 3.83426654 -1.1725001 3.82586663 -1.18125059 1 P 0 ;0,2=28,4=0.000000
L 3.82586663 -1.18125059 3.82026614 -1.19375246 1 P 0 ;0,2=28,4=0.000000
L 3.82026614 -1.19375246 3.8183999 -1.205 1 P 0 ;0,2=28,4=0.000000
L 3.8183999 -1.205 3.8576 -1.205 1 P 0 ;0,2=28,4=0.000000
L 3.91299911 -1.13 3.90553228 -1.13249951 1 P 0 ;0,2=28,4=0.000000
L 3.90553228 -1.13249951 3.89993346 -1.13875049 1 P 0 ;0,2=28,4=0.000000
L 3.89993346 -1.13875049 3.89619931 -1.14624882 1 P 0 ;0,2=28,4=0.000000
L 3.89619931 -1.14624882 3.8933999 -1.15625128 1 P 0 ;0,2=28,4=0.000000
L 3.8933999 -1.15625128 3.89246673 -1.16750118 1 P 0 ;0,2=28,4=0.000000
L 3.89246673 -1.16750118 3.8933999 -1.17875108 1 P 0 ;0,2=28,4=0.000000
L 3.8933999 -1.17875108 3.89619931 -1.18875128 1 P 0 ;0,2=28,4=0.000000
L 3.89619931 -1.18875128 3.89993346 -1.19625187 1 P 0 ;0,2=28,4=0.000000
L 3.89993346 -1.19625187 3.90553228 -1.20250059 1 P 0 ;0,2=28,4=0.000000
L 3.90553228 -1.20250059 3.91299911 -1.205 1 P 0 ;0,2=28,4=0.000000
L 3.91299911 -1.205 3.92046585 -1.20250059 1 P 0 ;0,2=28,4=0.000000
L 3.92046585 -1.20250059 3.92606644 -1.19625187 1 P 0 ;0,2=28,4=0.000000
L 3.92606644 -1.19625187 3.92980059 -1.18875128 1 P 0 ;0,2=28,4=0.000000
L 3.92980059 -1.18875128 3.9326 -1.17875108 1 P 0 ;0,2=28,4=0.000000
L 3.9326 -1.17875108 3.93353317 -1.16750118 1 P 0 ;0,2=28,4=0.000000
L 3.93353317 -1.16750118 3.9326 -1.15625128 1 P 0 ;0,2=28,4=0.000000
L 3.9326 -1.15625128 3.92980059 -1.14624882 1 P 0 ;0,2=28,4=0.000000
L 3.92980059 -1.14624882 3.92606644 -1.13875049 1 P 0 ;0,2=28,4=0.000000
L 3.92606644 -1.13875049 3.92046585 -1.13249951 1 P 0 ;0,2=28,4=0.000000
L 3.92046585 -1.13249951 3.91299911 -1.13 1 P 0 ;0,2=28,4=0.000000
L 3.97026614 -1.1424997 3.97586663 -1.13500128 1 P 0 ;0,2=28,4=0.000000
L 3.97586663 -1.13500128 3.9824003 -1.1312498 1 P 0 ;0,2=28,4=0.000000
L 3.9824003 -1.1312498 3.98986703 -1.13 1 P 0 ;0,2=28,4=0.000000
L 3.98986703 -1.13 3.9992001 -1.13249951 1 P 0 ;0,2=28,4=0.000000
L 3.9992001 -1.13249951 4.00573376 -1.13875049 1 P 0 ;0,2=28,4=0.000000
L 4.00573376 -1.13875049 4.0076 -1.14624882 1 P 0 ;0,2=28,4=0.000000
L 4.0076 -1.14624882 4.00666693 -1.15375187 1 P 0 ;0,2=28,4=0.000000
L 4.00666693 -1.15375187 4.00293268 -1.16000049 1 P 0 ;0,2=28,4=0.000000
L 4.00293268 -1.16000049 3.98426654 -1.1725001 1 P 0 ;0,2=28,4=0.000000
L 3.98426654 -1.1725001 3.97586663 -1.18125059 1 P 0 ;0,2=28,4=0.000000
L 3.97586663 -1.18125059 3.97026614 -1.19375246 1 P 0 ;0,2=28,4=0.000000
L 3.97026614 -1.19375246 3.9683999 -1.205 1 P 0 ;0,2=28,4=0.000000
L 3.9683999 -1.205 4.0076 -1.205 1 P 0 ;0,2=28,4=0.000000
L 4.04526614 -1.1424997 4.05086663 -1.13500128 1 P 0 ;0,2=28,4=0.000000
L 4.05086663 -1.13500128 4.0574003 -1.1312498 1 P 0 ;0,2=28,4=0.000000
L 4.0574003 -1.1312498 4.06486703 -1.13 1 P 0 ;0,2=28,4=0.000000
L 4.06486703 -1.13 4.0742001 -1.13249951 1 P 0 ;0,2=28,4=0.000000
L 4.0742001 -1.13249951 4.08073376 -1.13875049 1 P 0 ;0,2=28,4=0.000000
L 4.08073376 -1.13875049 4.0826 -1.14624882 1 P 0 ;0,2=28,4=0.000000
L 4.0826 -1.14624882 4.08166693 -1.15375187 1 P 0 ;0,2=28,4=0.000000
L 4.08166693 -1.15375187 4.07793268 -1.16000049 1 P 0 ;0,2=28,4=0.000000
L 4.07793268 -1.16000049 4.05926654 -1.1725001 1 P 0 ;0,2=28,4=0.000000
L 4.05926654 -1.1725001 4.05086663 -1.18125059 1 P 0 ;0,2=28,4=0.000000
L 4.05086663 -1.18125059 4.04526614 -1.19375246 1 P 0 ;0,2=28,4=0.000000
L 4.04526614 -1.19375246 4.0433999 -1.205 1 P 0 ;0,2=28,4=0.000000
L 4.0433999 -1.205 4.0826 -1.205 1 P 0 ;0,2=28,4=0.000000
L 4.12586663 -1.18000079 4.15013327 -1.18000079 1 P 0 ;0,2=28,4=0.000000
L 4.21299911 -1.13 4.20553228 -1.13249951 1 P 0 ;0,2=28,4=0.000000
L 4.20553228 -1.13249951 4.19993346 -1.13875049 1 P 0 ;0,2=28,4=0.000000
L 4.19993346 -1.13875049 4.19619931 -1.14624882 1 P 0 ;0,2=28,4=0.000000
L 4.19619931 -1.14624882 4.1933999 -1.15625128 1 P 0 ;0,2=28,4=0.000000
L 4.1933999 -1.15625128 4.19246673 -1.16750118 1 P 0 ;0,2=28,4=0.000000
L 4.19246673 -1.16750118 4.1933999 -1.17875108 1 P 0 ;0,2=28,4=0.000000
L 4.1933999 -1.17875108 4.19619931 -1.18875128 1 P 0 ;0,2=28,4=0.000000
L 4.19619931 -1.18875128 4.19993346 -1.19625187 1 P 0 ;0,2=28,4=0.000000
L 4.19993346 -1.19625187 4.20553228 -1.20250059 1 P 0 ;0,2=28,4=0.000000
L 4.20553228 -1.20250059 4.21299911 -1.205 1 P 0 ;0,2=28,4=0.000000
L 4.21299911 -1.205 4.22046585 -1.20250059 1 P 0 ;0,2=28,4=0.000000
L 4.22046585 -1.20250059 4.22606644 -1.19625187 1 P 0 ;0,2=28,4=0.000000
L 4.22606644 -1.19625187 4.22980059 -1.18875128 1 P 0 ;0,2=28,4=0.000000
L 4.22980059 -1.18875128 4.2326 -1.17875108 1 P 0 ;0,2=28,4=0.000000
L 4.2326 -1.17875108 4.23353317 -1.16750118 1 P 0 ;0,2=28,4=0.000000
L 4.23353317 -1.16750118 4.2326 -1.15625128 1 P 0 ;0,2=28,4=0.000000
L 4.2326 -1.15625128 4.22980059 -1.14624882 1 P 0 ;0,2=28,4=0.000000
L 4.22980059 -1.14624882 4.22606644 -1.13875049 1 P 0 ;0,2=28,4=0.000000
L 4.22606644 -1.13875049 4.22046585 -1.13249951 1 P 0 ;0,2=28,4=0.000000
L 4.22046585 -1.13249951 4.21299911 -1.13 1 P 0 ;0,2=28,4=0.000000
L 4.27026614 -1.1424997 4.27586663 -1.13500128 1 P 0 ;0,2=28,4=0.000000
L 4.27586663 -1.13500128 4.2824003 -1.1312498 1 P 0 ;0,2=28,4=0.000000
L 4.2824003 -1.1312498 4.28986703 -1.13 1 P 0 ;0,2=28,4=0.000000
L 4.28986703 -1.13 4.2992001 -1.13249951 1 P 0 ;0,2=28,4=0.000000
L 4.2992001 -1.13249951 4.30573376 -1.13875049 1 P 0 ;0,2=28,4=0.000000
L 4.30573376 -1.13875049 4.3076 -1.14624882 1 P 0 ;0,2=28,4=0.000000
L 4.3076 -1.14624882 4.30666693 -1.15375187 1 P 0 ;0,2=28,4=0.000000
L 4.30666693 -1.15375187 4.30293268 -1.16000049 1 P 0 ;0,2=28,4=0.000000
L 4.30293268 -1.16000049 4.28426654 -1.1725001 1 P 0 ;0,2=28,4=0.000000
L 4.28426654 -1.1725001 4.27586663 -1.18125059 1 P 0 ;0,2=28,4=0.000000
L 4.27586663 -1.18125059 4.27026614 -1.19375246 1 P 0 ;0,2=28,4=0.000000
L 4.27026614 -1.19375246 4.2683999 -1.205 1 P 0 ;0,2=28,4=0.000000
L 4.2683999 -1.205 4.3076 -1.205 1 P 0 ;0,2=28,4=0.000000
L 4.35086663 -1.18000079 4.37513327 -1.18000079 1 P 0 ;0,2=28,4=0.000000
L 4.42026614 -1.1424997 4.42586663 -1.13500128 1 P 0 ;0,2=28,4=0.000000
L 4.42586663 -1.13500128 4.4324003 -1.1312498 1 P 0 ;0,2=28,4=0.000000
L 4.4324003 -1.1312498 4.43986703 -1.13 1 P 0 ;0,2=28,4=0.000000
L 4.43986703 -1.13 4.4492001 -1.13249951 1 P 0 ;0,2=28,4=0.000000
L 4.4492001 -1.13249951 4.45573376 -1.13875049 1 P 0 ;0,2=28,4=0.000000
L 4.45573376 -1.13875049 4.4576 -1.14624882 1 P 0 ;0,2=28,4=0.000000
L 4.4576 -1.14624882 4.45666693 -1.15375187 1 P 0 ;0,2=28,4=0.000000
L 4.45666693 -1.15375187 4.45293268 -1.16000049 1 P 0 ;0,2=28,4=0.000000
L 4.45293268 -1.16000049 4.43426654 -1.1725001 1 P 0 ;0,2=28,4=0.000000
L 4.43426654 -1.1725001 4.42586663 -1.18125059 1 P 0 ;0,2=28,4=0.000000
L 4.42586663 -1.18125059 4.42026614 -1.19375246 1 P 0 ;0,2=28,4=0.000000
L 4.42026614 -1.19375246 4.4183999 -1.205 1 P 0 ;0,2=28,4=0.000000
L 4.4183999 -1.205 4.4576 -1.205 1 P 0 ;0,2=28,4=0.000000
L 4.49246673 -1.19375246 4.49806555 -1.20000108 1 P 0 ;0,2=28,4=0.000000
L 4.49806555 -1.20000108 4.50459921 -1.2037503 1 P 0 ;0,2=28,4=0.000000
L 4.50459921 -1.2037503 4.51299911 -1.205 1 P 0 ;0,2=28,4=0.000000
L 4.51299911 -1.205 4.52140069 -1.20250059 1 P 0 ;0,2=28,4=0.000000
L 4.52140069 -1.20250059 4.52793268 -1.19750167 1 P 0 ;0,2=28,4=0.000000
L 4.52793268 -1.19750167 4.5326 -1.18875128 1 P 0 ;0,2=28,4=0.000000
L 4.5326 -1.18875128 4.53353317 -1.17875108 1 P 0 ;0,2=28,4=0.000000
L 4.53353317 -1.17875108 4.53166693 -1.16875089 1 P 0 ;0,2=28,4=0.000000
L 4.53166693 -1.16875089 4.52699951 -1.1625 1 P 0 ;0,2=28,4=0.000000
L 4.52699951 -1.1625 4.52046585 -1.15750108 1 P 0 ;0,2=28,4=0.000000
L 4.52046585 -1.15750108 4.51393396 -1.15625128 1 P 0 ;0,2=28,4=0.000000
L 4.51393396 -1.15625128 4.5074003 -1.15750108 1 P 0 ;0,2=28,4=0.000000
L 4.5074003 -1.15750108 4.49900039 -1.1625 1 P 0 ;0,2=28,4=0.000000
L 4.49900039 -1.1625 4.5017998 -1.13 1 P 0 ;0,2=28,4=0.000000
L 4.5017998 -1.13 4.52699951 -1.13 1 P 0 ;0,2=28,4=0.000000
L 3.29433297 -1.255 3.29433297 -1.33 1 P 0 ;0,2=29,4=0.000000
L 3.29433297 -1.33 3.33166693 -1.33 1 P 0 ;0,2=29,4=0.000000
L 3.40480059 -1.33 3.40480059 -1.28000157 1 P 0 ;0,2=29,4=0.000000
L 3.40480059 -1.2887497 3.40106644 -1.28375079 1 P 0 ;0,2=29,4=0.000000
L 3.40106644 -1.28375079 3.39546585 -1.28125128 1 P 0 ;0,2=29,4=0.000000
L 3.39546585 -1.28125128 3.38893396 -1.28000157 1 P 0 ;0,2=29,4=0.000000
L 3.38893396 -1.28000157 3.3824003 -1.28250108 1 P 0 ;0,2=29,4=0.000000
L 3.3824003 -1.28250108 3.3767998 -1.2875 1 P 0 ;0,2=29,4=0.000000
L 3.3767998 -1.2875 3.37306555 -1.29500069 1 P 0 ;0,2=29,4=0.000000
L 3.37306555 -1.29500069 3.37119931 -1.30500079 1 P 0 ;0,2=29,4=0.000000
L 3.37119931 -1.30500079 3.37306555 -1.31500098 1 P 0 ;0,2=29,4=0.000000
L 3.37306555 -1.31500098 3.3767998 -1.32250167 1 P 0 ;0,2=29,4=0.000000
L 3.3767998 -1.32250167 3.3824003 -1.32750059 1 P 0 ;0,2=29,4=0.000000
L 3.3824003 -1.32750059 3.38893396 -1.33 1 P 0 ;0,2=29,4=0.000000
L 3.38893396 -1.33 3.39546585 -1.3287503 1 P 0 ;0,2=29,4=0.000000
L 3.39546585 -1.3287503 3.40106644 -1.32500108 1 P 0 ;0,2=29,4=0.000000
L 3.40106644 -1.32500108 3.40480059 -1.32000217 1 P 0 ;0,2=29,4=0.000000
L 3.4433999 -1.3524997 3.44900039 -1.35499921 1 P 0 ;0,2=29,4=0.000000
L 3.44900039 -1.35499921 3.45646713 -1.3524997 1 P 0 ;0,2=29,4=0.000000
L 3.45646713 -1.3524997 3.46113287 -1.34750079 1 P 0 ;0,2=29,4=0.000000
L 3.46113287 -1.34750079 3.46486703 -1.3412498 1 P 0 ;0,2=29,4=0.000000
L 3.46486703 -1.3412498 3.47046585 -1.32125187 1 P 0 ;0,2=29,4=0.000000
L 3.47046585 -1.32125187 3.4826 -1.28000157 1 P 0 ;0,2=29,4=0.000000
L 3.45273287 -1.28000157 3.47046585 -1.32125187 1 P 0 ;0,2=29,4=0.000000
L 3.52400039 -1.29625039 3.55386752 -1.29625039 1 P 0 ;0,2=29,4=0.000000
L 3.55386752 -1.29625039 3.55106644 -1.2875 1 P 0 ;0,2=29,4=0.000000
L 3.55106644 -1.2875 3.54640069 -1.28250108 1 P 0 ;0,2=29,4=0.000000
L 3.54640069 -1.28250108 3.53986703 -1.28000157 1 P 0 ;0,2=29,4=0.000000
L 3.53986703 -1.28000157 3.53333346 -1.28125128 1 P 0 ;0,2=29,4=0.000000
L 3.53333346 -1.28125128 3.52773287 -1.28500049 1 P 0 ;0,2=29,4=0.000000
L 3.52773287 -1.28500049 3.52400039 -1.29375089 1 P 0 ;0,2=29,4=0.000000
L 3.52400039 -1.29375089 3.52213238 -1.30125157 1 P 0 ;0,2=29,4=0.000000
L 3.52213238 -1.30125157 3.52213238 -1.30875 1 P 0 ;0,2=29,4=0.000000
L 3.52213238 -1.30875 3.52400039 -1.31625069 1 P 0 ;0,2=29,4=0.000000
L 3.52400039 -1.31625069 3.52866604 -1.32375138 1 P 0 ;0,2=29,4=0.000000
L 3.52866604 -1.32375138 3.53426654 -1.3287503 1 P 0 ;0,2=29,4=0.000000
L 3.53426654 -1.3287503 3.5408002 -1.33 1 P 0 ;0,2=29,4=0.000000
L 3.5408002 -1.33 3.54733386 -1.32750059 1 P 0 ;0,2=29,4=0.000000
L 3.54733386 -1.32750059 3.55386752 -1.32000217 1 P 0 ;0,2=29,4=0.000000
L 3.59993346 -1.33 3.59993346 -1.28000157 1 P 0 ;0,2=29,4=0.000000
L 3.59993346 -1.28999941 3.60459921 -1.28500049 1 P 0 ;0,2=29,4=0.000000
L 3.60459921 -1.28500049 3.60926654 -1.28125128 1 P 0 ;0,2=29,4=0.000000
L 3.60926654 -1.28125128 3.6158002 -1.28000157 1 P 0 ;0,2=29,4=0.000000
L 3.6158002 -1.28000157 3.62046585 -1.28125128 1 P 0 ;0,2=29,4=0.000000
L 3.62046585 -1.28125128 3.62606644 -1.28500049 1 P 0 ;0,2=29,4=0.000000
L 3.68799911 -1.33249941 3.68613287 -1.3312497 1 P 0 ;0,2=29,4=0.000000
L 3.68613287 -1.3312497 3.68613287 -1.3287503 1 P 0 ;0,2=29,4=0.000000
L 3.68613287 -1.3287503 3.68799911 -1.32750059 1 P 0 ;0,2=29,4=0.000000
L 3.68799911 -1.32750059 3.68986703 -1.3287503 1 P 0 ;0,2=29,4=0.000000
L 3.68986703 -1.3287503 3.68986703 -1.3312497 1 P 0 ;0,2=29,4=0.000000
L 3.68986703 -1.3312497 3.68799911 -1.33249941 1 P 0 ;0,2=29,4=0.000000
L 3.68799911 -1.29875217 3.68613287 -1.2975001 1 P 0 ;0,2=29,4=0.000000
L 3.68613287 -1.2975001 3.68613287 -1.29500069 1 P 0 ;0,2=29,4=0.000000
L 3.68613287 -1.29500069 3.68799911 -1.29375089 1 P 0 ;0,2=29,4=0.000000
L 3.68799911 -1.29375089 3.68986703 -1.29500069 1 P 0 ;0,2=29,4=0.000000
L 3.68986703 -1.29500069 3.68986703 -1.2975001 1 P 0 ;0,2=29,4=0.000000
L 3.68986703 -1.2975001 3.68799911 -1.29875217 1 P 0 ;0,2=29,4=0.000000
L 3.36933297 -1.08 3.36933297 -1.005 1 P 0 ;0,2=30,4=0.000000
L 3.36933297 -1.005 3.39266644 -1.005 1 P 0 ;0,2=30,4=0.000000
L 3.39266644 -1.005 3.40013327 -1.00875157 1 P 0 ;0,2=30,4=0.000000
L 3.40013327 -1.00875157 3.40480059 -1.01375049 1 P 0 ;0,2=30,4=0.000000
L 3.40480059 -1.01375049 3.40666693 -1.02375059 1 P 0 ;0,2=30,4=0.000000
L 3.40666693 -1.02375059 3.40480059 -1.03375079 1 P 0 ;0,2=30,4=0.000000
L 3.40480059 -1.03375079 3.3992001 -1.03999941 1 P 0 ;0,2=30,4=0.000000
L 3.3992001 -1.03999941 3.39266644 -1.04375089 1 P 0 ;0,2=30,4=0.000000
L 3.39266644 -1.04375089 3.36933297 -1.04375089 1 P 0 ;0,2=30,4=0.000000
L 3.39266644 -1.04375089 3.40666693 -1.08 1 P 0 ;0,2=30,4=0.000000
L 3.44900039 -1.04625039 3.47886752 -1.04625039 1 P 0 ;0,2=30,4=0.000000
L 3.47886752 -1.04625039 3.47606644 -1.0375 1 P 0 ;0,2=30,4=0.000000
L 3.47606644 -1.0375 3.47140069 -1.03250108 1 P 0 ;0,2=30,4=0.000000
L 3.47140069 -1.03250108 3.46486703 -1.03000157 1 P 0 ;0,2=30,4=0.000000
L 3.46486703 -1.03000157 3.45833346 -1.03125128 1 P 0 ;0,2=30,4=0.000000
L 3.45833346 -1.03125128 3.45273287 -1.03500049 1 P 0 ;0,2=30,4=0.000000
L 3.45273287 -1.03500049 3.44900039 -1.04375089 1 P 0 ;0,2=30,4=0.000000
L 3.44900039 -1.04375089 3.44713238 -1.05125157 1 P 0 ;0,2=30,4=0.000000
L 3.44713238 -1.05125157 3.44713238 -1.05875 1 P 0 ;0,2=30,4=0.000000
L 3.44713238 -1.05875 3.44900039 -1.06625069 1 P 0 ;0,2=30,4=0.000000
L 3.44900039 -1.06625069 3.45366604 -1.07375138 1 P 0 ;0,2=30,4=0.000000
L 3.45366604 -1.07375138 3.45926654 -1.0787503 1 P 0 ;0,2=30,4=0.000000
L 3.45926654 -1.0787503 3.4658002 -1.08 1 P 0 ;0,2=30,4=0.000000
L 3.4658002 -1.08 3.47233386 -1.07750059 1 P 0 ;0,2=30,4=0.000000
L 3.47233386 -1.07750059 3.47886752 -1.07000217 1 P 0 ;0,2=30,4=0.000000
L 3.52119931 -1.03000157 3.53799911 -1.08 1 P 0 ;0,2=30,4=0.000000
L 3.53799911 -1.08 3.55480059 -1.03000157 1 P 0 ;0,2=30,4=0.000000
L 3.68799911 -1.08249941 3.68613287 -1.0812497 1 P 0 ;0,2=30,4=0.000000
L 3.68613287 -1.0812497 3.68613287 -1.0787503 1 P 0 ;0,2=30,4=0.000000
L 3.68613287 -1.0787503 3.68799911 -1.07750059 1 P 0 ;0,2=30,4=0.000000
L 3.68799911 -1.07750059 3.68986703 -1.0787503 1 P 0 ;0,2=30,4=0.000000
L 3.68986703 -1.0787503 3.68986703 -1.0812497 1 P 0 ;0,2=30,4=0.000000
L 3.68986703 -1.0812497 3.68799911 -1.08249941 1 P 0 ;0,2=30,4=0.000000
L 3.68799911 -1.04875217 3.68613287 -1.0475001 1 P 0 ;0,2=30,4=0.000000
L 3.68613287 -1.0475001 3.68613287 -1.04500069 1 P 0 ;0,2=30,4=0.000000
L 3.68613287 -1.04500069 3.68799911 -1.04375089 1 P 0 ;0,2=30,4=0.000000
L 3.68799911 -1.04375089 3.68986703 -1.04500069 1 P 0 ;0,2=30,4=0.000000
L 3.68986703 -1.04500069 3.68986703 -1.0475001 1 P 0 ;0,2=30,4=0.000000
L 3.68986703 -1.0475001 3.68799911 -1.04875217 1 P 0 ;0,2=30,4=0.000000
L 3.83799911 -1.005 3.83053228 -1.00749951 1 P 0 ;0,2=30,4=0.000000
L 3.83053228 -1.00749951 3.82493346 -1.01375049 1 P 0 ;0,2=30,4=0.000000
L 3.82493346 -1.01375049 3.82119931 -1.02124882 1 P 0 ;0,2=30,4=0.000000
L 3.82119931 -1.02124882 3.8183999 -1.03125128 1 P 0 ;0,2=30,4=0.000000
L 3.8183999 -1.03125128 3.81746673 -1.04250118 1 P 0 ;0,2=30,4=0.000000
L 3.81746673 -1.04250118 3.8183999 -1.05375108 1 P 0 ;0,2=30,4=0.000000
L 3.8183999 -1.05375108 3.82119931 -1.06375128 1 P 0 ;0,2=30,4=0.000000
L 3.82119931 -1.06375128 3.82493346 -1.07125187 1 P 0 ;0,2=30,4=0.000000
L 3.82493346 -1.07125187 3.83053228 -1.07750059 1 P 0 ;0,2=30,4=0.000000
L 3.83053228 -1.07750059 3.83799911 -1.08 1 P 0 ;0,2=30,4=0.000000
L 3.83799911 -1.08 3.84546585 -1.07750059 1 P 0 ;0,2=30,4=0.000000
L 3.84546585 -1.07750059 3.85106644 -1.07125187 1 P 0 ;0,2=30,4=0.000000
L 3.85106644 -1.07125187 3.85480059 -1.06375128 1 P 0 ;0,2=30,4=0.000000
L 3.85480059 -1.06375128 3.8576 -1.05375108 1 P 0 ;0,2=30,4=0.000000
L 3.8576 -1.05375108 3.85853317 -1.04250118 1 P 0 ;0,2=30,4=0.000000
L 3.85853317 -1.04250118 3.8576 -1.03125128 1 P 0 ;0,2=30,4=0.000000
L 3.8576 -1.03125128 3.85480059 -1.02124882 1 P 0 ;0,2=30,4=0.000000
L 3.85480059 -1.02124882 3.85106644 -1.01375049 1 P 0 ;0,2=30,4=0.000000
L 3.85106644 -1.01375049 3.84546585 -1.00749951 1 P 0 ;0,2=30,4=0.000000
L 3.84546585 -1.00749951 3.83799911 -1.005 1 P 0 ;0,2=30,4=0.000000
L 3.91299911 -1.08 3.91299911 -1.005 1 P 0 ;0,2=30,4=0.000000
L 3.91299911 -1.005 3.9017998 -1.01999911 1 P 0 ;0,2=30,4=0.000000
L 3.9017998 -1.08 3.92419843 -1.08 1 P 0 ;0,2=30,4=0.000000

### steps/pcb/layers/l04_gnd2/features
#
#Num Features
#
F 2385

#
#Units
#
U INCH

#
#Feature symbol names
#
$0 r5
$1 r6
$2 r10
$3 r26
$4 r28
$5 r30
$6 r32
$7 r39
$8 r82
$9 r99
$10 r102
$11 r125
$12 r143
$13 r150
$14 024x051ob071x075p_l
$15 024x051ob071x075p_r
$16 024x063ob035x075p
$17 ths102x92.01x45x4x14 I
$18 ths105x95x45x4x14 I
$19 ths191.99x182x45x4x27 I
$20 ths42.01x31.99x45x4x10 I
$21 ths58.99x49x45x4x10 I
$22 ths89x79x45x4x11.99 I

#
#Feature attribute names
#
@0 .nomenclature
@1 .geometry
@2 .sip

#
#Feature attribute text strings
#
&0 V010C020P_TP030B
&1 V008C018P-ANTI28-NSM
&2 V010C020P
&3 TPV010CT020B030
&4 V008C018P_ANTI026_TP030B
&5 V008C018P_NATI28_TP030B_NSMT
&6 016C024P
&7 V008C018P_TP030B
&8 V008C018P
&9 V008C018P_ANTI28
&10 059C086P
&11 V008C018P_ANTI026_NSM
&12 076S104P
&13 076C104P
&14 079C100P
&15 V010C020P_SM014-NTH
&16 024X063OB035X075P
&17 166CT244CB198P
&18 024X051OB071X075P_R
&19 024X051OB071X075P_L
&20 033C057P
&21 063C090P
&22 MTH100C090N
&23 MTH125C115N
&24 MTH118C108N

#
#Layer features
#
S P 0;0,2=1
OB -24.76435 -17.98935 I
OS -24.76435 16.38535
OS 21.05735 16.38535
OS 21.05735 -17.98935
OS -24.76435 -17.98935
OE
OB -0.00110019685 0.21653976378 H
OC 0.039369783465 0.176069783465 0.039369783465 0.21653976378 N
OS 0.551194094488 0.176069980315
OC 0.59165 0.216525885827 0.551180019685 0.21653996063 N
OS 0.59165019685 0.46260019685
OC 0.629906200787 0.500870177165 0.629920177165 0.46260019685 Y
OS 1.273619980315 0.500869980315
OC 1.31188996063 0.462613779528 1.273619980315 0.4626 Y
OS 1.31188976378 0.21653976378
OC 1.35235984252 0.176069783465 1.352359744094 0.21653976378 N
OS 1.588594094488 0.176069980315
OC 1.62905 0.216525885827 1.588580019685 0.21653996063 N
OS 1.62905019685 0.430120177165
OC 1.77055019685 0.430134055118 1.69980019685 0.430120177165 Y
OS 1.770550098425 0.019702952756
OC 1.770872244094 0.018912204724 1.77165 0.019690059055 N
OS 1.790547933071 -0.000763484252
OC 1.791339862205 -0.001100098425 1.79133996063 -0.000000098425 N
OS 2.192896850394 -0.001100098425
OC 2.193511712598 -0.000920767717 2.192909645669 -0.00000019685 N
OC 2.193677066929 -0.000788484252 2.192910728346 -0.000000098425 N
OS 2.213388188976 0.018922637795
OC 2.213699901575 0.019689862205 2.212599901575 0.019689862205 N
OS 2.2137 0.29331003937
OC 2.2863 0.29331003937 2.25 0.29331003937 Y
OS 2.286300098425 0.019690059055
OC 2.286636712598 0.018898129921 2.287400098425 0.01969015748 N
OS 2.306298129921 -0.000763287402
OC 2.307090059055 -0.001099901575 2.30709015748 0.000000098425 N
OS 3.102347047244 -0.001099901575
OC 3.102961909449 -0.000920570866 3.10235984252 0 N
OC 3.10312726378 -0.000788287402 3.102360925197 0.000000098425 N
OS 3.122837893701 0.01892234252
OC 3.122970570866 0.019087992126 3.122049901575 0.019689468504 N
OC 3.123149901575 0.019702952756 3.12205 0.019690059055 N
OS 3.12314980315 0.462613779528
OC 3.161419783465 0.500869783465 3.161419783465 0.46259980315 Y
OS 6.561034055118 0.500869980315
OC 6.60148996063 0.541325885827 6.561019980315 0.54133996063 N
OS 6.60149015748 2.374999901575
OC 6.580710531496 2.39579015748 6.580705216535 2.375005216535 N
OS 6.572096555118 2.39578996063
OC 6.553530019685 2.414369980315 6.57211003937 2.414369980315 Y
OS 6.553529822835 2.826783759843
OC 6.572110137795 2.84535984252 6.57211476378 2.826774901575 Y
OS 6.572111122047 2.84535984252
OS 6.580724409449 2.84536003937
OC 6.60148996063 2.866125590551 6.58071003937 2.86613996063 N
OS 6.60149015748 4.33661023622
OC 6.561020177165 4.377080216535 6.561020177165 4.33661023622 N
OS 0.039355905512 4.377080019685
OC -0.0011 4.336624114173 0.039369980315 4.33661003937 N
OS -0.00110019685 0.21653976378
OE
SE
S P 0
OB -0.00110019685 0.21653976378 I
OS -0.0011 4.336624114173
OC 0.039355905512 4.377080019685 0.039369980315 4.33661003937 Y
OS 6.561020177165 4.377080216535
OC 6.60149015748 4.33661023622 6.561020177165 4.33661023622 Y
OS 6.60148996063 2.866125590551
OC 6.580724409449 2.84536003937 6.58071003937 2.86613996063 Y
OS 6.580725 2.84536003937
OS 6.580710629921 2.845359940945
OS 6.572123917323 2.845359940945
OS 6.572111122047 2.84535984252
OS 6.572110137795 2.84535984252
OC 6.553529822835 2.826783759843 6.57211476378 2.826774901575 N
OS 6.553530019685 2.414369980315
OC 6.572096555118 2.39578996063 6.57211003937 2.414369980315 N
OS 6.580710531496 2.39579015748
OC 6.60149015748 2.374999901575 6.580705216535 2.375005216535 Y
OS 6.60148996063 0.541325885827
OC 6.561034055118 0.500869980315 6.561019980315 0.54133996063 Y
OS 6.561034744094 0.500869980315
OS 6.561020570866 0.50086988189
OS 3.161433858268 0.50086988189
OS 3.161419783465 0.500869783465
OC 3.12314980315 0.462613779528 3.161419783465 0.46259980315 N
OS 3.123149901575 0.019702952756
OC 3.122970570866 0.019087992126 3.12205 0.019690059055 Y
OC 3.122837893701 0.01892234252 3.122049901575 0.019689468504 Y
OS 3.10312726378 -0.000788287402
OC 3.102961909449 -0.000920570866 3.102360925197 0.000000098425 Y
OC 3.102347047244 -0.001099901575 3.10235984252 0 Y
OS 2.307090059055 -0.001099901575
OC 2.306298129921 -0.000763287402 2.30709015748 0.000000098425 Y
OS 2.286636712598 0.018898129921
OC 2.286300098425 0.019690059055 2.287400098425 0.01969015748 Y
OS 2.2863 0.29331003937
OC 2.2137 0.29331003937 2.25 0.29331003937 N
OS 2.213699901575 0.019689862205
OC 2.213388188976 0.018922637795 2.212599901575 0.019689862205 Y
OS 2.193677066929 -0.000788484252
OC 2.193511712598 -0.000920767717 2.192910728346 -0.000000098425 Y
OC 2.192896850394 -0.001100098425 2.192909645669 -0.00000019685 Y
OS 1.791339862205 -0.001100098425
OC 1.790547933071 -0.000763484252 1.79133996063 -0.000000098425 Y
OS 1.770872244094 0.018912204724
OC 1.770550098425 0.019702952756 1.77165 0.019690059055 Y
OS 1.77055019685 0.430134055118
OC 1.62905019685 0.430120177165 1.69980019685 0.430120177165 N
OS 1.62905 0.216525885827
OC 1.588594094488 0.176069980315 1.588580019685 0.21653996063 Y
OS 1.588594783465 0.176069980315
OS 1.588580610236 0.17606988189
OS 1.352373917323 0.17606988189
OS 1.35235984252 0.176069783465
OC 1.31188976378 0.21653976378 1.352359744094 0.21653976378 Y
OS 1.31188996063 0.462613779528
OC 1.273619980315 0.500869980315 1.273619980315 0.4626 N
OS 0.629906200787 0.500870177165
OC 0.59165019685 0.46260019685 0.629920177165 0.46260019685 N
OS 0.59165 0.216525885827
OC 0.551194094488 0.176069980315 0.551180019685 0.21653996063 Y
OS 0.551194783465 0.176069980315
OS 0.551180610236 0.17606988189
OS 0.039383858268 0.17606988189
OS 0.039369783465 0.176069783465
OC -0.00110019685 0.21653976378 0.039369783465 0.21653976378 Y
OE
OB 0.03003996063 0.21653996063 H
OC 0.039369980315 0.20721003937 0.03936988189 0.21653996063 N
OS 0.551180019685 0.20721003937
OC 0.56051003937 0.21653996063 0.55118011811 0.21653996063 N
OS 0.56051003937 0.4626
OC 0.629919980315 0.53201003937 0.629919980315 0.462600098425 Y
OS 1.273619980315 0.53201003937
OC 1.343030019685 0.4626 1.273619980315 0.4626 Y
OS 1.343030019685 0.21653996063
OC 1.35236003937 0.20721003937 1.352359940945 0.21653996063 N
OS 1.588580019685 0.20721003937
OC 1.59791003937 0.21653996063 1.58858011811 0.21653996063 N
OS 1.59791003937 0.430119980315
OC 1.80168996063 0.430119980315 1.6998 0.430119980315 Y
OS 1.80168996063 0.262
OS 2.18256003937 0.262
OS 2.18256003937 0.29331003937
OC 2.31743996063 0.29331003937 2.25 0.29331003937 Y
OS 2.31743996063 0.262
OS 3.09201003937 0.262
OS 3.09201003937 0.4626
OC 3.161419980315 0.53201003937 3.161419980315 0.462600098425 Y
OS 6.561019980315 0.53201003937
OC 6.57035 0.54133996063 6.56102007874 0.54133996063 N
OS 6.57035 2.364680019685
OC 6.52238996063 2.414369980315 6.572111220472 2.41437007874 Y
OS 6.52238996063 2.826780019685
OC 6.57035 2.876469980315 6.572115452756 2.826775885827 Y
OS 6.57035 4.33661003937
OC 6.561019980315 4.34593996063 6.56102007874 4.33661003937 N
OS 0.039369980315 4.34593996063
OC 0.03003996063 4.33661003937 0.03936988189 4.33661003937 N
OS 0.03003996063 0.21653996063
OE
OB 0.36981003937 0.36811003937 I
OC 0.36981003937 0.36811003937 0.295280019685 0.36811003937 Y
OE
OB 0.36981003937 3.73031003937 I
OC 0.36981003937 3.73031003937 0.295280019685 3.73031003937 Y
OE
OB 0.688980019685 3.560980019685 I
OS 0.688980019685 3.589019980315
OS 0.749019980315 3.589019980315
OS 0.749019980315 3.560980019685
OS 0.688980019685 3.560980019685
OE
OB 1.058980019685 3.810980019685 I
OS 1.058980019685 3.839019980315
OS 1.119019980315 3.839019980315
OS 1.119019980315 3.810980019685
OS 1.058980019685 3.810980019685
OE
OB 1.4977 1.060430019685 I
OC 1.4977 1.060430019685 1.435669980315 1.060430019685 Y
OE
OB 1.5227 2.680430019685 I
OC 1.5227 2.680430019685 1.460669980315 2.680430019685 Y
OE
OB 2.39006003937 0.679980019685 I
OS 2.39006003937 0.750019980315
OS 2.4201 0.750019980315
OS 2.4201 0.679980019685
OS 2.39006003937 0.679980019685
OE
OB 2.4562 0.748980019685 I
OS 2.4562 0.777019980315
OS 2.51623996063 0.777019980315
OS 2.51623996063 0.748980019685
OS 2.4562 0.748980019685
OE
OB 2.7477 1.121430019685 I
OC 2.7477 1.121430019685 2.685669980315 1.121430019685 Y
OE
OB 2.7477 2.559430019685 I
OC 2.7477 2.559430019685 2.685669980315 2.559430019685 Y
OE
OB 2.629380019685 0.338980019685 I
OS 2.629380019685 0.399019980315
OS 2.6574 0.399019980315
OS 2.6574 0.338980019685
OS 2.629380019685 0.338980019685
OE
OB 2.65306003937 0.748980019685 I
OS 2.65306003937 0.777019980315
OS 2.713080019685 0.777019980315
OS 2.713080019685 0.748980019685
OS 2.65306003937 0.748980019685
OE
OB 2.783 1.971980019685 I
OS 2.783 2.002019980315
OS 2.853019980315 2.002019980315
OS 2.853019980315 1.971980019685
OS 2.783 1.971980019685
OE
OB 2.78686003937 0.338980019685 I
OS 2.78686003937 0.399019980315
OS 2.814880019685 0.399019980315
OS 2.814880019685 0.338980019685
OS 2.78686003937 0.338980019685
OE
OB 2.80453996063 0.748980019685 I
OS 2.80453996063 0.777019980315
OS 2.86456003937 0.777019980315
OS 2.86456003937 0.748980019685
OS 2.80453996063 0.748980019685
OE
OB 2.829980019685 1.823980019685 I
OS 2.829980019685 1.894019980315
OS 2.860019980315 1.894019980315
OS 2.860019980315 1.823980019685
OS 2.829980019685 1.823980019685
OE
OB 2.94433996063 0.338980019685 I
OS 2.94433996063 0.399019980315
OS 2.97236003937 0.399019980315
OS 2.97236003937 0.338980019685
OS 2.94433996063 0.338980019685
OE
OB 2.94433996063 0.434980019685 I
OS 2.94433996063 0.495019980315
OS 2.97236003937 0.495019980315
OS 2.97236003937 0.434980019685
OS 2.94433996063 0.434980019685
OE
OB 3.10516003937 0.875 I
OS 3.125 0.89483996063
OS 3.167469980315 0.852369980315
OS 3.147630019685 0.832530019685
OS 3.10516003937 0.875
OE
OB 3.213080019685 1.888980019685 I
OS 3.213080019685 1.917
OS 3.273119980315 1.917
OS 3.273119980315 1.888980019685
OS 3.213080019685 1.888980019685
OE
OB 3.359980019685 1.142980019685 I
OS 3.359980019685 1.213019980315
OS 3.390019980315 1.213019980315
OS 3.390019980315 1.142980019685
OS 3.359980019685 1.142980019685
OE
OB 3.398980019685 1.069980019685 I
OS 3.398980019685 1.100019980315
OS 3.469019980315 1.100019980315
OS 3.469019980315 1.069980019685
OS 3.398980019685 1.069980019685
OE
OB 3.439 1.884980019685 I
OS 3.439 1.945
OS 3.467019980315 1.945
OS 3.467019980315 1.884980019685
OS 3.439 1.884980019685
OE
OB 3.49563996063 1.03206003937 I
OS 3.49563996063 1.062080019685
OS 3.56566003937 1.062080019685
OS 3.56566003937 1.03206003937
OS 3.49563996063 1.03206003937
OE
OB 3.610980019685 0.905980019685 I
OS 3.610980019685 0.934019980315
OS 3.671019980315 0.934019980315
OS 3.671019980315 0.905980019685
OS 3.610980019685 0.905980019685
OE
OB 3.637 1.869580019685 I
OS 3.637 1.9296
OS 3.665019980315 1.9296
OS 3.665019980315 1.869580019685
OS 3.637 1.869580019685
OE
OB 3.871930019685 1.417019980315 I
OC 3.871930019685 1.443080019685 3.871930019685 1.43005 Y
OS 3.9113 1.443080019685
OC 3.9113 1.417019980315 3.9113 1.43005 Y
OS 3.871930019685 1.417019980315
OE
OB 3.871930019685 1.49576003937 I
OC 3.871930019685 1.521819980315 3.871930019685 1.508790059055 Y
OS 3.9113 1.521819980315
OC 3.9113 1.49576003937 3.9113 1.508790059055 Y
OS 3.871930019685 1.49576003937
OE
OB 3.871930019685 1.5745 I
OC 3.871930019685 1.60056003937 3.871930019685 1.587530019685 Y
OS 3.9113 1.60056003937
OC 3.9113 1.5745 3.9113 1.587530019685 Y
OS 3.871930019685 1.5745
OE
OB 3.871930019685 1.65323996063 I
OC 3.871930019685 1.6793 3.871930019685 1.666269980315 Y
OS 3.9113 1.6793
OC 3.9113 1.65323996063 3.9113 1.666269980315 Y
OS 3.871930019685 1.65323996063
OE
OB 3.950669980315 1.53513996063 I
OC 3.950669980315 1.561180019685 3.950669980315 1.54816003937 Y
OS 3.99003996063 1.561180019685
OC 3.99003996063 1.53513996063 3.99003996063 1.54816003937 Y
OS 3.950669980315 1.53513996063
OE
OB 3.950669980315 1.692619980315 I
OC 3.950669980315 1.71866003937 3.950669980315 1.705640059055 Y
OS 3.99003996063 1.71866003937
OC 3.99003996063 1.692619980315 3.99003996063 1.705640059055 Y
OS 3.950669980315 1.692619980315
OE
OB 3.950669980315 1.4564 I
OC 3.950669980315 1.48243996063 3.950669980315 1.469419980315 Y
OS 3.99003996063 1.48243996063
OC 3.99003996063 1.4564 3.99003996063 1.469419980315 Y
OS 3.950669980315 1.4564
OE
OB 3.950669980315 1.613880019685 I
OC 3.950669980315 1.639919980315 3.950669980315 1.6269 Y
OS 3.99003996063 1.639919980315
OC 3.99003996063 1.613880019685 3.99003996063 1.6269 Y
OS 3.950669980315 1.613880019685
OE
OB 3.997480019685 1.145980019685 I
OS 3.997480019685 1.176
OS 4.067519980315 1.176
OS 4.067519980315 1.145980019685
OS 3.997480019685 1.145980019685
OE
OB 4.029419980315 1.49576003937 I
OC 4.029419980315 1.521819980315 4.029419980315 1.508790059055 Y
OS 4.06878996063 1.521819980315
OC 4.06878996063 1.49576003937 4.06878996063 1.508790059055 Y
OS 4.029419980315 1.49576003937
OE
OB 4.029419980315 1.65323996063 I
OC 4.029419980315 1.6793 4.029419980315 1.666269980315 Y
OS 4.06878996063 1.6793
OC 4.06878996063 1.65323996063 4.06878996063 1.666269980315 Y
OS 4.029419980315 1.65323996063
OE
OB 4.3575 1.150980019685 I
OS 4.3575 1.181
OS 4.427519980315 1.181
OS 4.427519980315 1.150980019685
OS 4.3575 1.150980019685
OE
OB 4.42311003937 1.850080019685 I
OC 4.42311003937 1.87613996063 4.42311003937 1.86311003937 Y
OS 4.462480019685 1.87613996063
OC 4.462480019685 1.850080019685 4.462480019685 1.86311003937 Y
OS 4.42311003937 1.850080019685
OE
OB 4.462480019685 1.417019980315 I
OC 4.462480019685 1.443080019685 4.462480019685 1.43005 Y
OS 4.50185 1.443080019685
OC 4.50185 1.417019980315 4.50185 1.43005 Y
OS 4.462480019685 1.417019980315
OE
OB 4.5223 1.20666003937 I
OS 4.5223 1.236680019685
OS 4.592319980315 1.236680019685
OS 4.592319980315 1.20666003937
OS 4.5223 1.20666003937
OE
OB 4.61996003937 1.2989 I
OC 4.61996003937 1.32496003937 4.61996003937 1.311930019685 Y
OS 4.659330019685 1.32496003937
OC 4.659330019685 1.2989 4.659330019685 1.311930019685 Y
OS 4.61996003937 1.2989
OE
OB 4.6987 1.4564 I
OC 4.6987 1.48243996063 4.6987 1.469419980315 Y
OS 4.738069980315 1.48243996063
OC 4.738069980315 1.4564 4.738069980315 1.469419980315 Y
OS 4.6987 1.4564
OE
OB 4.72503996063 1.3513 I
OS 4.72503996063 1.390669980315
OC 4.7511 1.390669980315 4.738069980315 1.390669980315 Y
OS 4.7511 1.3513
OC 4.72503996063 1.3513 4.738069980315 1.3513 Y
OE
OB 6.190030019685 2.094 I
OC 6.190030019685 2.094 5.99 2.094 Y
OE
OB 5.974969980315 1.045 I
OC 5.984369980315 1.1056 6.174999507874 1.045001377953 Y
OC 5.97846003937 1.12348996063 6.008502165354 1.123493208661 Y
OS 5.97846003937 1.1235
OC 6.00696003937 1.1535 6.008499507874 1.1235 Y
OC 6.175 1.245030019685 6.175000098425 1.045012598425 Y
OC 6.375030019685 1.045 6.175 1.045 Y
OC 6.362830019685 0.97621003937 6.174992913386 1.045 Y
OC 6.365 0.96501003937 6.334998523622 0.965007480315 Y
OS 6.365 0.965
OC 6.342730019685 0.93601003937 6.334996161417 0.965 Y
OC 6.175 0.844969980315 6.174999901575 1.045000984252 Y
OC 5.974969980315 1.045 6.175 1.045 Y
OE
OB 6.1856 2.230719980315 I
OS 6.1856 2.29076003937
OS 6.213619980315 2.29076003937
OS 6.213619980315 2.230719980315
OS 6.1856 2.230719980315
OE
OB 6.424580019685 3.34448996063 I
OC 6.424580019685 3.34448996063 6.34055 3.34448996063 Y
OE
OB 6.424580019685 3.67518996063 I
OC 6.424580019685 3.67518996063 6.34055 3.67518996063 Y
OE
OB 6.474919980315 0.65353996063 I
OC 6.474919980315 0.65353996063 6.40038996063 0.65353996063 Y
OE
OB 6.474919980315 4.17835 I
OC 6.474919980315 4.17835 6.40038996063 4.17835 Y
OE
SE
P 4.31 4.065 6 P 0 8 0;1=0
P 4.31 4.115 6 P 0 8 0;1=0
P 4.61 2.3 6 P 0 8 0;1=0
P 4.50185 2.05996004 4 P 0 8 0;1=1
P 4.49 2.275 6 P 0 8 0;1=0
P 4.435 2.315 6 P 0 8 0;1=0
P 4.49 2.325 6 P 0 8 0;1=0
P 4.435 2.365 6 P 0 8 0;1=0
P 3.655 2.465 6 P 0 8 0;1=0
P 3.125 1.605 6 P 0 8 0;1=0
P 3.65 2.68 6 P 0 8 0;1=2
P 3.12 2.645 6 P 0 8 0;1=2
P 4.1869 2.09933002 4 P 0 8 0;1=1
P 3.765 2.69 6 P 0 8 0;1=0
P 4.50185 1.50878996 4 P 0 8 0;1=1
P 4.3 3.865 4 P 0 8 0;1=3
P 3.36525 3.305 3 P 0 8 0;1=4
P 3.37 3.44 4 P 0 8 0;1=3
P 4.795 0.925 4 P 0 8 0;1=3
P 4.08 3.27 4 P 0 8 0;1=3
P 3.95 3.82 4 P 0 8 0;1=3
P 3.746 1.782 4 P 0 8 0;1=3
P 4.06878996 1.58753002 4 P 0 8 0;1=1
P 4.205 0.82 4 P 0 8 0;1=3
P 3.82286004 0.86213996 6 P 0 8 0;1=0
P 3.705 0.84 4 P 0 8 0;1=3
P 0.496 2.13455 6 P 0 8 0;1=0
P 0.528 2.72 6 P 0 8 0;1=0
P 0.575 1.015 6 P 0 8 0;1=0
P 0.48956998 1.53618996 6 P 0 8 0;1=0
P 4.65933002 1.98121998 4 P 0 8 0;1=1
P 4.06878996 1.90248002 4 P 0 8 0;1=1
P 4.50185 1.39066998 4 P 0 8 0;1=1
P 4.06878996 2.1387 4 P 0 8 0;1=1
P 4.22626998 2.05996004 4 P 0 8 0;1=1
P 3.95066998 2.05996004 4 P 0 8 0;1=1
P 4.22626998 2.02058996 4 P 0 8 0;1=1
P 4.26563996 2.09933002 4 P 0 8 0;1=1
P 4.26563996 2.05996004 4 P 0 8 0;1=1
P 4.50185 1.90248002 4 P 0 8 0;1=1
P 4.73806998 2.09933002 4 P 0 8 0;1=1
P 4.02941998 2.02058996 4 P 0 8 0;1=1
P 4.50185 1.86311004 4 P 0 8 0;1=1
P 4.6987 2.05996004 4 P 0 8 0;1=1
P 4.61996004 1.94185 4 P 0 8 0;1=1
P 4.61996004 1.98121998 4 P 0 8 0;1=1
P 4.26563996 2.02058996 4 P 0 8 0;1=1
P 4.61996004 1.90248002 4 P 0 8 0;1=1
P 4.58058996 1.98121998 4 P 0 8 0;1=1
P 4.54121998 2.02058996 4 P 0 8 0;1=1
P 4.34436998 2.09933002 4 P 0 8 0;1=1
P 4.06878996 2.09933002 4 P 0 8 0;1=5
P 4.6987 1.50878996 4 P 0 8 0;1=1
P 4.54121998 1.98121998 4 P 0 8 0;1=1
P 4.06878996 2.05996004 4 P 0 8 0;1=1
P 4.65933002 1.50878996 4 P 0 8 0;1=1
P 3.95066998 2.09933002 4 P 0 8 0;1=1
P 4.61996004 1.54816004 4 P 0 8 0;1=1
P 3.99005 2.09933002 4 P 0 8 0;1=5
P 4.58058996 1.54816004 4 P 0 8 0;1=1
P 4.6987 1.94185 4 P 0 8 0;1=1
P 4.50185 2.02058996 4 P 0 8 0;1=1
P 4.46248002 2.02058996 4 P 0 8 0;1=1
P 4.42311004 1.98121998 4 P 0 8 0;1=1
P 4.46248002 1.94185 4 P 0 8 0;1=1
P 4.38373996 1.86311004 4 P 0 8 0;1=1
P 4.38373996 1.82373996 4 P 0 8 0;1=1
P 4.46248002 1.98121998 4 P 0 8 0;1=1
P 4.10816004 1.94185 4 P 0 8 0;1=1
P 4.02941998 1.98121998 4 P 0 8 0;1=1
P 4.58058996 2.17806998 4 P 0 8 0;1=1
P 4.73806998 1.90248002 4 P 0 8 0;1=1
P 4.54121998 2.1387 4 P 0 8 0;1=1
P 4.10816004 2.02058996 4 P 0 8 0;1=1
P 4.50185 2.1387 4 P 0 8 0;1=1
P 3.99005 1.94185 4 P 0 8 0;1=1
P 4.02941998 1.94185 4 P 0 8 0;1=1
P 4.50185 2.09933002 4 P 0 8 0;1=1
P 4.14753002 2.02058996 4 P 0 8 0;1=1
P 4.61996004 2.17806998 4 P 0 8 0;1=1
P 4.02941998 1.86311004 4 P 0 8 0;1=1
P 4.06878996 1.43005 4 P 0 8 0;1=1
P 4.54121998 1.54816004 4 P 0 8 0;1=1
P 4.26563996 1.50878996 4 P 0 8 0;1=1
P 4.1869 1.94185 4 P 0 8 0;1=1
P 4.14753002 1.46941998 4 P 0 8 0;1=1
P 4.1869 1.46941998 4 P 0 8 0;1=1
P 4.1869 2.1387 4 P 0 8 0;1=1
P 4.6987 1.43005 4 P 0 8 0;1=1
P 4.10816004 1.39066998 4 P 0 8 0;1=1
P 4.65933002 1.43005 4 P 0 8 0;1=1
P 4.14753002 1.39066998 4 P 0 8 0;1=1
P 4.61996004 1.43005 4 P 0 8 0;1=1
P 4.10816004 1.43005 4 P 0 8 0;1=1
P 4.58058996 1.43005 4 P 0 8 0;1=1
P 4.14753002 1.43005 4 P 0 8 0;1=1
P 4.1869 1.43005 4 P 0 8 0;1=1
P 4.22626998 1.43005 4 P 0 8 0;1=1
P 4.54121998 1.46941998 4 P 0 8 0;1=1
P 4.22626998 1.39066998 4 P 0 8 0;1=1
P 4.50185 1.46941998 4 P 0 8 0;1=1
P 4.26563996 1.39066998 4 P 0 8 0;1=1
P 4.61996004 1.46941998 4 P 0 8 0;1=1
P 4.26563996 1.31193002 4 P 0 8 0;1=1
P 4.61996004 1.50878996 4 P 0 8 0;1=1
P 4.34436998 1.31193002 4 P 0 8 0;1=1
P 4.58058996 1.46941998 4 P 0 8 0;1=1
P 4.34436998 1.3513 4 P 0 8 0;1=1
P 4.54121998 1.50878996 4 P 0 8 0;1=1
P 4.34436998 1.39066998 4 P 0 8 0;1=1
P 4.1869 1.50878996 4 P 0 8 0;1=1
P 4.46248002 1.50878996 4 P 0 8 0;1=1
P 4.22626998 1.50878996 4 P 0 8 0;1=1
P 4.26563996 1.43005 4 P 0 8 0;1=5
P 4.26563996 1.46941998 4 P 0 8 0;1=1
P 4.38373996 1.39066998 4 P 0 8 0;1=1
P 4.38373996 1.43005 4 P 0 8 0;1=1
P 4.54121998 1.31193002 4 P 0 8 0;1=1
P 4.49876004 1.31501998 4 P 0 8 0;1=1
P 4.34436998 1.98121998 4 P 0 8 0;1=1
P 4.57843996 1.35345 4 P 0 8 0;1=1
P 3.9113 1.3513 4 P 0 8 0;1=1
P 4.54121998 1.3513 4 P 0 8 0;1=1
P 3.95066998 1.3513 4 P 0 8 0;1=1
P 4.45938996 1.35438996 4 P 0 8 0;1=1
P 3.99 1.31188002 4 P 0 8 0;1=1
P 4.46248002 1.39066998 4 P 0 8 0;1=1
P 4.65933002 1.3513 4 P 0 8 0;1=1
P 3.99 1.35125 4 P 0 8 0;1=1
P 4.61996004 1.3513 4 P 0 8 0;1=1
P 4.6987 1.86311004 4 P 0 8 0;1=1
P 4.46248002 2.05996004 4 P 0 8 0;1=1
P 4.06873996 1.31188002 4 P 0 8 0;1=1
P 4.65933002 1.82373996 4 P 0 8 0;1=1
P 4.42311004 2.05996004 4 P 0 8 0;1=1
P 4.10811004 1.31188002 4 P 0 8 0;1=1
P 4.58058996 1.39066998 4 P 0 8 0;1=1
P 4.02941998 1.39066998 4 P 0 8 0;1=1
P 4.54121998 1.39066998 4 P 0 8 0;1=1
P 4.06878996 1.39066998 4 P 0 8 0;1=1
P 4.73806998 1.78436998 4 P 0 8 0;1=1
P 4.73806998 1.31193002 4 P 0 8 0;1=1
P 4.1869 1.31193002 4 P 0 8 0;1=1
P 4.73806998 1.70563996 4 P 0 8 0;1=1
P 4.6987 1.31193002 4 P 0 8 0;1=1
P 4.22626998 1.31193002 4 P 0 8 0;1=1
P 4.10816004 1.3513 4 P 0 8 0;1=1
P 4.14753002 1.3513 4 P 0 8 0;1=1
P 4.6987 1.39066998 4 P 0 8 0;1=1
P 4.1869 1.3513 4 P 0 8 0;1=1
P 4.65933002 1.39066998 4 P 0 8 0;1=1
P 4.22626998 1.3513 4 P 0 8 0;1=1
P 4.73806998 2.17806998 4 P 0 8 0;1=1
P 4.73806998 2.1387 4 P 0 8 0;1=1
P 4.58058996 2.09933002 4 P 0 8 0;1=1
P 4.54121998 2.09933002 4 P 0 8 0;1=1
P 4.58058996 1.86311004 4 P 0 8 0;1=1
P 4.65933002 2.05996004 4 P 0 8 0;1=1
P 4.58058996 2.05996004 4 P 0 8 0;1=1
P 4.54121998 1.90248002 4 P 0 8 0;1=1
P 4.58058996 2.02058996 4 P 0 8 0;1=1
P 4.22626998 1.98121998 4 P 0 8 0;1=1
P 4.26563996 1.94185 4 P 0 8 0;1=1
P 4.10816004 1.98121998 4 P 0 8 0;1=1
P 4.14753002 1.98121998 4 P 0 8 0;1=1
P 4.61996004 2.1387 4 P 0 8 0;1=1
P 4.6987 1.70563996 4 P 0 8 0;1=1
P 4.6987 1.66626998 4 P 0 8 0;1=1
P 1.45 3.59 6 P 0 8 0;1=0
P 1.56 3.165 6 P 0 8 0;1=2
P 1.56 3.205 6 P 0 8 0;1=0
P 0.72 3.463 6 P 0 8 0;1=2
P 0.42326004 3.4315 7 P 0 8 0;1=6
P 0.40553996 3.4008 7 P 0 8 0;1=6
P 0.2815 3.4315 7 P 0 8 0;1=6
P 0.26378002 3.4008 7 P 0 8 0;1=6
P 0.71 3.305 4 P 0 8 0;1=3
P 1.14 3.52 6 P 0 8 0;1=0
P 1.245 3.52 6 P 0 8 0;1=0
P 4.705 3.95 3 P 0 8 0;1=4
P 4.705 3.91 6 P 0 8 0;1=2
P 1.566 2.95 6 P 0 8 0;1=0
P 1.045 3.77 6 P 0 8 0;1=2
P 1.515 3.58 6 P 0 8 0;1=2
P 6.145 4.035 6 P 0 8 0;1=0
P 1.37 3.64 6 P 0 8 0;1=2
P 1.667 3.438 6 P 0 8 0;1=2
P 1.591 3.546 6 P 0 8 0;1=2
P 1.13 3.445 6 P 0 8 0;1=2
P 0.95 3.445 6 P 0 8 0;1=2
P 2.19 3.488 6 P 0 8 0;1=2
P 2.192 3.388 6 P 0 8 0;1=2
P 1.41916004 3.33916004 6 P 0 8 0;1=2
P 1.407 3.2 6 P 0 8 0;1=2
P 1.495 3.11033996 6 P 0 8 0;1=2
P 1.535 3.105 4 P 0 8 0;1=3
P 1.15253002 3.06246998 6 P 0 8 0;1=2
P 0.95 3.215 6 P 0 8 0;1=2
P 0.945 3.125 6 P 0 8 0;1=2
P 1.175 2.9 6 P 0 8 0;1=2
P 1.025 3.02 6 P 0 8 0;1=2
P 5.275 3.891 6 P 0 8 0;1=0
P 5.275 3.931 6 P 0 8 0;1=2
P 5.275 3.971 6 P 0 8 0;1=0
P 5.321 3.99 6 P 0 8 0;1=2
P 5.762 3.425 5 P 0 8 0;1=7
P 5.567 3.203 6 P 0 8 0;1=2
P 5.617 3.203 6 P 0 8 0;1=0
P 5.62 3.316 6 P 0 8 0;1=2
P 5.625 3.261 6 P 0 8 0;1=0
P 5.625 3.361 6 P 0 8 0;1=2
P 5.6 3.421 6 P 0 8 0;1=0
P 5.552 3.71141004 5 P 0 8 0;1=8
P 5.552 3.74683996 5 P 0 8 0;1=8
P 5.552 3.78226998 5 P 0 8 0;1=8
P 5.552 3.67596998 5 P 0 8 0;1=8
P 5.52 3.78226998 5 P 0 8 0;1=8
P 5.52 3.74683996 5 P 0 8 0;1=8
P 5.52 3.71141004 5 P 0 8 0;1=8
P 5.52 3.67596998 5 P 0 8 0;1=8
P 0.978 3.918 4 P 0 8 0;1=3
P 0.928 3.961 6 P 0 8 0;1=2
P 0.968 3.961 6 P 0 8 0;1=2
P 0.968 4.021 6 P 0 8 0;1=2
P 0.928 4.021 6 P 0 8 0;1=0
P 0.928 4.081 6 P 0 8 0;1=2
P 0.968 4.081 6 P 0 8 0;1=0
P 0.928 4.141 6 P 0 8 0;1=0
P 0.968 4.141 6 P 0 8 0;1=2
P 0.603 3.951 6 P 0 8 0;1=0
P 0.643 3.956 6 P 0 8 0;1=2
P 0.603 4.011 6 P 0 8 0;1=2
P 0.643 4.016 6 P 0 8 0;1=0
P 0.603 4.071 6 P 0 8 0;1=0
P 0.643 4.076 6 P 0 8 0;1=2
P 0.603 4.131 6 P 0 8 0;1=2
P 0.643 4.136 6 P 0 8 0;1=0
P 0.854 3.942 6 P 0 8 0;1=2
P 0.807 3.942 6 P 0 8 0;1=2
P 0.76 3.942 6 P 0 8 0;1=2
P 0.713 3.942 6 P 0 8 0;1=2
P 0.76 4.042 6 P 0 8 0;1=2
P 0.76 3.992 6 P 0 8 0;1=2
P 0.713 3.992 6 P 0 8 0;1=2
P 0.713 4.042 6 P 0 8 0;1=2
P 0.713 4.092 6 P 0 8 0;1=2
P 0.76 4.092 6 P 0 8 0;1=2
P 0.807 4.092 6 P 0 8 0;1=2
P 0.807 4.042 6 P 0 8 0;1=2
P 0.807 3.992 6 P 0 8 0;1=2
P 0.854 3.992 6 P 0 8 0;1=2
P 0.854 4.042 6 P 0 8 0;1=2
P 0.854 4.092 6 P 0 8 0;1=2
P 0.74 1.005 6 P 0 8 0;1=0
P 0.79 1.005 6 P 0 8 0;1=0
P 0.84 1.005 6 P 0 8 0;1=0
P 1.568 3.011 6 P 0 8 0;1=0
P 1.738 3.241 6 P 0 8 0;1=0
P 1.765 2.9 6 P 0 8 0;1=0
P 1.78 3.095 6 P 0 8 0;1=0
P 1.795 2.946 6 P 0 8 0;1=0
P 5.2 0.87 6 P 0 8 0;1=0
P 4.47 3.21998002 6 P 0 8 0;1=0
P 4.385 3.645 6 P 0 8 0;1=0
P 0.78 3.305 4 P 0 8 0;1=3
P 1.03 3.515 6 P 0 8 0;1=0
P 1.19 3.52 6 P 0 8 0;1=0
P 0.95 2.915 4 P 0 8 0;1=3
P 0.945 2.99 4 P 0 8 0;1=3
P 0.885 3.03 4 P 0 8 0;1=3
P 0.875 2.955 4 P 0 8 0;1=3
P 0.795 3.085 4 P 0 8 0;1=3
P 0.55 3.36 6 P 0 8 0;1=0
P 0.3701 3.4008 7 P 0 8 0;1=6
P 0.55 3.554 6 P 0 8 0;1=0
P 0.31693996 3.4315 7 P 0 8 0;1=6
P 5.92 1.57063002 6 P 0 8 0;1=0
P 6.22 1.57 6 P 0 8 0;1=0
P 5.92 1.46 6 P 0 8 0;1=0
P 6.22 1.465 6 P 0 8 0;1=0
P 5.92 1.68 6 P 0 8 0;1=0
P 6.22035 1.67063002 6 P 0 8 0;1=0
P 5.92 1.78 6 P 0 8 0;1=0
P 6.22 1.755 6 P 0 8 0;1=0
P 6.09423996 4.13778996 6 P 0 8 0;1=0
P 3.51 3.08 6 P 0 8 0;1=0
P 1.025 2.9 6 P 0 8 0;1=2
P 4.42311004 1.94185 4 P 0 8 0;1=1
P 3.46 3.065 6 P 0 8 0;1=0
P 1.125 2.9 6 P 0 8 0;1=2
P 4.42311004 1.90248002 4 P 0 8 0;1=1
P 3.035 1.64 6 P 0 8 0;1=2
P 3.445 2.65 4 P 0 8 0;1=3
P 1.1288 0.7302 5 P 0 8 0;1=7
P 3.075 1.605 6 P 0 8 0;1=2
P 3.365 2.95 3 P 0 8 0;1=4
P 0.755 0.62 4 P 0 8 0;1=3
P 0.715 0.77 6 P 0 8 0;1=0
P 0.83 3.445 6 P 0 8 0;1=0
P 0.795 3.485 6 P 0 8 0;1=0
P 0.83 3.525 6 P 0 8 0;1=0
P 0.951 3.519 6 P 0 8 0;1=0
P 0.82951004 3.2794 6 P 0 8 0;1=0
P 0.79 3.155 6 P 0 8 0;1=0
P 0.78635 3.24491998 6 P 0 8 0;1=0
P 1.26 3.18 6 P 0 8 0;1=0
P 1.295 3.28 6 P 0 8 0;1=0
P 1.075 3.02 6 P 0 8 0;1=0
P 1.125 3.02 6 P 0 8 0;1=0
P 1.073 3.825 4 P 0 8 0;1=9
P 0.703 3.575 4 P 0 8 0;1=9
P 0.35238002 3.4315 7 P 0 8 0;1=6
P 0.33466004 3.4008 7 P 0 8 0;1=6
P 0.735 3.575 4 P 0 8 0;1=9
P 1.105 3.825 4 P 0 8 0;1=9
P 0.38781998 3.4315 7 P 0 8 0;1=6
P 0.29921998 3.4008 7 P 0 8 0;1=6
P 0.995 3.7 4 P 0 8 0;1=3
P 4.285 3.46 6 P 0 8 0;1=2
P 2.15 3.438 6 P 0 8 0;1=0
P 2.05 3.538 6 P 0 8 0;1=0
P 2.05 3.488 6 P 0 8 0;1=0
P 1.29 3.215 6 P 0 8 0;1=2
P 1.0541 3.185 6 P 0 8 0;1=0
P 1.3 3.49663996 6 P 0 8 0;1=2
P 1.04018996 3.47425 6 P 0 8 0;1=2
P 4.205 3.66 6 P 0 8 0;1=0
P 0.975 3.41 6 P 0 8 0;1=2
P 4.225 3.545 6 P 0 8 0;1=0
P 1.015 3.41 6 P 0 8 0;1=2
P 3.95 3.6 6 P 0 8 0;1=0
P 0.835 3.6 6 P 0 8 0;1=2
P 3.95 3.7 6 P 0 8 0;1=0
P 0.915 3.595 6 P 0 8 0;1=2
P 4.1184 3.5362 6 P 0 8 0;1=2
P 4.085 3.11 6 P 0 8 0;1=0
P 4.51 3.065 6 P 0 8 0;1=2
P 4.33381998 3.60466004 6 P 0 8 0;1=0
P 4.34 3.28 6 P 0 8 0;1=2
P 4.335 3.665 6 P 0 8 0;1=0
P 4.09 3.71338996 6 P 0 8 0;1=0
P 3.38 1.025 6 P 0 8 0;1=2
P 4.585 0.865 6 P 0 8 0;1=0
P 0.62 3.235 6 P 0 8 0;1=2
P 3.925 3.239 6 P 0 8 0;1=0
P 0.825 3.39 6 P 0 8 0;1=2
P 0.795 3.4179 6 P 0 8 0;1=2
P 3.795 3.758 6 P 0 8 0;1=0
P 3.62 1.28 6 P 0 8 0;1=2
P 5.195 0.755 6 P 0 8 0;1=0
P 4.96 0.85 6 P 0 8 0;1=2
P 0.66 3.185 6 P 0 8 0;1=2
P 3.62 1.235 6 P 0 8 0;1=2
P 5.195 0.815 6 P 0 8 0;1=0
P 4.937 0.79161004 6 P 0 8 0;1=2
P 0.66 3.235 6 P 0 8 0;1=2
P 4.205 3.81 6 P 0 8 0;1=2
P 5.814 2.821 5 P 0 8 0;1=7
P 4.19 3.735 6 P 0 8 0;1=2
P 5.814 2.721 5 P 0 8 0;1=7
P 3.895 3.7 6 P 0 8 0;1=2
P 5.815 3.021 5 P 0 8 0;1=7
P 4.135 3.735 6 P 0 8 0;1=2
P 5.814 2.621 5 P 0 8 0;1=7
P 2.3 3.475 6 P 0 8 0;1=2
P 5.045 3.405 6 P 0 8 0;1=2
P 6.33 2.67 5 P 0 8 0;1=7
P 1.35 3.12 6 P 0 8 0;1=2
P 2.255 3.475 6 P 0 8 0;1=2
P 5.09 3.405 6 P 0 8 0;1=2
P 6.33 2.865 6 P 0 8 0;1=0
P 1.46 3.34 6 P 0 8 0;1=2
P 4.575 2.235 6 P 0 8 0;1=2
P 4.50185 1.94185 4 P 0 8 0;1=1
P 4.705 0.825 6 P 0 8 0;1=0
P 4.575 2.275 6 P 0 8 0;1=2
P 4.38373996 1.98121998 4 P 0 8 0;1=1
P 4.755 0.825 6 P 0 8 0;1=0
P 1.26 0.72 6 P 0 8 0;1=0
P 4.6987 1.82373996 4 P 0 8 0;1=1
P 0.842 0.75 6 P 0 8 0;1=0
P 4.73806998 1.82373996 4 P 0 8 0;1=1
P 4.10816004 1.90248002 4 P 0 8 0;1=5
P 3.73648996 1.85735 6 P 0 8 0;1=2
P 4.10816004 1.82373996 4 P 0 8 0;1=1
P 4.345 3.02 6 P 0 8 0;1=2
P 4.075 3.005 6 P 0 8 0;1=2
P 3.925 3.291 6 P 0 8 0;1=0
P 4.14753002 1.82373996 4 P 0 8 0;1=1
P 4.39 3.02 6 P 0 8 0;1=2
P 4.13 3.005 6 P 0 8 0;1=2
P 3.795 3.81 6 P 0 8 0;1=0
P 4.615 3.11 6 P 0 8 0;1=2
P 4.6987 1.90248002 4 P 0 8 0;1=1
P 4.4 3.325 6 P 0 8 0;1=0
P 4.615 2.68408996 6 P 0 8 0;1=2
P 4.15 2.468 6 P 0 8 0;1=2
P 6.22 1.415 6 P 0 8 0;1=0
P 4.685 2.7 6 P 0 8 0;1=2
P 4.209 2.468 6 P 0 8 0;1=2
P 4.34436998 2.1387 4 P 0 8 0;1=1
P 6.22 1.516 6 P 0 8 0;1=0
P 4.975 2.26 6 P 0 8 0;1=2
P 4.093 2.468 6 P 0 8 0;1=2
P 6.22 1.62 6 P 0 8 0;1=0
P 4.925 2.26 6 P 0 8 0;1=0
P 4.037 2.468 6 P 0 8 0;1=2
P 6.22 1.815 6 P 0 8 0;1=0
P 5.92 1.41 6 P 0 8 0;1=0
P 5.09 2.155 6 P 0 8 0;1=2
P 3.801 2.468 6 P 0 8 0;1=2
P 4.10816004 2.09933002 4 P 0 8 0;1=1
P 5.92 1.515 6 P 0 8 0;1=0
P 5.135 2.155 6 P 0 8 0;1=2
P 3.86 2.468 6 P 0 8 0;1=2
P 4.14753002 2.09933002 4 P 0 8 0;1=1
P 5.92 1.63 6 P 0 8 0;1=0
P 5.115 2.065 6 P 0 8 0;1=2
P 3.919 2.468 6 P 0 8 0;1=2
P 5.92 1.73 6 P 0 8 0;1=0
P 5.13 2.105 6 P 0 8 0;1=2
P 3.978 2.468 6 P 0 8 0;1=2
P 4.685 2.645 6 P 0 8 0;1=2
P 4.1 3.38 6 P 0 8 0;1=0
P 4.53 2.5 6 P 0 8 0;1=2
P 3.9 3.385 6 P 0 8 0;1=0
P 4.485 3.115 6 P 0 8 0;1=0
P 4.575 2.374 6 P 0 8 0;1=2
P 4.485 2.5 6 P 0 8 0;1=2
P 4.29441998 3.10075 6 P 0 8 0;1=0
P 4.61 2.345 6 P 0 8 0;1=2
P 4.54 3.125 6 P 0 8 0;1=0
P 4.085 3.21998002 6 P 0 8 0;1=0
P 4.35 2.505 6 P 0 8 0;1=2
P 5.365 0.79 6 P 0 8 0;1=0
P 5.365 0.845 6 P 0 8 0;1=0
P 4.0661 3.5341 6 P 0 8 0;1=0
P 3.83 3.466 5 P 0 8 0;1=7
P 4.35143002 3.06643002 6 P 0 8 0;1=2
P 3.7 3.325 6 P 0 8 0;1=0
P 3.5825 3.4005 3 P 0 8 0;1=4
P 4.33 3.1432 6 P 0 8 0;1=2
P 3.83 3.235 6 P 0 8 0;1=0
P 4.085 3.165 6 P 0 8 0;1=2
P 3.415 3.335 3 P 0 8 0;1=4
P 0.74 1.3 6 P 0 8 0;1=2
P 1.26 0.62 5 P 0 8 0;1=7
P 0.785 0.8225 6 P 0 8 0;1=2
P 0.695 1.3 6 P 0 8 0;1=2
P 1.26 0.67 5 P 0 8 0;1=7
P 0.76321004 0.783 6 P 0 8 0;1=2
P 3.32 3.015 4 P 0 8 0;1=3
P 3.24 3.01 4 P 0 8 0;1=3
P 0.606 1.57 6 P 0 8 0;1=0
P 0.835 1.73 6 P 0 8 0;1=0
P 0.355 3.27 6 P 0 8 0;1=0
P 0.28 3.27 6 P 0 8 0;1=0
P 0.13 3.187 6 P 0 8 0;1=0
P 0.69023002 1.98523996 6 P 0 8 0;1=2
P 0.125 2.195 6 P 0 8 0;1=0
P 0.69 1.93 6 P 0 8 0;1=2
P 0.125 2.145 6 P 0 8 0;1=0
P 0.69 1.875 6 P 0 8 0;1=2
P 0.125 2.045 6 P 0 8 0;1=0
P 0.13 2.73326998 6 P 0 8 0;1=0
P 0.287 2.743 6 P 0 8 0;1=0
P 0.125 2.615 6 P 0 8 0;1=0
P 0.735 1.19 6 P 0 8 0;1=2
P 0.125 1.06 6 P 0 8 0;1=0
P 0.68 1.19 6 P 0 8 0;1=2
P 0.125 1.01 6 P 0 8 0;1=0
P 0.675 1.145 6 P 0 8 0;1=2
P 0.125 0.91 6 P 0 8 0;1=0
P 0.125 1.62 6 P 0 8 0;1=0
P 0.13 1.57 6 P 0 8 0;1=0
P 0.1362 1.4872 6 P 0 8 0;1=0
P 2.937 3.173 6 P 0 8 0;1=0
P 3.01 3.17 6 P 0 8 0;1=2
P 0.896 2.489 3 P 0 8 0;1=4
P 4.31168996 4.01168996 3 P 0 8 0;1=4
P 4.319 3.922 3 P 0 8 0;1=4
P 4.5 4.115 6 P 0 8 0;1=0
P 1.315 2.905 5 P 0 8 0;1=8
P 2.932 3.295 5 P 0 8 0;1=8
P 0.915 1.4 6 P 0 8 0;1=2
P 1.42 0.69535 5 P 0 8 0;1=7
P 4.5 4.165 6 P 0 8 0;1=0
P 1.36 2.905 5 P 0 8 0;1=8
P 2.896 3.301 5 P 0 8 0;1=8
P 0.965 1.4 6 P 0 8 0;1=2
P 1.4207 0.779 5 P 0 8 0;1=7
P 4.65933002 2.02058996 4 P 0 8 0;1=5
P 4.33 3.535 6 P 0 8 0;1=2
P 4.44 4.065 3 P 0 8 0;1=4
P 4.61996004 2.05996004 4 P 0 8 0;1=1
P 4.395 3.415 5 P 0 8 0;1=8
P 4.44 4.115 3 P 0 8 0;1=4
P 4.61996004 2.09933002 4 P 0 8 0;1=1
P 4.425 3.36088996 5 P 0 8 0;1=8
P 0.638 2.74 5 P 0 8 0;1=8
P 0.825 2.305 3 P 0 8 0;1=4
P 0.755 2.825 5 P 0 8 0;1=8
P 0.795 2.345 3 P 0 8 0;1=4
P 5.97613002 4.13778996 6 P 0 8 0;1=0
P 5.90748002 4.18725 6 P 0 8 0;1=0
P 4.06878996 2.02058996 4 P 0 8 0;1=1
P 0.905 1.935 6 P 0 8 0;1=0
P 3.99005 2.05996004 4 P 0 8 0;1=1
P 0.945 1.97 6 P 0 8 0;1=0
P 4.02941998 2.05996004 4 P 0 8 0;1=1
P 0.905 1.885 6 P 0 8 0;1=0
P 0.63 2.15 6 P 0 8 0;1=2
P 3.95066998 2.02058996 4 P 0 8 0;1=1
P 0.985 2.185 6 P 0 8 0;1=0
P 0.287 2.62508002 6 P 0 8 0;1=2
P 0.43 2.555 6 P 0 8 0;1=0
P 3.95066998 1.98121998 4 P 0 8 0;1=1
P 0.63 2.105 6 P 0 8 0;1=2
P 0.99 2.015 6 P 0 8 0;1=2
P 0.242 2.62508002 6 P 0 8 0;1=0
P 3.99005 1.98121998 4 P 0 8 0;1=1
P 0.63 2.06 6 P 0 8 0;1=2
P 0.99 1.975 6 P 0 8 0;1=2
P 4.02941998 1.82373996 4 P 0 8 0;1=1
P 0.935 1.3 6 P 0 8 0;1=0
P 3.95066998 1.90248002 4 P 0 8 0;1=1
P 0.87 1.255 6 P 0 8 0;1=0
P 3.95066998 1.86311004 4 P 0 8 0;1=1
P 0.935 1.25 6 P 0 8 0;1=0
P 4.06878996 1.94185 4 P 0 8 0;1=1
P 0.92 1.73 6 P 0 8 0;1=0
P 0.281 1.48798002 6 P 0 8 0;1=2
P 4.06878996 1.86311004 4 P 0 8 0;1=1
P 0.985 1.655 6 P 0 8 0;1=0
P 0.371 1.48798002 6 P 0 8 0;1=2
P 4.06878996 1.82373996 4 P 0 8 0;1=1
P 0.985 1.59 6 P 0 8 0;1=0
P 0.236 1.48798002 6 P 0 8 0;1=2
P 0.345 3.09 6 P 0 8 0;1=2
P 3.84091004 2.00091004 6 P 0 8 0;1=0
P 0.99 1.885 6 P 0 8 0;1=2
P 0.395 3.09 6 P 0 8 0;1=2
P 3.87193002 2.09933002 4 P 0 8 0;1=5
P 0.99 2.065 6 P 0 8 0;1=2
P 0.445 3.09 6 P 0 8 0;1=0
P 3.9113 2.09933002 4 P 0 8 0;1=1
P 0.975 2.14 6 P 0 8 0;1=2
P 0.53 2.005 6 P 0 8 0;1=0
P 0.552 2.535 6 P 0 8 0;1=0
P 0.455 1.825 6 P 0 8 0;1=0
P 0.16038996 1.85433002 8 P 0 8 0;1=10
P 0.46 2.195 6 P 0 8 0;1=0
P 0.16038996 2.4252 8 P 0 8 0;1=10
P 0.445 0.735 6 P 0 8 0;1=0
P 0.16038996 0.7126 8 P 0 8 0;1=10
P 0.455 1.0439 6 P 0 8 0;1=0
P 0.16038996 1.28346004 8 P 0 8 0;1=10
P 0.535 1.835 6 P 0 8 0;1=0
P 0.532 2.40186998 6 P 0 8 0;1=0
P 0.505 0.60228002 6 P 0 8 0;1=0
P 0.5374 1.26 6 P 0 8 0;1=0
P 0.48 2.005 6 P 0 8 0;1=0
P 0.485 2.525 6 P 0 8 0;1=0
P 0.515 0.835 6 P 0 8 0;1=0
P 0.475 1.405 6 P 0 8 0;1=0
P 6.335 0.965 6 P 0 8 0;1=0
P 6.335 1.02 6 P 0 8 0;1=0
P 6.335 1.08 6 P 0 8 0;1=0
P 2.085 3.017 5 P 0 8 0;1=7
P 2.135 3.017 5 P 0 8 0;1=7
P 2.185 3.017 5 P 0 8 0;1=7
P 6.0085 1.1235 6 P 0 8 0;1=0
P 2.22 3.3 5 P 0 8 0;1=7
P 5.8 1.048 4 P 0 8 0;1=3
P 4.34436998 2.02058996 4 P 0 8 0;1=1
P 5.285 2.99 5 P 0 8 0;1=8
P 3.125 3.075 6 P 0 8 0;1=2
P 4.34436998 2.17806998 4 P 0 8 0;1=1
P 2.017 3.279 4 P 0 8 0;1=3
P 0.636 2.915 4 P 0 8 0;1=3
P 4.38373996 2.17806998 4 P 0 8 0;1=1
P 2.97 3.105 6 P 0 8 0;1=0
P 5.91 2.785 6 P 0 8 0;1=0
P 5.91 2.615 5 P 0 8 0;1=7
P 5.91 2.915 6 P 0 8 0;1=0
P 5.91 2.715 6 P 0 8 0;1=0
P 0.54 2.135 6 P 0 8 0;1=2
P 0.67 1.09 6 P 0 8 0;1=0
P 4.61996004 1.66626998 4 P 0 8 0;1=1
P 0.45 2.13 6 P 0 8 0;1=2
P 4.6987 2.09933002 4 P 0 8 0;1=1
P 0.965 2.355 6 P 0 8 0;1=0
P 4.5806 1.70563996 4 P 0 8 0;1=1
P 0.735 1.125 6 P 0 8 0;1=0
P 0.48231998 2.6453 6 P 0 8 0;1=2
P 3.755 3.505 5 P 0 8 0;1=8
P 4.6987 2.1387 4 P 0 8 0;1=1
P 0.525 2.78 6 P 0 8 0;1=2
P 4.6 0.76 6 P 0 8 0;1=2
P 4.61996004 1.78436998 4 P 0 8 0;1=1
P 0.905 1.05 6 P 0 8 0;1=2
P 4.175 0.75 6 P 0 8 0;1=2
P 0.51765 0.966 3 P 0 8 0;1=4
P 2.078 0.8301 6 P 0 8 0;1=2
P 0.46 0.82 3 P 0 8 0;1=4
P 4.65933002 1.78436998 4 P 0 8 0;1=1
P 0.5413 1.525 6 P 0 8 0;1=0
P 4.61996004 1.70563996 4 P 0 8 0;1=1
P 0.625 1.005 6 P 0 8 0;1=2
P 4.65933002 1.70563996 4 P 0 8 0;1=1
P 0.935 1.105 6 P 0 8 0;1=0
P 0.4839 1.28311998 6 P 0 8 0;1=2
P 1.128 0.666 3 P 0 8 0;1=4
P 5.97613002 4.27558002 6 P 0 8 0;1=0
P 4.14753002 1.86311004 4 P 0 8 0;1=1
P 0.945 1.63 6 P 0 8 0;1=2
P 0.635 0.845 4 P 0 8 0;1=3
P 4.1869 1.86311004 4 P 0 8 0;1=1
P 0.975 1.72 6 P 0 8 0;1=2
P 0.644 0.7 4 P 0 8 0;1=3
P 0.555 0.59 6 P 0 8 0;1=0
P 3.935 3.91 5 P 0 8 0;1=7
P 0.835 1.885 6 P 0 8 0;1=2
P 3.885 3.91 5 P 0 8 0;1=7
P 0.835 1.93 6 P 0 8 0;1=2
P 3.985 3.91 5 P 0 8 0;1=7
P 0.835 1.78 6 P 0 8 0;1=2
P 0.645 1.295 4 P 0 8 0;1=3
P 4.1869 1.90248002 4 P 0 8 0;1=1
P 0.955 1.92 6 P 0 8 0;1=2
P 0.565 1.13 4 P 0 8 0;1=3
P 4.14753002 1.90248002 4 P 0 8 0;1=1
P 0.885 1.49 6 P 0 8 0;1=0
P 0.99 1.755 6 P 0 8 0;1=2
P 3.935 4 5 P 0 8 0;1=8
P 0.332 2.62508002 6 P 0 8 0;1=0
P 3.885 4 5 P 0 8 0;1=8
P 0.405 2.62 6 P 0 8 0;1=0
P 3.985 4 5 P 0 8 0;1=8
P 0.19 2.625 6 P 0 8 0;1=0
P 0.62 1.995 4 P 0 8 0;1=3
P 4.34436998 1.82373996 4 P 0 8 0;1=1
P 0.75 1.417 6 P 0 8 0;1=2
P 4.26563996 1.82373996 4 P 0 8 0;1=1
P 0.952 1.51 6 P 0 8 0;1=0
P 0.545 1.71 4 P 0 8 0;1=3
P 0.415 1.275 6 P 0 8 0;1=2
P 0.87 1.2 6 P 0 8 0;1=2
P 0.7558 4.19003996 5 P 0 8 0;1=7
P 3.98 4.185 5 P 0 8 0;1=8
P 0.465 1.33 6 P 0 8 0;1=2
P 0.87 1.3 6 P 0 8 0;1=2
P 0.705 4.19 5 P 0 8 0;1=7
P 4.03 4.185 5 P 0 8 0;1=8
P 0.41408996 1.32591004 6 P 0 8 0;1=2
P 0.89 1.105 6 P 0 8 0;1=2
P 0.805 4.205 6 P 0 8 0;1=0
P 3.93 4.185 5 P 0 8 0;1=8
P 0.647 2.517 4 P 0 8 0;1=3
P 4.22626998 1.82373996 4 P 0 8 0;1=1
P 0.939 1.552 6 P 0 8 0;1=2
P 0.575 2.265 4 P 0 8 0;1=3
P 4.22626998 1.86311004 4 P 0 8 0;1=1
P 0.957 2.275 6 P 0 8 0;1=0
P 4.168 4.24 5 P 0 8 0;1=8
P 0.855 4.205 5 P 0 8 0;1=8
P 0.15 2.79 6 P 0 8 0;1=0
P 0.326 1.487 6 P 0 8 0;1=2
P 0.09 2.86 6 P 0 8 0;1=0
P 0.9 4.205 5 P 0 8 0;1=8
P 4.22336998 4.24 5 P 0 8 0;1=8
P 0.416 1.48798002 6 P 0 8 0;1=2
P 0.09 2.79 6 P 0 8 0;1=0
P 0.98 4.2 5 P 0 8 0;1=8
P 4.14 4.19 5 P 0 8 0;1=8
P 0.191 1.48798002 6 P 0 8 0;1=2
P 4.10463002 3.83 5 P 0 8 0;1=7
P 0.33 3.145 6 P 0 8 0;1=2
P 4.05463002 3.83 5 P 0 8 0;1=7
P 0.43 3.145 6 P 0 8 0;1=2
P 4.15463002 3.83 5 P 0 8 0;1=7
P 0.18 3.145 6 P 0 8 0;1=2
P 0.869 2.672 6 P 0 8 0;1=2
P 0.871 2.713 3 P 0 8 0;1=4
P 0.686 2.74 5 P 0 8 0;1=8
P 0.64248002 2.58 6 P 0 8 0;1=2
P 0.736 2.525 5 P 0 8 0;1=8
P 0.714 2.329 6 P 0 8 0;1=2
P 3.429 2.468 3 P 0 8 0;1=4
P 3.51 2.33243002 6 P 0 8 0;1=2
P 3.278 2.468 3 P 0 8 0;1=4
P 3.243 2.547 3 P 0 8 0;1=4
P 3.385 2.135 4 P 0 8 0;1=3
P 3.24 2.36 3 P 0 8 0;1=4
P 3.285 2.38645 3 P 0 8 0;1=4
P 0.832 2.603 6 P 0 8 0;1=0
P 0.77963996 2.601 3 P 0 8 0;1=4
P 0.695 2.578 6 P 0 8 0;1=0
P 0.72 2.714 3 P 0 8 0;1=4
P 0.825 2.732 3 P 0 8 0;1=4
P 6.01953002 2.18853002 6 P 0 8 0;1=0
P 4.415 2.975 3 P 0 8 0;1=4
P 6.09423996 4.27558002 6 P 0 8 0;1=0
P 0.959 2.789 6 P 0 8 0;1=2
P 0.845 2.18 6 P 0 8 0;1=0
P 5.955 2.39 4 P 0 8 0;1=3
P 5.94153002 2.205 5 P 0 8 0;1=7
P 6.01901998 2.001 5 P 0 8 0;1=7
P 5.87 1.84 4 P 0 8 0;1=3
P 3.4593 2.17 5 P 0 8 0;1=7
P 3.44 2.12 6 P 0 8 0;1=0
P 4.34436998 1.94185 4 P 0 8 0;1=1
P 3.18 2.685 3 P 0 8 0;1=4
P 3.523 1.75 5 P 0 8 0;1=8
P 4.712 1.157 4 P 0 8 0;1=3
P 4.42311004 1.50878996 4 P 0 8 0;1=1
P 4.61996004 1.6269 4 P 0 8 0;1=3
P 4.29 1.235 4 P 0 8 0;1=3
P 4.38373996 1.46941998 4 P 0 8 0;1=1
P 4.15 1.235 4 P 0 8 0;1=3
P 4.34436998 1.50878996 4 P 0 8 0;1=1
P 5.035 1.49 4 P 0 8 0;1=3
P 4.65933002 1.58753002 4 P 0 8 0;1=1
P 4.185 1.17 4 P 0 8 0;1=3
P 4.34436998 1.46941998 4 P 0 8 0;1=1
P 4.816 1.258 4 P 0 8 0;1=3
P 4.665 1.104 4 P 0 8 0;1=3
P 4.38373996 1.3513 4 P 0 8 0;1=1
P 4.91 1.54 4 P 0 8 0;1=3
P 4.768 1.207 4 P 0 8 0;1=3
P 4.42311004 1.46941998 4 P 0 8 0;1=1
P 5.03 1.55 4 P 0 8 0;1=3
P 4.58058996 1.6269 4 P 0 8 0;1=1
P 4.828 1.103 4 P 0 8 0;1=3
P 4.42311004 1.43005 4 P 0 8 0;1=1
P 4.83 1.33 4 P 0 8 0;1=3
P 4.22 1.235 4 P 0 8 0;1=3
P 3.83128002 1.78371998 5 P 0 8 0;1=8
P 6.02558996 4.175 6 P 0 8 0;1=0
P 6.1437 4.175 6 P 0 8 0;1=0
P 3.87193002 1.86311004 4 P 0 8 0;1=1
P 4.14753002 2.05996004 4 P 0 8 0;1=1
P 5.83 2.97 6 P 0 8 0;1=2
P 5.89953002 2.366 5 P 0 8 0;1=7
P 3.61123996 3.49876004 3 P 0 8 0;1=4
P 4.54121998 1.94185 4 P 0 8 0;1=1
P 4.22626998 1.94185 4 P 0 8 0;1=1
P 1.96496998 0.76501998 5 P 0 8 0;1=7
P 4.1869 1.98121998 4 P 0 8 0;1=1
P 3.12 2.565 6 P 0 8 0;1=2
P 3.119 2.299 6 P 0 8 0;1=0
P 4.26563996 1.90248002 4 P 0 8 0;1=1
P 3.385 2.59 6 P 0 8 0;1=0
P 5.155 2.01 6 P 0 8 0;1=2
P 6.025 1.83 6 P 0 8 0;1=0
P 4.1869 2.05996004 4 P 0 8 0;1=1
P 4.34436998 1.90248002 4 P 0 8 0;1=1
P 2.554 2.901 6 P 0 8 0;1=0
P 4.75 1.63 4 P 0 8 0;1=5
P 3.205 1.7 6 P 0 8 0;1=0
P 4.775 1.705 6 P 0 8 0;1=2
P 4.84 1.855 6 P 0 8 0;1=0
P 4.58058996 1.82373996 4 P 0 8 0;1=1
P 4.65933002 1.86311004 4 P 0 8 0;1=1
P 4.815 1.93 6 P 0 8 0;1=0
P 4.885 3.46 6 P 0 8 0;1=2
P 4.61996004 1.86311004 4 P 0 8 0;1=1
P 4.83501004 3.46 6 P 0 8 0;1=0
P 3.125 2.254 6 P 0 8 0;1=2
P 4.26563996 1.86311004 4 P 0 8 0;1=5
P 3.12 2.69 6 P 0 8 0;1=2
P 4.565 3.055 6 P 0 8 0;1=2
P 4.3 3.81 6 P 0 8 0;1=0
P 1.3825 3.7225 5 P 0 8 0;1=8
P 5.905 3.015 5 P 0 8 0;1=7
P 5.41 0.96 4 P 0 8 0;1=3
P 4.85033002 1.74933996 6 P 0 8 0;1=2
P 4.54121998 1.78436998 4 P 0 8 0;1=1
P 5.26 2.955 6 P 0 8 0;1=2
P 3.625 0.92 4 P 0 8 0;1=9
P 6.19961004 2.27673996 4 P 0 8 0;1=9
P 3.657 0.92 4 P 0 8 0;1=9
P 6.19961004 2.24473996 4 P 0 8 0;1=9
P 3.3255 2.1355 6 P 0 8 0;1=0
P 3.35153002 2.17875 6 P 0 8 0;1=2
P 3.44 2.95 3 P 0 8 0;1=4
P 3.27923002 2.21576998 6 P 0 8 0;1=2
P 3.3435 2.82 3 P 0 8 0;1=4
P 4.46 2.94 6 P 0 8 0;1=0
P 4.47 2.83 6 P 0 8 0;1=0
P 5.995 1.165 6 P 0 8 0;1=2
P 3.106 3.26 6 P 0 8 0;1=2
P 3.222 3.385 5 P 0 8 0;1=8
P 3.106 3.35 5 P 0 8 0;1=8
P 1.959 3.325 6 P 0 8 0;1=2
P 3.222 3.205 5 P 0 8 0;1=8
P 3.49 2.955 6 P 0 8 0;1=2
P 3.98 3.365 6 P 0 8 0;1=2
P 3.7 3.37 6 P 0 8 0;1=2
P 3.55 3.37 6 P 0 8 0;1=2
P 4.175 3.37 6 P 0 8 0;1=2
P 3.71 3.26 6 P 0 8 0;1=2
P 3.55 3.28 5 P 0 8 0;1=8
P 3.414 3.235 6 P 0 8 0;1=2
P 3.41 3.04 6 P 0 8 0;1=2
P 3.548 2.856 5 P 0 8 0;1=8
P 3.5768 2.7178 6 P 0 8 0;1=2
P 3.395 2.82 6 P 0 8 0;1=2
P 3.58 2.615 4 P 0 8 0;1=3
P 3.485 2.6 6 P 0 8 0;1=2
P 3.525 2.6 6 P 0 8 0;1=2
P 3.335 2.589 6 P 0 8 0;1=2
P 3.24 2.2075 6 P 0 8 0;1=2
P 4.905 2.1675 6 P 0 8 0;1=2
P 4.85 2.02738996 6 P 0 8 0;1=2
P 4.965 1.975 6 P 0 8 0;1=2
P 3.49128002 1.86628002 6 P 0 8 0;1=2
P 4.65933002 1.66626998 4 P 0 8 0;1=1
P 3.795 2.375 6 P 0 8 0;1=2
P 3.99005 2.02058996 4 P 0 8 0;1=1
P 4.34436998 1.86311004 4 P 0 8 0;1=1
P 4.02941998 1.90248002 4 P 0 8 0;1=1
P 3.855 1.96153996 4 P 0 8 0;1=1
P 3.9113 1.86311004 4 P 0 8 0;1=1
P 4.06878996 1.78436998 4 P 0 8 0;1=1
P 4.1869 1.82373996 4 P 0 8 0;1=1
P 3.86 2.5925 6 P 0 8 0;1=2
P 3.758 2.552 6 P 0 8 0;1=2
P 4.209 2.59 6 P 0 8 0;1=2
P 4.65933002 2.09933002 4 P 0 8 0;1=1
P 4.54121998 2.05996004 4 P 0 8 0;1=1
P 4.50185 2.17806998 4 P 0 8 0;1=1
P 4.46248002 1.90248002 4 P 0 8 0;1=1
P 4.42311004 2.02058996 4 P 0 8 0;1=1
P 4.38373996 2.1387 4 P 0 8 0;1=1
P 4.26563996 1.98121998 4 P 0 8 0;1=1
P 4.22626998 2.09933002 4 P 0 8 0;1=1
P 4.14753002 1.94185 4 P 0 8 0;1=1
P 4.10816004 2.05996004 4 P 0 8 0;1=1
P 4.06878996 2.17806998 4 P 0 8 0;1=1
P 3.95066998 2.1387 4 P 0 8 0;1=1
P 4.6987 1.98121998 4 P 0 8 0;1=1
P 4.58058996 1.94185 4 P 0 8 0;1=1
P 4.73806998 1.86311004 4 P 0 8 0;1=1
P 4.61996004 1.82373996 4 P 0 8 0;1=1
P 4.50185 1.78436998 4 P 0 8 0;1=1
P 4.249 2.929 6 P 0 8 0;1=0
P 4.239 2.785 6 P 0 8 0;1=0
P 4.249 2.843 6 P 0 8 0;1=0
P 4.575 2.5 6 P 0 8 0;1=2
P 4.395 2.5 6 P 0 8 0;1=2
P 4.77 2.39 6 P 0 8 0;1=2
P 4.71 2.39 6 P 0 8 0;1=2
P 4.075 2.25 6 P 0 8 0;1=2
P 3.735 2.47 6 P 0 8 0;1=2
P 5.0395 1.335 6 P 0 8 0;1=2
P 4.97 1.75 6 P 0 8 0;1=0
P 4.96 1.63 6 P 0 8 0;1=2
P 6.22 1.27063002 6 P 0 8 0;1=2
P 3.839 3.846 6 P 0 8 0;1=2
P 4.384 3.824 6 P 0 8 0;1=2
P 4.95 3.46 6 P 0 8 0;1=2
P 5.94003002 1.87 6 P 0 8 0;1=2
P 6.379 1.169 6 P 0 8 0;1=2
P 6.105 1.905 6 P 0 8 0;1=2
P 5.92 1.27063002 6 P 0 8 0;1=2
P 5.88 0.965 6 P 0 8 0;1=2
P 6.47 1.08 6 P 0 8 0;1=2
P 5.19 3.075 6 P 0 8 0;1=2
P 5.375 3.04 6 P 0 8 0;1=2
P 5.41 2.815 6 P 0 8 0;1=2
P 5.544 2.675 6 P 0 8 0;1=2
P 6.1865 2.493 6 P 0 8 0;1=2
P 6.141 2.364 6 P 0 8 0;1=2
P 5.85 2.265 6 P 0 8 0;1=2
P 5.62 2.5487 6 P 0 8 0;1=2
P 5.42 2.9645 6 P 0 8 0;1=2
P 4.645 2.985 6 P 0 8 0;1=2
P 4.61 3.025 6 P 0 8 0;1=2
P 4.43 3.865 5 P 0 8 0;1=8
P 5.221 4.165 6 P 0 8 0;1=2
P 4.32 3.965 5 P 0 8 0;1=8
P 4.535 3.815 6 P 0 8 0;1=2
P 4.509 3.309 6 P 0 8 0;1=2
P 4.235 4.155 6 P 0 8 0;1=2
P 4.505 3.685 6 P 0 8 0;1=2
P 5.975 4.219 6 P 0 8 0;1=2
P 5.84 4.219 6 P 0 8 0;1=2
P 6.145 3.98 6 P 0 8 0;1=2
P 4.655 0.785 6 P 0 8 0;1=2
P 4.635 0.92 6 P 0 8 0;1=2
P 5.249 0.99 6 P 0 8 0;1=2
P 5.53 1.085 6 P 0 8 0;1=2
P 5.33 0.82 6 P 0 8 0;1=2
P 5.265 0.675 6 P 0 8 0;1=2
P 2.964 0.702 6 P 0 8 0;1=2
P 5.515 0.59596998 6 P 0 8 0;1=2
P 2.0477 0.6778 6 P 0 8 0;1=2
P 2.285 0.79 6 P 0 8 0;1=2
P 2.285 0.755 6 P 0 8 0;1=2
P 3.09 1.645 6 P 0 8 0;1=2
P 1.605 0.715 6 P 0 8 0;1=2
P 1.605 0.755 6 P 0 8 0;1=2
P 1.826 2.895 6 P 0 8 0;1=2
P 1.401 3.069 6 P 0 8 0;1=2
P 3.119 2.434 6 P 0 8 0;1=2
P 2.245 3.02 5 P 0 8 0;1=8
P 2.49 2.903 6 P 0 8 0;1=2
P 2.128 2.895 5 P 0 8 0;1=8
P 0.11976004 3.23523996 6 P 0 8 0;1=2
P 0.78 2.915 6 P 0 8 0;1=2
P 0.241 3.109 6 P 0 8 0;1=2
P 0.16 2.975 6 P 0 8 0;1=2
P 0.374 2.829 6 P 0 8 0;1=2
P 0.5459 2.6687 6 P 0 8 0;1=2
P 0.674 2.271 6 P 0 8 0;1=2
P 0.857 2.365 6 P 0 8 0;1=2
P 0.677 2.402 6 P 0 8 0;1=2
P 0.11963002 2.66436998 6 P 0 8 0;1=2
P 0.51451998 2.199 6 P 0 8 0;1=2
P 0.58 2.135 6 P 0 8 0;1=2
P 0.125 2.095 6 P 0 8 0;1=2
P 0.64445 1.68945 6 P 0 8 0;1=2
P 0.884 1.549 6 P 0 8 0;1=2
P 0.883 1.639 5 P 0 8 0;1=8
P 0.514 1.616 6 P 0 8 0;1=2
P 0.605 1.52 6 P 0 8 0;1=2
P 0.11263996 1.52263996 6 P 0 8 0;1=2
P 0.625 1.17 6 P 0 8 0;1=2
P 0.59 0.965 6 P 0 8 0;1=0
P 0.505 1.048 6 P 0 8 0;1=2
P 0.125 0.96 6 P 0 8 0;1=2
P 0.821 0.793 6 P 0 8 0;1=2
P 0.764 0.872 6 P 0 8 0;1=2
P 1.25 0.765 6 P 0 8 0;1=2
P 1.1133 0.5981 6 P 0 8 0;1=2
P 0.86 0.631 6 P 0 8 0;1=2
P 0.601 0.73 6 P 0 8 0;1=2
P 0.596 0.602 6 P 0 8 0;1=2
P 1.5327 0.584 6 P 0 8 0;1=2
P 4.6987 1.54816004 4 P 0 8 0;1=1
P 4.58058996 1.50878996 4 P 0 8 0;1=1
P 4.14753002 1.50878996 4 P 0 8 0;1=1
P 4.73806998 1.43005 4 P 0 8 0;1=1
P 4.61996004 1.39066998 4 P 0 8 0;1=1
P 4.50185 1.3513 4 P 0 8 0;1=1
P 4.46248002 1.46941998 4 P 0 8 0;1=1
P 4.38373996 1.31193002 4 P 0 8 0;1=1
P 4.34436998 1.43005 4 P 0 8 0;1=1
P 4.1869 1.39066998 4 P 0 8 0;1=1
P 4.06878996 1.3513 4 P 0 8 0;1=1
P 3.95066998 1.31193002 4 P 0 8 0;1=1
P 5.039 1.2869 6 P 0 8 0;1=2
P 5.0386 1.2415 6 P 0 8 0;1=2
P 4.625 1.17 6 P 0 8 0;1=2
P 4.485 1.005 6 P 0 8 0;1=2
P 3.69171998 1.02828002 6 P 0 8 0;1=2
P 3.6931 1.095 6 P 0 8 0;1=2
P 6.04 3.98 6 P 0 8 0;1=2
P 5.445 0.795 4 P 0 8 0;1=3
P 5.494 0.816 6 P 0 8 0;1=2
P 5.443 0.871 6 P 0 8 0;1=2
P 5.49 0.78223002 6 P 0 8 0;1=2
P 3.795 4.175 6 P 0 8 0;1=2
P 3.66 3.5085 6 P 0 8 0;1=2
P 3.105 3.21 6 P 0 8 0;1=2
P 5.55 4.02 6 P 0 8 0;1=2
P 5.01 2.635 6 P 0 8 0;1=0
P 5 2.78798996 5 P 0 8 0;1=7
P 5.226 2.762 5 P 0 8 0;1=7
P 3.775 2.235 6 P 0 8 0;1=2
P 3.775 2.265 6 P 0 8 0;1=0
P 3.775 2.21 6 P 0 8 0;1=2
P 3.775 2.185 6 P 0 8 0;1=2
P 4.42311004 1.78436998 4 P 0 8 0;1=1
P 4.46248002 1.70563996 4 P 0 8 0;1=1
P 4.34436998 1.78436998 4 P 0 8 0;1=1
P 4.22626998 1.78436998 4 P 0 8 0;1=1
P 4.22626998 1.66626998 4 P 0 8 0;1=1
P 4.14753002 1.78436998 4 P 0 8 0;1=1
P 4.02941998 1.78436998 4 P 0 8 0;1=1
P 5.765 0.98 4 P 0 8 0;1=3
P 1.385 3.875 5 P 0 8 0;1=7
P 5.31 2.855 6 P 0 8 0;1=2
P 4.608 2.942 6 P 0 8 0;1=2
P 4.25 3.81 6 P 0 8 0;1=2
P 0.99 2.60025 6 P 0 8 0;1=2
P 0.985 2.56661004 6 P 0 8 0;1=2
P 3.555 2.23 6 P 0 8 0;1=2
P 3.555 2.255 6 P 0 8 0;1=2
P 3.555 2.205 6 P 0 8 0;1=2
P 3.555 2.18 6 P 0 8 0;1=2
P 5.345 2.536 4 P 0 8 0;1=3
P 5.22 2.47 6 P 0 8 0;1=2
P 5.254 2.47 6 P 0 8 0;1=2
P 5.239 2.571 6 P 0 8 0;1=2
P 5.243 2.617 6 P 0 8 0;1=2
P 5.224 2.707 5 P 0 8 0;1=7
P 5.005 2.711 5 P 0 8 0;1=7
P 3.793 3.05 3 P 0 8 0;1=4
P 3.96981004 3.04481998 6 P 0 8 0;1=0
P 3.948 2.813 6 P 0 8 0;1=0
P 4.831 2.728 4 P 0 8 0;1=3
P 3.55 1.415 6 P 0 8 0;1=2
P 3.525 1.415 6 P 0 8 0;1=2
P 3.5 1.415 6 P 0 8 0;1=2
P 3.475 1.415 6 P 0 8 0;1=2
P 3.655 2.795 4 P 0 8 0;1=3
P 3.745 2.76 6 P 0 8 0;1=2
P 3.7 2.76 6 P 0 8 0;1=2
P 3.822 2.81 6 P 0 8 0;1=2
P 3.78 2.81 6 P 0 8 0;1=2
P 3.894 2.811 6 P 0 8 0;1=0
P 3.916 3.048 3 P 0 8 0;1=4
P 5.589 2.025 6 P 0 8 0;1=0
P 5.546 2.024 6 P 0 8 0;1=2
P 5.69943002 2.233 6 P 0 8 0;1=0
P 5.48158002 2.28033002 5 P 0 8 0;1=7
P 4.50185 1.66626998 4 P 0 8 0;1=1
P 4.42311004 1.66626998 4 P 0 8 0;1=1
P 4.38373996 1.70563996 4 P 0 8 0;1=1
P 4.26563996 1.70563996 4 P 0 8 0;1=1
P 4.14753002 1.66626998 4 P 0 8 0;1=1
P 4.1869 1.70563996 4 P 0 8 0;1=1
P 4.50185 1.58753002 4 P 0 8 0;1=1
P 4.46248002 1.6269 4 P 0 8 0;1=1
P 4.46248002 1.54816004 4 P 0 8 0;1=1
P 4.38373996 1.54816004 4 P 0 8 0;1=1
P 4.42311004 1.58753002 4 P 0 8 0;1=1
P 4.34436998 1.58753002 4 P 0 8 0;1=1
P 4.26563996 1.54816004 4 P 0 8 0;1=1
P 4.22626998 1.58753002 4 P 0 8 0;1=1
P 4.14753002 1.58753002 4 P 0 8 0;1=1
P 4.1869 1.6269 4 P 0 8 0;1=1
P 4.1869 1.54816004 4 P 0 8 0;1=1
P 5.145 1.57 6 P 0 8 0;1=2
P 5.145 1.54 6 P 0 8 0;1=2
P 5.145 1.44 6 P 0 8 0;1=0
P 5.145 1.48 6 P 0 8 0;1=2
P 5.145 1.51 6 P 0 8 0;1=2
P 5.76 2.465 4 P 0 8 0;1=3
P 4.2136 3.5997 3 P 0 8 0;1=4
P 3.755 3.092 6 P 0 8 0;1=2
P 3.99005 1.66626998 4 P 0 8 0;1=1
P 4.06878996 1.54816004 4 P 0 8 0;1=1
P 4.06878996 1.6269 4 P 0 8 0;1=1
P 4.02941998 1.58753002 4 P 0 8 0;1=1
P 3.99005 1.50878996 4 P 0 8 0;1=1
P 3.679 1.54228002 6 P 0 8 0;1=2
P 3.714 1.543 6 P 0 8 0;1=2
P 3.784 1.543 6 P 0 8 0;1=2
P 3.749 1.54228002 6 P 0 8 0;1=2
P 3.605 1.545 6 P 0 8 0;1=2
P 3.50085 1.543 6 P 0 8 0;1=2
P 3.53481998 1.54156998 6 P 0 8 0;1=2
P 3.57 1.542 6 P 0 8 0;1=2
P 5.4227 1.724 6 P 0 8 0;1=2
P 5.3977 1.724 6 P 0 8 0;1=2
P 5.58 1.615 4 P 0 8 0;1=3
P 5.3977 1.699 6 P 0 8 0;1=2
P 5.3977 1.749 6 P 0 8 0;1=2
P 5.4227 1.699 6 P 0 8 0;1=2
P 5.4352 1.7497 6 P 0 8 0;1=2
P 5.654 2.447 6 P 0 8 0;1=2
P 5.667 2.275 5 P 0 8 0;1=7
P 5.595 2.28 5 P 0 8 0;1=7
P 5.483 2.226 6 P 0 8 0;1=0
P 5.6695 2.2 6 P 0 8 0;1=2
P 5.771 2.279 5 P 0 8 0;1=7
P 5.789 2.366 6 P 0 8 0;1=2
P 5.6 2.4 6 P 0 8 0;1=2
P 5.6 4.01 4 P 0 8 0;1=3
P 5.55568996 3.88051004 3 P 0 8 0;1=4
P 5.765 2.197 6 P 0 8 0;1=0
P 5.71 2.179 6 P 0 8 0;1=2
P 5.41 2.164 6 P 0 8 0;1=0
P 5.458 2.165 6 P 0 8 0;1=2
P 5.465 2.405 6 P 0 8 0;1=2
P 5.53121998 2.27978996 5 P 0 8 0;1=7
P 3.817 0.924 5 P 0 8 0;1=7
P 4.25 0.877 6 P 0 8 0;1=0
P 5.495 0.694 5 P 0 8 0;1=7
P 5.49 0.635 6 P 0 8 0;1=0
P 5.725 0.60301004 5 P 0 8 0;1=7
P 5.686 0.76 5 P 0 8 0;1=7
P 5.7287 0.6757 5 P 0 8 0;1=7
P 5.38558002 4.13778996 6 P 0 8 0;1=0
P 5.485 4.11 6 P 0 8 0;1=0
P 5.725 4.135 6 P 0 8 0;1=0
P 5.6218 4.13778996 6 P 0 8 0;1=0
P 5.323 4.257 5 P 0 8 0;1=7
P 3.83 3.335 3 P 0 8 0;1=4
P 3.415 3.285 3 P 0 8 0;1=4
P 3.83 3.285 3 P 0 8 0;1=4
P 3.415 3.385 3 P 0 8 0;1=4
P 4.83871004 1.98241004 6 P 0 8 0;1=0
P 4.80288002 2.03788002 6 P 0 8 0;1=0
P 4.97 3.41 6 P 0 8 0;1=0
P 4.38373996 1.90248002 4 P 0 8 0;1=1
P 4.81 3.41 6 P 0 8 0;1=2
P 4.42311004 2.09933002 4 P 0 8 0;1=5
P 3.48863002 4.105 6 P 0 8 0;1=0
P 2.987 3.235 5 P 0 8 0;1=8
P 0.7595 1.642 5 P 0 8 0;1=7
P 2.987 3.27 5 P 0 8 0;1=8
P 0.761 1.544 5 P 0 8 0;1=7
P 4.54121998 1.82373996 4 P 0 8 0;1=1
P 4.79246004 1.78463996 6 P 0 8 0;1=0
P 4.54121998 2.17806998 4 P 0 8 0;1=5
P 0.955 1.455 6 P 0 8 0;1=0
P 1.512 0.75191004 6 P 0 8 0;1=2
P 1.8091 0.6339 5 P 0 8 0;1=7
P 1.459 0.752 5 P 0 8 0;1=8
P 0.905 1.445 6 P 0 8 0;1=2
P 2.40508002 0.731 5 P 0 8 0;1=8
P 4.06878996 1.66626998 3 P 0 8 0;1=11
P 2.40508002 0.699 5 P 0 8 0;1=8
P 4.02941998 1.66626998 3 P 0 8 0;1=11
P 4.4085 1.16598996 5 P 0 8 0;1=8
P 4.46248002 1.43005 3 P 0 8 0;1=11
P 4.3765 1.16598996 5 P 0 8 0;1=8
P 4.50185 1.43005 3 P 0 8 0;1=11
P 4.0485 1.16098996 5 P 0 8 0;1=8
P 4.06878996 1.50878996 3 P 0 8 0;1=11
P 4.0165 1.16098996 5 P 0 8 0;1=8
P 4.02941998 1.50878996 3 P 0 8 0;1=11
P 4.82 2.125 4 P 0 8 0;1=3
P 4.38373996 1.78436998 4 P 0 8 0;1=1
P 3.54663996 1.04706998 5 P 0 8 0;1=8
P 4.6987 1.46941998 3 P 0 8 0;1=11
P 3.51463996 1.04706998 5 P 0 8 0;1=8
P 4.73806998 1.46941998 3 P 0 8 0;1=11
P 3.44998996 1.085 5 P 0 8 0;1=8
P 4.73806998 1.39066998 3 P 0 8 0;1=11
P 3.41798996 1.085 5 P 0 8 0;1=8
P 4.73806998 1.3513 3 P 0 8 0;1=11
P 3.445 1.815 6 P 0 8 0;1=2
P 4.58058996 1.90248002 4 P 0 8 0;1=1
P 4.65933002 1.94185 4 P 0 8 0;1=1
P 4.785 3.46 6 P 0 8 0;1=0
P 3.9113 1.70563996 4 P 0 8 0;1=1
P 3.674 1.744 6 P 0 8 0;1=2
P 3.95066998 1.58753002 4 P 0 8 0;1=1
P 3.9113 1.54816004 4 P 0 8 0;1=1
P 3.9113 1.6269 4 P 0 8 0;1=1
P 3.95066998 1.43005 4 P 0 8 0;1=1
P 3.9113 1.46941998 4 P 0 8 0;1=1
P 3.82 1.42 6 P 0 8 0;1=0
P 3.79 1.41 6 P 0 8 0;1=2
P 3.74 1.41 6 P 0 8 0;1=2
P 3.765 1.41 6 P 0 8 0;1=2
P 4.54121998 1.6269 4 P 0 8 0;1=1
P 4.9097 1.385 5 P 0 8 0;1=7
P 4.54121998 1.66626998 4 P 0 8 0;1=1
P 4.84 1.66 6 P 0 8 0;1=0
P 4.81 1.725 6 P 0 8 0;1=0
P 3.375 1.194 5 P 0 8 0;1=8
P 4.5413 1.22166998 5 P 0 8 0;1=8
P 4.61996004 1.31193002 3 P 0 8 0;1=11
P 3.375 1.162 5 P 0 8 0;1=8
P 4.5733 1.22166998 5 P 0 8 0;1=8
P 4.65933002 1.31193002 3 P 0 8 0;1=11
P 5.3 4.065 4 P 0 8 0;1=3
P 4.10816004 1.70563996 4 P 0 8 0;1=1
P 4.365 2.33 6 P 0 8 0;1=2
P 4.38373996 2.02058996 4 P 0 8 0;1=5
P 4.38373996 2.05996004 4 P 0 8 0;1=1
P 4.485 2.375 6 P 0 8 0;1=0
P 4.38373996 2.09933002 4 P 0 8 0;1=1
P 4.54121998 1.58753002 4 P 0 8 0;1=1
P 4.9097 1.335 5 P 0 8 0;1=7
P 4.26563996 1.78436998 4 P 0 8 0;1=1
P 4.365 2.375 6 P 0 8 0;1=0
P 3.465 1.74 6 P 0 8 0;1=2
P 3.44 1.03 6 P 0 8 0;1=0
P 6.285 1.895 6 P 0 8 0;1=2
P 6.258 2.15873996 5 P 0 8 0;1=8
P 6.275 2.05373996 6 P 0 8 0;1=2
P 6.335 2.05906004 5 P 0 8 0;1=7
P 1.77 3.98 6 P 0 8 0;1=0
P 1.75 3.945 6 P 0 8 0;1=2
P 1.5315 3.9459 5 P 0 8 0;1=7
P 1.517 4.113 6 P 0 8 0;1=0
P 1.511 3.863 5 P 0 8 0;1=7
P 1.5153 4.063 5 P 0 8 0;1=7
P 1.521 3.993 5 P 0 8 0;1=7
P 1.579 3.874 6 P 0 8 0;1=0
P 1.585 4.052 6 P 0 8 0;1=2
P 1.435 4.18 6 P 0 8 0;1=2
P 1.522 4.163 5 P 0 8 0;1=7
P 1.4 4.01 6 P 0 8 0;1=2
P 5.14 3.74 6 P 0 8 0;1=2
P 5.175 3.74 6 P 0 8 0;1=2
P 5.18 3.825 6 P 0 8 0;1=2
P 5.675 4.03 6 P 0 8 0;1=2
P 1.56 3.29 6 P 0 8 0;1=2
P 1.56 3.25 6 P 0 8 0;1=2
P 3.245 2.955 6 P 0 8 0;1=2
P 3.21 2.955 6 P 0 8 0;1=2
P 3.175 2.955 6 P 0 8 0;1=2
P 2.59 3.445 6 P 0 8 0;1=2
P 2.55 3.445 6 P 0 8 0;1=2
P 2.51 3.445 6 P 0 8 0;1=2
P 2.47 3.445 6 P 0 8 0;1=2
P 2.2 3.96 6 P 0 8 0;1=2
P 2.25 3.96 4 P 0 8 0;1=3
P 1.351 4.126 6 P 0 8 0;1=2
P 2.165 3.96 6 P 0 8 0;1=2
P 2.155 3.925 6 P 0 8 0;1=2
P 2.19 3.925 6 P 0 8 0;1=2
P 3.23 4.015 6 P 0 8 0;1=0
P 3.2 3.985 6 P 0 8 0;1=2
P 5.9065 2.4568 6 P 0 8 0;1=2
P 3.745 4.185 4 P 0 8 0;1=3
P 3.47 3.912 6 P 0 8 0;1=0
P 3.69 4.135 4 P 0 8 0;1=3
P 3.48278996 4.05678002 6 P 0 8 0;1=2
P 3.476 3.988 6 P 0 8 0;1=0
P 3.437 4.099 6 P 0 8 0;1=0
P 3.598 3.977 6 P 0 8 0;1=2
P 3.477 3.816 6 P 0 8 0;1=0
P 3.405 3.916 6 P 0 8 0;1=2
P 5.68326004 3.712 6 P 0 8 0;1=0
P 5.686 3.807 6 P 0 8 0;1=0
P 5.50643002 4.009 3 P 0 8 0;1=4
P 5.686 3.76 6 P 0 8 0;1=0
P 5.675 3.865 6 P 0 8 0;1=0
P 5.718 3.965 4 P 0 8 0;1=3
P 6.05315 3.67518996 9 P 0 8 0;1=12
P 6.05315 3.50983996 9 P 0 8 0;1=13
P 6.05315 3.34448996 9 P 0 8 0;1=13
P 0.865 3.645 6 P 0 8 0;1=2
P 0.905 3.645 6 P 0 8 0;1=2
P 0.945 3.645 6 P 0 8 0;1=2
P 0.945 3.69 6 P 0 8 0;1=2
P 0.945 3.73 6 P 0 8 0;1=2
P 0.945 3.765 6 P 0 8 0;1=2
P 0.865 3.845 6 P 0 8 0;1=2
P 0.905 3.845 6 P 0 8 0;1=2
P 0.94 3.845 6 P 0 8 0;1=2
P 0.945 3.805 6 P 0 8 0;1=0
P 0.828 3.846 6 P 0 8 0;1=2
P 0.828 3.646 6 P 0 8 0;1=2
P 5.66 3.47 4 P 0 8 0;1=3
P 5.68 3.567 3 P 0 8 0;1=4
P 5.406 3.863 6 P 0 8 0;1=0
P 3.46 4.16 6 P 0 8 0;1=2
P 3.495 4.15 6 P 0 8 0;1=2
P 3.5 4.195 6 P 0 8 0;1=2
P 3.53 4.165 6 P 0 8 0;1=2
P 5.769 4.031 6 P 0 8 0;1=2
P 5.644 3.967 6 P 0 8 0;1=0
P 5.803 3.907 6 P 0 8 0;1=2
P 1.45 3.78 6 P 0 8 0;1=2
P 1.485 3.76 5 P 0 8 0;1=7
P 1.485 3.8 6 P 0 8 0;1=2
P 5.406 2.346 4 P 0 8 0;1=3
P 5.375 2.32 6 P 0 8 0;1=2
P 5.34 2.315 6 P 0 8 0;1=2
P 5.43 3.6 6 P 0 8 0;1=0
P 5.433 3.651 6 P 0 8 0;1=2
P 5.43 3.7 6 P 0 8 0;1=2
P 5.39 3.6 6 P 0 8 0;1=2
P 5.393 3.651 6 P 0 8 0;1=2
P 5.39 3.7 6 P 0 8 0;1=2
P 1.6055 4.134 6 P 0 8 0;1=2
P 1.60581998 4.1 6 P 0 8 0;1=2
P 1.606 4.174 5 P 0 8 0;1=7
P 1.636 3.786 6 P 0 8 0;1=2
P 1.591 3.826 6 P 0 8 0;1=2
P 1.633 3.829 5 P 0 8 0;1=7
P 3.408 4.152 6 P 0 8 0;1=2
P 3.363 4.192 6 P 0 8 0;1=2
P 3.363 4.152 6 P 0 8 0;1=2
P 3.363 4.232 6 P 0 8 0;1=0
P 3.393 3.877 6 P 0 8 0;1=2
P 3.393 3.84 6 P 0 8 0;1=2
P 3.392 3.803 6 P 0 8 0;1=2
P 3.607 4.062 6 P 0 8 0;1=2
P 1.352 4.084 6 P 0 8 0;1=0
P 1.95 0.5455 5 P 0 8 0;1=7
P 5.681 3.617 6 P 0 8 0;1=0
P 5.681 3.664 6 P 0 8 0;1=0
P 5.40318002 2.70436004 5 P 0 8 0;1=7
P 0.55921998 1.40543002 6 P 0 8 0;1=0
P 0.57 0.835 6 P 0 8 0;1=0
P 3.584 1.827 5 P 0 8 0;1=7
P 1.535 3.905 5 P 0 8 0;1=8
P 1.98135 0.365 5 P 0 8 0;1=8
P 1.7317 0.7084 6 P 0 8 0;1=0
P 1.91535 0.412 5 P 0 8 0;1=8
P 1.8039 0.7072 5 P 0 8 0;1=7
P 3.2271 1.90298996 4 P 0 8 0;1=9
P 3.45301004 1.89898996 4 P 0 8 0;1=9
P 3.2591 1.90298996 4 P 0 8 0;1=9
P 3.45301004 1.93098996 4 P 0 8 0;1=9
P 1.26066998 2.64043002 10 P 0 8 0;1=14
P 5.035 3.945 6 P 0 8 0;1=0
P 5.075 3.945 6 P 0 8 0;1=2
P 2.97771998 1.88693996 6 P 0 8 0;1=2
P 3.00995 1.87611004 6 P 0 8 0;1=2
P 2.86066998 2.64043002 10 P 0 8 0;1=14
P 2.105 0.305 5 P 0 8 0;1=8
P 2.235 0.5825 6 P 0 8 0;1=2
P 3.405 0.635 6 P 0 8 0;1=2
P 5.295 0.605 6 P 0 8 0;1=0
P 5.91 4.04 6 P 0 8 0;1=0
P 2.135 0.54 6 P 0 8 0;1=2
P 5.215 0.6 6 P 0 8 0;1=0
P 6.025 4.04 6 P 0 8 0;1=0
P 3.36 0.6106 6 P 0 8 0;1=2
P 0.96 2.41 6 P 0 8 0;1=2
P 0.68 2.355 6 P 0 8 0;1=2
P 2.38 3.45 6 P 0 8 0;1=2
P 1.41 3.795 6 P 0 8 0;1=2
P 3.445 3.613 6 P 0 8 0;1=2
P 3.365 3.613 6 P 0 8 0;1=0
P 3.25 3.63 6 P 0 8 0;1=2
P 3.325 3.613 6 P 0 8 0;1=2
P 3.405 3.613 6 P 0 8 0;1=2
P 3.48418002 3.613 6 P 0 8 0;1=2
P 3.645 4.135 6 P 0 8 0;1=2
P 3.655 3.059 6 P 0 8 0;1=2
P 3.614 3.099 6 P 0 8 0;1=2
P 3.614 3.058 6 P 0 8 0;1=2
P 3.614 3.015 6 P 0 8 0;1=2
P 5.236 2.811 6 P 0 8 0;1=2
P 4.3305 2.914 6 P 0 8 0;1=15
P 4.3815 2.838 6 P 0 8 0;1=15
P 4.29 2.74 4 P 0 8 0;1=3
P 4.456 2.783 6 P 0 8 0;1=2
P 4.355 2.745 6 P 0 8 0;1=2
P 4.346 2.783 6 P 0 8 0;1=2
P 4.4 2.785 6 P 0 8 0;1=2
P 4 2.655 6 P 0 8 0;1=2
P 5.022 2.407 6 P 0 8 0;1=2
P 4.923 2.408 6 P 0 8 0;1=2
P 4.972 2.406 6 P 0 8 0;1=2
P 4.971 2.447 6 P 0 8 0;1=2
P 5.2871 2.275 6 P 0 8 0;1=2
P 5.62533002 1.02001004 6 P 0 8 0;1=2
P 5.65933002 1.02 6 P 0 8 0;1=2
P 3.804 0.816 5 P 0 8 0;1=8
P 4.23 0.7295 6 P 0 8 0;1=2
P 2.31 0.715 6 P 0 8 0;1=2
P 2.31 0.68 6 P 0 8 0;1=2
P 2.595 0.547 6 P 0 8 0;1=2
P 1.87598002 0.289 5 P 0 8 0;1=8
P 1.86 0.33 5 P 0 8 0;1=8
P 1.895 0.33 5 P 0 8 0;1=8
P 1.87598002 0.369 5 P 0 8 0;1=8
P 0.705 3.82 6 P 0 8 0;1=2
P 0.665 3.82 6 P 0 8 0;1=2
P 0.625 3.82 6 P 0 8 0;1=2
P 0.625 3.78 6 P 0 8 0;1=0
P 0.625 3.73 6 P 0 8 0;1=0
P 0.66 3.65 6 P 0 8 0;1=2
P 0.695 3.65 6 P 0 8 0;1=2
P 0.73 3.65 6 P 0 8 0;1=2
P 0.625 3.69 6 P 0 8 0;1=2
P 0.625 3.65 6 P 0 8 0;1=2
P 3.51 2.37 6 P 0 8 0;1=2
P 0.29 2.915 6 P 0 8 0;1=0
P 0.28 2.965 6 P 0 8 0;1=0
P 0.285 3.02 6 P 0 8 0;1=0
P 2.977 3.351 3 P 0 8 0;1=4
P 3.36525 3.255 3 P 0 8 0;1=4
P 3.36525 3.205 3 P 0 8 0;1=4
P 1.8062 0.7789 5 P 0 8 0;1=7
P 3.073 0.613 5 P 0 8 0;1=7
P 2.54526998 0.339 5 P 0 8 0;1=8
P 2.527 0.44 3 P 0 8 0;1=4
P 5.73991004 4.27558002 6 P 0 8 0;1=0
P 5.38558002 4.27558002 6 P 0 8 0;1=0
P 5.50368996 4.27558002 6 P 0 8 0;1=0
P 5.6218 4.27558002 6 P 0 8 0;1=0
P 5.875 1.9 6 P 0 8 0;1=0
P 3.865 3.65 6 P 0 8 0;1=2
P 6.06901998 1.86 6 P 0 8 0;1=0
P 3.81 3.65 6 P 0 8 0;1=2
P 5.97 1.999 5 P 0 8 0;1=7
P 2.86066998 1.04042992 18 P 0 8 0;1=14
P 5.9645 2.1035 6 P 0 8 0;1=15
P 6.0155 2.0845 6 P 0 8 0;1=15
P 0.43705 3.51576004 16 P 0 8 0;1=16
P 0.43705 3.31655 16 P 0 8 0;1=16
P 0.24806998 3.47245 16 P 0 8 0;1=16
P 0.24806998 3.35985 16 P 0 8 0;1=16
P 0.24605994 3.4315 20 P 0 8 0;1=6
P 0.4587 3.4315 20 P 0 8 0;1=6
P 0.44097992 3.4008 20 P 0 8 0;1=6
P 0.22833996 3.4008 20 P 0 8 0;1=6
P 4.94093996 4.12008002 19 P 0 8 0;1=17
P 4.94093996 3.09646004 19 P 0 8 0;1=17
P 2.55906004 4.12008002 19 P 0 8 0;1=17
P 2.55906004 3.09646004 19 P 0 8 0;1=17
P 5.88778996 3.34448996 17 P 0 8 0;1=13
P 5.88778996 3.50983996 17 P 0 8 0;1=13
P 5.88778996 3.67518996 17 P 0 8 0;1=13
P 6.51581998 2.24803996 15 P 0 8 0;1=18
P 6.51581998 1.97243996 14 P 0 8 0;1=19
P 6.40951998 2.20866998 21 P 0 8 0;1=20
P 6.40951998 2.01180994 21 P 0 8 0;1=20
P 0.06038996 1.38345994 22 P 0 8 0;1=21
P 0.26038996 1.38345994 22 P 0 8 0;1=21
P 0.06038996 1.18345994 22 P 0 8 0;1=21
P 0.26038996 1.18345994 22 P 0 8 0;1=21
P 0.06038996 0.8126 22 P 0 8 0;1=21
P 0.26038996 0.8126 22 P 0 8 0;1=21
P 0.06038996 0.6126 22 P 0 8 0;1=21
P 0.26038996 0.6126 22 P 0 8 0;1=21
P 0.06038996 2.5252 22 P 0 8 0;1=21
P 0.26038996 2.5252 22 P 0 8 0;1=21
P 0.06038996 2.3252 22 P 0 8 0;1=21
P 0.26038996 2.3252 22 P 0 8 0;1=21
P 0.06038996 1.95433002 22 P 0 8 0;1=21
P 0.26038996 1.95433002 22 P 0 8 0;1=21
P 0.06038996 1.75433002 22 P 0 8 0;1=21
P 0.26038996 1.75433002 22 P 0 8 0;1=21
P 1.26066998 1.84042992 18 P 0 8 0;1=14
P 5.91901998 2.003 5 P 0 8 0;1=7
P 6.06901998 2.004 5 P 0 8 0;1=7
P 3.49 0.825 5 P 0 8 0;1=7
P 2.65966998 0.93443002 10 P 0 8 0;1=14
P 6.095 2.545 6 P 0 8 0;1=0
P 5.07 1.885 6 P 0 8 0;1=2
P 5.33 0.995 5 P 0 8 0;1=8
P 3.54 0.825 6 P 0 8 0;1=2
P 6.04 2.545 6 P 0 8 0;1=0
P 5.07 1.925 6 P 0 8 0;1=2
P 5.33 0.95 5 P 0 8 0;1=8
P 2.53966998 0.93443002 10 P 0 8 0;1=14
P 2.802 1.987 5 P 0 8 0;1=8
P 2.834 1.987 5 P 0 8 0;1=8
P 2.845 1.875 5 P 0 8 0;1=8
P 2.845 1.843 5 P 0 8 0;1=8
P 2.77866998 0.93443002 10 P 0 8 0;1=14
P 4.97 1.54 4 P 0 8 0;1=3
P 4.9806 1.855 6 P 0 8 0;1=0
P 1.26066998 1.04043002 10 P 0 8 0;1=14
P 0.724 2.646 6 P 0 8 0;1=0
P 0.758 2.743 3 P 0 8 0;1=4
P 3.235 2.63 4 P 0 8 0;1=3
P 3.275 2.32 3 P 0 8 0;1=4
P 3.24 2.275 6 P 0 8 0;1=0
P 3.305 2.65 4 P 0 8 0;1=3
P 3.375 2.65 4 P 0 8 0;1=3
P 3.326 2.466 3 P 0 8 0;1=4
P 2.1481 0.7881 5 P 0 8 0;1=7
P 5.08 1.105 6 P 0 8 0;1=2
P 5.225 1.145 6 P 0 8 0;1=2
P 5.132 0.66 6 P 0 8 0;1=2
P 2.0816 0.7399 6 P 0 8 0;1=2
P 2.03 0.75 5 P 0 8 0;1=7
P 5.08 1.155 6 P 0 8 0;1=2
P 5.08 1.055 6 P 0 8 0;1=2
P 2.0788 0.7874 5 P 0 8 0;1=7
P 2.29581998 0.48918002 4 P 0 8 0;1=3
P 2.633 0.522 5 P 0 8 0;1=8
P 3.455 0.87 6 P 0 8 0;1=2
P 0.9225 0.9775 6 P 0 8 0;1=2
P 4.82 0.835 6 P 0 8 0;1=0
P 0.8825 1.7725 6 P 0 8 0;1=2
P 3.405 0.87 6 P 0 8 0;1=2
P 0.965 0.98 6 P 0 8 0;1=2
P 0.91 1.815 6 P 0 8 0;1=0
P 4.78 0.78 6 P 0 8 0;1=2
P 4.42311004 1.86311004 3 P 0 8 0;1=11
P 3.65101004 1.88358996 4 P 0 8 0;1=9
P 4.46248002 1.86311004 3 P 0 8 0;1=11
P 3.65101004 1.91558996 4 P 0 8 0;1=9
P 3.065 1.695 4 P 0 8 0;1=3
P 2.98283996 1.75183996 6 P 0 8 0;1=2
P 2.225 3.245 6 P 0 8 0;1=2
P 4.595 2.62 6 P 0 8 0;1=2
P 4.025 3.08 6 P 0 8 0;1=2
P 0.62 3.07 6 P 0 8 0;1=2
P 5.865 1.125 6 P 0 8 0;1=0
P 5.865 1.07 6 P 0 8 0;1=0
P 2.265 3.34 6 P 0 8 0;1=2
P 4.57 2.585 6 P 0 8 0;1=2
P 4.02 3.03 6 P 0 8 0;1=2
P 0.645 2.9675 6 P 0 8 0;1=2
P 5.48828996 4.16328996 6 P 0 8 0;1=0
P 3.99005 1.90248002 4 P 0 8 0;1=1
P 5.55315 4.175 6 P 0 8 0;1=0
P 3.99005 1.86311004 4 P 0 8 0;1=1
P 5.67126004 4.175 6 P 0 8 0;1=0
P 3.95066998 1.82373996 4 P 0 8 0;1=1
P 5.78936998 4.175 6 P 0 8 0;1=0
P 3.9113 1.82373996 4 P 0 8 0;1=1
P 4.205 2.295 4 P 0 8 0;1=3
P 4.65933002 1.6269 4 P 0 8 0;1=3
P 4.254 2.296 4 P 0 8 0;1=3
P 4.23 2.354 4 P 0 8 0;1=3
P 4.915 1.485 4 P 0 8 0;1=3
P 4.65933002 1.54816004 4 P 0 8 0;1=1
P 3.94 2.235 4 P 0 8 0;1=3
P 4.85 1.54 4 P 0 8 0;1=3
P 4.149 2.298 4 P 0 8 0;1=3
P 4.161 2.354 4 P 0 8 0;1=3
P 3.75 2.1 4 P 0 8 0;1=3
P 4.975 1.485 4 P 0 8 0;1=3
P 4.58058996 1.58753002 4 P 0 8 0;1=1
P 3.8 2.1 4 P 0 8 0;1=3
P 4.73806998 1.54816004 4 P 0 8 0;1=3
P 3.9 2.325 4 P 0 8 0;1=3
P 4.73806998 1.50878996 4 P 0 8 0;1=3
P 3.83 2.325 4 P 0 8 0;1=3
P 0.846 2.489 3 P 0 8 0;1=4
P 3.28 3.065 6 P 0 8 0;1=2
P 0.796 2.489 3 P 0 8 0;1=4
P 3.325 3.065 6 P 0 8 0;1=2
P 5.03 3.546 3 P 0 8 0;1=4
P 4.935 3.59 3 P 0 8 0;1=4
P 4.67 3.555 4 P 0 8 0;1=3
P 4.885 3.59 5 P 0 8 0;1=7
P 4.70461998 3.69461998 3 P 0 8 0;1=4
P 4.50185 1.82373996 4 P 0 8 0;1=1
P 5.395 2.92 6 P 0 8 0;1=0
P 5.015 1.925 6 P 0 8 0;1=2
P 5.39976998 2.75123996 5 P 0 8 0;1=7
P 4.46248002 1.82373996 4 P 0 8 0;1=1
P 5.375 2.96606998 5 P 0 8 0;1=7
P 4.58058996 1.78436998 4 P 0 8 0;1=1
P 5.4525 2.563 5 P 0 8 0;1=7
P 3.545 0.6092 6 P 0 8 0;1=2
P 1.395 0.625 5 P 0 8 0;1=7
P 5.085 0.645 6 P 0 8 0;1=2
P 3.495 0.61 6 P 0 8 0;1=2
P 5.04 0.645 6 P 0 8 0;1=2
P 1.485 0.625 5 P 0 8 0;1=7
P 3.99005 1.6269 3 P 0 8 0;1=11
P 2.95835 0.385 4 P 0 8 0;1=9
P 3.95066998 1.6269 3 P 0 8 0;1=11
P 2.95835 0.353 4 P 0 8 0;1=9
P 3.9113 1.66626998 3 P 0 8 0;1=11
P 2.80086998 0.385 4 P 0 8 0;1=9
P 3.87193002 1.66626998 3 P 0 8 0;1=11
P 2.80086998 0.353 4 P 0 8 0;1=9
P 3.99005 1.70563996 3 P 0 8 0;1=11
P 2.64338996 0.385 4 P 0 8 0;1=9
P 3.95066998 1.70563996 3 P 0 8 0;1=11
P 2.64338996 0.353 4 P 0 8 0;1=9
P 3.9113 1.58753002 3 P 0 8 0;1=11
P 2.95835 0.481 4 P 0 8 0;1=9
P 2.95835 0.449 4 P 0 8 0;1=9
P 3.87193002 1.58753002 3 P 0 8 0;1=11
P 3.125 0.875 4 P 0 8 0;1=9
P 3.99005 1.54816004 3 P 0 8 0;1=11
P 3.14763002 0.85236998 4 P 0 8 0;1=9
P 3.95066998 1.54816004 3 P 0 8 0;1=11
P 2.81855 0.763 4 P 0 8 0;1=9
P 3.9113 1.50878996 3 P 0 8 0;1=11
P 2.85055 0.763 4 P 0 8 0;1=9
P 3.87193002 1.50878996 3 P 0 8 0;1=11
P 2.66706998 0.763 4 P 0 8 0;1=9
P 3.99005 1.46941998 3 P 0 8 0;1=11
P 2.69906998 0.763 4 P 0 8 0;1=9
P 3.95066998 1.46941998 3 P 0 8 0;1=11
P 2.47021998 0.763 4 P 0 8 0;1=9
P 3.9113 1.43005 3 P 0 8 0;1=11
P 2.50221998 0.763 4 P 0 8 0;1=9
P 3.87193002 1.43005 3 P 0 8 0;1=11
P 1.889 0.5496 6 P 0 8 0;1=2
P 2.435 0.4865 3 P 0 8 0;1=4
P 3.56 3.023 6 P 0 8 0;1=0
P 3.57 2.955 6 P 0 8 0;1=0
P 4.975 2.14 6 P 0 8 0;1=2
P 5.03005 0.99493996 6 P 0 8 0;1=0
P 5.638 3.907 6 P 0 8 0;1=0
P 1.8317 0.5639 5 P 0 8 0;1=7
P 2.68566998 1.12143002 11 P 0 8 0;1=22
P 2.68566998 2.55943002 11 P 0 8 0;1=22
P 1.46066998 2.68043002 11 P 0 8 0;1=22
P 1.43566998 1.06043002 11 P 0 8 0;1=22
P 6.40038996 0.65353996 13 P 0 8 0;1=23
P 0.29528002 3.73031004 13 P 0 8 0;1=23
P 0.29528002 0.36811004 13 P 0 8 0;1=23
P 6.40038996 4.17835 13 P 0 8 0;1=23
P 6.34055 3.34448996 12 P 0 8 0;1=24
P 6.34055 3.67518996 12 P 0 8 0;1=24
L 3.80999961 -1.25 3.80999961 -1.33 1 N 0 ;0
L 3.80999961 -1.33 3.8500003 -1.33 1 N 0 ;0
L 3.90999902 -1.25 3.90199892 -1.25266614 1 N 0 ;0
L 3.90199892 -1.25266614 3.8960002 -1.25933386 1 N 0 ;0
L 3.8960002 -1.25933386 3.89199921 -1.26733209 1 N 0 ;0
L 3.89199921 -1.26733209 3.8889999 -1.27800138 1 N 0 ;0
L 3.8889999 -1.27800138 3.8880001 -1.29000128 1 N 0 ;0
L 3.8880001 -1.29000128 3.8889999 -1.30200118 1 N 0 ;0
L 3.8889999 -1.30200118 3.89199921 -1.31266801 1 N 0 ;0
L 3.89199921 -1.31266801 3.8960002 -1.3206687 1 N 0 ;0
L 3.8960002 -1.3206687 3.90199892 -1.32733396 1 N 0 ;0
L 3.90199892 -1.32733396 3.90999902 -1.33 1 N 0 ;0
L 3.90999902 -1.33 3.91799911 -1.32733396 1 N 0 ;0
L 3.91799911 -1.32733396 3.9239997 -1.3206687 1 N 0 ;0
L 3.9239997 -1.3206687 3.92800069 -1.31266801 1 N 0 ;0
L 3.92800069 -1.31266801 3.931 -1.30200118 1 N 0 ;0
L 3.931 -1.30200118 3.9319998 -1.29000128 1 N 0 ;0
L 3.9319998 -1.29000128 3.931 -1.27800138 1 N 0 ;0
L 3.931 -1.27800138 3.92800069 -1.26733209 1 N 0 ;0
L 3.92800069 -1.26733209 3.9239997 -1.25933386 1 N 0 ;0
L 3.9239997 -1.25933386 3.91799911 -1.25266614 1 N 0 ;0
L 3.91799911 -1.25266614 3.90999902 -1.25 1 N 0 ;0
L 4.0020001 -1.33 4.0020001 -1.25 1 N 0 ;0
L 4.0020001 -1.25 3.96499892 -1.30733337 1 N 0 ;0
L 3.96499892 -1.30733337 4.01500098 -1.30733337 1 N 0 ;0
L 4.04 -1.35666585 4.1 -1.35666585 1 N 0 ;0
L 4.15599961 -1.29000128 4.17600079 -1.29000128 1 N 0 ;0
L 4.17600079 -1.29000128 4.17600079 -1.31400098 1 N 0 ;0
L 4.17600079 -1.31400098 4.1700003 -1.32200177 1 N 0 ;0
L 4.1700003 -1.32200177 4.1629999 -1.32733396 1 N 0 ;0
L 4.1629999 -1.32733396 4.1530002 -1.33 1 N 0 ;0
L 4.1530002 -1.33 4.14300049 -1.32733396 1 N 0 ;0
L 4.14300049 -1.32733396 4.1360002 -1.32200177 1 N 0 ;0
L 4.1360002 -1.32200177 4.12999961 -1.31400098 1 N 0 ;0
L 4.12999961 -1.31400098 4.12599862 -1.30466722 1 N 0 ;0
L 4.12599862 -1.30466722 4.12399911 -1.29400039 1 N 0 ;0
L 4.12399911 -1.29400039 4.12399911 -1.28466663 1 N 0 ;0
L 4.12399911 -1.28466663 4.12599862 -1.27666831 1 N 0 ;0
L 4.12599862 -1.27666831 4.12999961 -1.26733209 1 N 0 ;0
L 4.12999961 -1.26733209 4.1360002 -1.25933386 1 N 0 ;0
L 4.1360002 -1.25933386 4.14199892 -1.25400167 1 N 0 ;0
L 4.14199892 -1.25400167 4.14999902 -1.25 1 N 0 ;0
L 4.14999902 -1.25 4.15699941 -1.25 1 N 0 ;0
L 4.15699941 -1.25 4.16499951 -1.25266614 1 N 0 ;0
L 4.16499951 -1.25266614 4.171 -1.25800079 1 N 0 ;0
L 4.2070003 -1.33 4.2070003 -1.25 1 N 0 ;0
L 4.2070003 -1.25 4.25299961 -1.33 1 N 0 ;0
L 4.25299961 -1.33 4.25299961 -1.25 1 N 0 ;0
L 4.2880001 -1.33 4.2880001 -1.25 1 N 0 ;0
L 4.2880001 -1.25 4.30799951 -1.25 1 N 0 ;0
L 4.30799951 -1.25 4.31599961 -1.25400167 1 N 0 ;0
L 4.31599961 -1.25400167 4.3220001 -1.25933386 1 N 0 ;0
L 4.3220001 -1.25933386 4.32700089 -1.26733209 1 N 0 ;0
L 4.32700089 -1.26733209 4.331 -1.27666831 1 N 0 ;0
L 4.331 -1.27666831 4.3319998 -1.29000128 1 N 0 ;0
L 4.3319998 -1.29000128 4.331 -1.30333415 1 N 0 ;0
L 4.331 -1.30333415 4.32700089 -1.31266801 1 N 0 ;0
L 4.32700089 -1.31266801 4.3220001 -1.3206687 1 N 0 ;0
L 4.3220001 -1.3206687 4.31599961 -1.32600089 1 N 0 ;0
L 4.31599961 -1.32600089 4.30799951 -1.33 1 N 0 ;0
L 4.30799951 -1.33 4.2880001 -1.33 1 N 0 ;0
L 4.37099941 -1.26333297 4.377 -1.25533465 1 N 0 ;0
L 4.377 -1.25533465 4.3840003 -1.25133307 1 N 0 ;0
L 4.3840003 -1.25133307 4.39200039 -1.25 1 N 0 ;0
L 4.39200039 -1.25 4.4020001 -1.25266614 1 N 0 ;0
L 4.4020001 -1.25266614 4.40900049 -1.25933386 1 N 0 ;0
L 4.40900049 -1.25933386 4.411 -1.26733209 1 N 0 ;0
L 4.411 -1.26733209 4.4100003 -1.27533533 1 N 0 ;0
L 4.4100003 -1.27533533 4.40599931 -1.28200049 1 N 0 ;0
L 4.40599931 -1.28200049 4.3859999 -1.29533346 1 N 0 ;0
L 4.3859999 -1.29533346 4.377 -1.30466722 1 N 0 ;0
L 4.377 -1.30466722 4.37099941 -1.31800266 1 N 0 ;0
L 4.37099941 -1.31800266 4.3689999 -1.33 1 N 0 ;0
L 4.3689999 -1.33 4.411 -1.33 1 N 0 ;0
L 3.16 -0.655 3.16 -1.58 2 N 0 ;0
L 1.36 -0.655 1.36 -1.58 2 N 0 ;0
L 1.36 -1.58 5.06 -1.58 2 N 0 ;0
L 5.06 -1.58 5.06 -0.655 2 N 0 ;0
L 5.06 -0.655 1.36 -0.655 2 N 0 ;0
A 1.559 -1.33655 1.559 -1.33655 1.55268002 -1.33655 1 N 0 N;0
A 1.54775 -1.205 1.54775 -1.205 1.53883002 -1.205 1 N 0 N;0
A 1.54763996 -0.99775 1.54763996 -0.99775 1.53871998 -0.99775 1 N 0 N;0
A 1.54063996 -1.10118002 1.54063996 -1.10118002 1.52603996 -1.10118002 1 N 0 N;0
A 1.49695 -1.10118002 1.49695 -1.10118002 1.48656998 -1.10118002 1 N 0 N;0
A 1.45963996 -1.10118002 1.45963996 -1.10118002 1.4533 -1.10118002 1 N 0 N;0
A 1.52135 -0.98681004 1.52135 -0.98681004 1.51503002 -0.98681004 1 N 0 N;0
A 1.79433002 -1.43586998 1.79433002 -1.43586998 1.78798996 -1.43586998 1 N 0 N;0
A 1.79841004 -1.40261004 1.79841004 -1.40261004 1.78798996 -1.40261004 1 N 0 N;0
A 1.80255 -1.36311004 1.80255 -1.36311004 1.78798996 -1.36311004 1 N 0 N;0
A 1.80668996 -1.31528002 1.80668996 -1.31528002 1.78798996 -1.31528002 1 N 0 N;0
A 1.68013002 -1.37456004 1.68013002 -1.37456004 1.67378996 -1.37456004 1 N 0 N;0
A 1.69321998 -1.35033002 1.69321998 -1.35033002 1.6843 -1.35033002 1 N 0 N;0
A 1.7108 -1.31738996 1.7108 -1.31738996 1.69798002 -1.31738996 1 N 0 N;0
A 1.89666998 -1.31511004 1.89666998 -1.31511004 1.88383996 -1.31511004 1 N 0 N;0
A 1.88198996 -1.16876004 1.88198996 -1.16876004 1.85558996 -1.16876004 1 N 0 N;0
A 1.87928002 -1.27801998 1.87928002 -1.27801998 1.86343996 -1.27801998 1 N 0 N;0
A 1.86176998 -1.23075 1.86176998 -1.23075 1.84206004 -1.23075 1 N 0 N;0
A 1.80978996 -1.25916998 1.80978996 -1.25916998 1.78798996 -1.25916998 1 N 0 N;0
A 1.74681004 -1.16876004 1.74681004 -1.16876004 1.72041004 -1.16876004 1 N 0 N;0
A 1.67813002 -1.15513002 1.67813002 -1.15513002 1.65841998 -1.15513002 1 N 0 N;0
A 1.73018002 -1.27816004 1.73018002 -1.27816004 1.71433996 -1.27816004 1 N 0 N;0
A 1.75373002 -1.23081004 1.75373002 -1.23081004 1.73405 -1.23081004 1 N 0 N;0
A 1.65531004 -1.25255 1.65531004 -1.25255 1.63661998 -1.25255 1 N 0 N;0
A 1.69808996 -1.21291998 1.69808996 -1.21291998 1.67628996 -1.21291998 1 N 0 N;0
A 1.81438996 -1.1968 1.81438996 -1.1968 1.78798996 -1.1968 1 N 0 N;0
A 1.6269 -1.1749 1.6269 -1.1749 1.61106004 -1.1749 1 N 0 N;0
A 1.58461004 -1.19126004 1.58461004 -1.19126004 1.57178002 -1.19126004 1 N 0 N;0
A 1.5853 -1.31428002 1.5853 -1.31428002 1.57488996 -1.31428002 1 N 0 N;0
A 1.61735 -1.28638996 1.61735 -1.28638996 1.60276998 -1.28638996 1 N 0 N;0
A 1.88198996 -1.03361004 1.88198996 -1.03361004 1.85558996 -1.03361004 1 N 0 N;0
A 1.71881004 -1.10118002 1.71881004 -1.10118002 1.69238996 -1.10118002 1 N 0 N;0
A 1.65183002 -1.10118002 1.65183002 -1.10118002 1.63003002 -1.10118002 1 N 0 N;0
A 1.67801998 -1.04738996 1.67801998 -1.04738996 1.65831004 -1.04738996 1 N 0 N;0
A 1.74681004 -1.03361004 1.74681004 -1.03361004 1.72041004 -1.03361004 1 N 0 N;0
A 1.69811998 -0.98951004 1.69811998 -0.98951004 1.67631998 -0.98951004 1 N 0 N;0
A 1.81438996 -1.00556004 1.81438996 -1.00556004 1.78798996 -1.00556004 1 N 0 N;0
A 1.59258002 -1.10118002 1.59258002 -1.10118002 1.5739 -1.10118002 1 N 0 N;0
A 1.58451004 -1.01148996 1.58451004 -1.01148996 1.57168002 -1.01148996 1 N 0 N;0
A 1.62681004 -1.02773996 1.62681004 -1.02773996 1.61096998 -1.02773996 1 N 0 N;0
A 1.92148002 -1.21285 1.92148002 -1.21285 1.89968002 -1.21285 1 N 0 N;0
A 1.92148002 -0.98951004 1.92148002 -0.98951004 1.89968002 -0.98951004 1 N 0 N;0
A 1.80978996 -0.9432 1.80978996 -0.9432 1.78798996 -0.9432 1 N 0 N;0
A 1.80668996 -0.88708002 1.80668996 -0.88708002 1.78798996 -0.88708002 1 N 0 N;0
A 1.80255 -0.83923996 1.80255 -0.83923996 1.78798996 -0.83923996 1 N 0 N;0
A 1.8919 -0.88538002 1.8919 -0.88538002 1.87906998 -0.88538002 1 N 0 N;0
A 1.87838996 -0.92456998 1.87838996 -0.92456998 1.86255 -0.92456998 1 N 0 N;0
A 1.65531004 -0.94981004 1.65531004 -0.94981004 1.63661998 -0.94981004 1 N 0 N;0
A 1.73123002 -0.92378002 1.73123002 -0.92378002 1.71538996 -0.92378002 1 N 0 N;0
A 1.71216998 -0.88443996 1.71216998 -0.88443996 1.69935 -0.88443996 1 N 0 N;0
A 1.86225 -0.97178002 1.86225 -0.97178002 1.84253996 -0.97178002 1 N 0 N;0
A 1.75451998 -0.97123996 1.75451998 -0.97123996 1.73483996 -0.97123996 1 N 0 N;0
A 1.61741998 -0.91601004 1.61741998 -0.91601004 1.60283996 -0.91601004 1 N 0 N;0
A 1.5853 -0.88808996 1.5853 -0.88808996 1.57488996 -0.88808996 1 N 0 N;0
A 1.79841004 -0.79975 1.79841004 -0.79975 1.78798996 -0.79975 1 N 0 N;0
A 1.79433002 -0.76648002 1.79433002 -0.76648002 1.78798996 -0.76648002 1 N 0 N;0
A 1.92135 -1.36781004 1.92135 -1.36781004 1.91503996 -1.36781004 1 N 0 N;0
A 1.91096004 -1.34658002 1.91096004 -1.34658002 1.90203996 -1.34658002 1 N 0 N;0
A 2.19078996 -1.1806 2.26591004 -1.16473002 2.21741014 -1.12088169 1 N 0 N;0
A 2.15903002 -1.1402 2.19078996 -1.18061004 2.22093406 -1.12423278 1 N 0 N;0
A 2.05721004 -1.16178996 2.08853002 -1.16658996 2.08281614 -1.09929134 1 N 0 N;0
A 2.00546998 -1.13951998 2.03345 -1.17196004 2.07793927 -1.10530069 1 N 0 N;0
A 2.03346004 -1.17195 2.0847 -1.18461004 2.07891181 -1.09801299 1 N 0 N;0
A 2.0847 -1.18461998 2.14261004 -1.15663002 2.07348435 -1.08751378 1 N 0 N;0
A 2.08853996 -1.16658002 2.13313002 -1.14451998 2.06368967 -1.06025512 1 N 0 N;0
A 1.95808002 -1.25255 1.95808002 -1.25255 1.93938996 -1.25255 1 N 0 N;0
A 1.98775 -1.28635 1.98775 -1.28635 1.97316998 -1.28635 1 N 0 N;0
A 2.27411998 -1.11835 2.15906004 -1.11835 2.21658996 -1.11611998 1 N 0 N;0
L 2.25188002 -1.11418002 2.1807 -1.11418002 1 N 0 ;0
L 2.1807 -1.11418002 2.1807 -1.11398996 1 N 8191 ;0
A 2.25188996 -1.11398996 2.18071004 -1.11398996 2.2163 -1.1124 1 N 0 N;0
A 2.08028996 -1.03428996 2.02048996 -1.08258996 2.0798126 -1.09486801 1 N 0 N;0
A 2.13151998 -1.05146004 2.0803 -1.0343 2.0802999 -1.11932195 1 N 0 N;0
A 2.1315 -1.05146998 2.14175 -1.03951004 2.1356003 -1.04461171 1 N 0 N;0
A 2.14175 -1.03951004 2.08283002 -1.01613002 2.07772461 -1.11492805 1 N 0 N;0
A 2.08283996 -1.01611998 2.00698002 -1.05835 2.08064724 -1.10143169 1 N 0 N;0
L 2.27413002 -1.12868996 2.18073996 -1.12868996 1 N 0 ;0
A 2.18075 -1.12868996 2.19083002 -1.15751998 2.22417795 -1.12968307 1 N 0 N;0
A 2.19083002 -1.15753002 2.25311004 -1.15211004 2.21927195 -1.12381791 1 N 0 N;0
L 2.15903996 -1.1402 2.15903996 -1.11835 1 N 8191 ;0
A 2.02048996 -1.0826 2.05721998 -1.16181004 2.09087933 -1.0980811 1 N 0 N;0
A 2.00698996 -1.05836004 2.00546998 -1.13953002 2.09672953 -1.10063967 1 N 0 N;0
A 2.14258996 -1.15661004 2.13313996 -1.14453002 2.13544892 -1.15246004 1 N 0 N;0
A 1.95808002 -0.94981004 1.95808002 -0.94981004 1.93938996 -0.94981004 1 N 0 N;0
A 1.90183996 -0.8525 1.90183996 -0.8525 1.89291004 -0.8525 1 N 0 N;0
A 1.91108002 -0.82726998 1.91108002 -0.82726998 1.90473996 -0.82726998 1 N 0 N;0
L 2.32081004 -1.02041004 2.32081004 -1.17625 1 N 0 ;0
A 2.49568002 -1.15528996 2.47898002 -1.16443002 2.4882003 -1.1614502 1 N 0 N;0
A 2.47896998 -1.16443996 2.50283002 -1.18086004 2.51649242 -1.13546152 1 N 0 N;0
A 2.50281998 -1.18086998 2.54318002 -1.1834 2.52887392 -1.08843022 1 N 0 N;0
A 2.52306998 -1.16761004 2.52848996 -1.16771998 2.52673258 -1.12070098 1 N 0 N;0
A 2.49566004 -1.15528996 2.52306998 -1.1676 2.5255122 -1.12549094 1 N 0 N;0
A 2.37851998 -1.15753002 2.4408 -1.15211004 2.40696191 -1.12381791 1 N 0 N;0
A 2.45358002 -1.16471998 2.44078996 -1.1521 2.44541191 -1.16020689 1 N 0 N;0
A 2.37848002 -1.1806 2.4536 -1.16473002 2.4051001 -1.12088169 1 N 0 N;0
A 2.34673002 -1.1402 2.37848996 -1.18061004 2.40863406 -1.12423278 1 N 0 N;0
A 2.2659 -1.16471998 2.25311004 -1.1521 2.25773199 -1.16020689 1 N 0 N;0
A 2.3006 -1.17626004 2.3208 -1.17626004 2.3107 -1.17386841 1 N 0 N;0
L 2.30058996 -1.17625 2.30058996 -1.02033996 1 N 0 ;0
A 2.50836998 -1.10106004 2.54306004 -1.11513002 2.56106673 -1.02093386 1 N 0 N;0
A 2.51081004 -1.07948002 2.50836998 -1.10103996 2.51886093 -1.09130915 1 N 0 N;0
A 2.53611004 -1.07688996 2.5108 -1.07948996 2.52742205 -1.11680827 1 N 0 N;0
A 2.56883996 -1.07368002 2.50178002 -1.06358996 2.5273123 -1.12178858 1 N 0 N;0
A 2.50178996 -1.06358996 2.48536998 -1.08248996 2.52926211 -1.10403986 1 N 0 N;0
L 2.48536998 -1.0825 2.48536998 -1.09748002 1 N 8191 ;0
A 2.48536998 -1.09748002 2.49956004 -1.12031004 2.51189104 -1.09682067 1 N 0 N;0
A 2.46181004 -1.11835 2.34675 -1.11835 2.40428002 -1.11611998 1 N 0 N;0
L 2.43956998 -1.11418002 2.36841004 -1.11418002 1 N 0 ;0
L 2.36841004 -1.11418002 2.36841004 -1.11398996 1 N 8191 ;0
A 2.43958002 -1.11398996 2.3684 -1.11398996 2.40398996 -1.1124 1 N 0 N;0
L 2.43956998 -1.11398996 2.43956998 -1.11418002 1 N 8191 ;0
A 2.49955 -1.1203 2.52723002 -1.12985 2.58163209 -0.92727982 1 N 0 N;0
A 2.55001998 -1.14328002 2.52723002 -1.12986004 2.51462185 -1.17733228 1 N 0 N;0
L 2.46181004 -1.12868996 2.36843996 -1.12868996 1 N 0 ;0
A 2.36843996 -1.12868996 2.37851998 -1.15751998 2.41186801 -1.12968307 1 N 0 N;0
L 2.34675 -1.1402 2.34675 -1.11835 1 N 8191 ;0
L 2.46181004 -1.11835 2.46181004 -1.12868996 1 N 8191 ;0
L 2.25188002 -1.11398996 2.25188002 -1.11418002 1 N 8191 ;0
A 2.3208 -1.02041004 2.3006 -1.02033996 2.31069163 -1.02276978 1 N 0 N;0
L 2.27413002 -1.11835 2.27413002 -1.12868996 1 N 8191 ;0
A 2.52848996 -1.16771004 2.54891998 -1.15895 2.52774557 -1.13777087 1 N 0 N;0
A 2.55608002 -1.08618002 2.53611998 -1.07688996 2.5249185 -1.12704419 1 N 0 N;0
L 2.71926004 -1.06796998 2.71926004 -1.17483996 1 N 0 ;0
A 2.78888996 -1.16296998 2.81508002 -1.16676998 2.8083499 -1.12100167 1 N 0 N;0
A 2.8151 -1.16675 2.83966004 -1.15211998 2.80521398 -1.12222392 1 N 0 N;0
A 2.85201004 -1.16508002 2.83966004 -1.15211004 2.84505768 -1.15933514 1 N 0 N;0
L 2.85201004 -1.16508002 2.84523996 -1.17161004 1 N 8191 ;0
A 2.81425 -1.1835 2.84525 -1.17161004 2.81425 -1.13714291 1 N 0 N;0
L 2.81425 -1.1835 2.79571004 -1.1835 1 N 8191 ;0
A 2.75886998 -1.16443002 2.79571998 -1.18351998 2.80278976 -1.12476142 1 N 0 N;0
A 2.74528996 -1.13568002 2.75888002 -1.16443002 2.80246565 -1.12624016 1 N 0 N;0
A 2.54316998 -1.1834 2.56906004 -1.1647 2.5305814 -1.13869892 1 N 0 N;0
A 2.56906004 -1.1647 2.57053996 -1.13728002 2.53763041 -1.14925374 1 N 0 N;0
A 2.65463996 -1.18351998 2.66863996 -1.17373996 2.65440246 -1.16826969 1 N 0 N;0
L 2.65463002 -1.1835 2.64165 -1.1835 1 N 8191 ;0
A 2.60955 -1.16043002 2.64163996 -1.18351004 2.63911063 -1.15317815 1 N 0 N;0
A 2.62978002 -1.15461998 2.66001998 -1.16328996 2.6502374 -1.14033868 1 N 0 N;0
A 2.66863996 -1.17375 2.66001998 -1.16328996 2.66100344 -1.17126132 1 N 0 N;0
A 2.6962 -1.17483996 2.71926004 -1.17483996 2.70773002 -1.17286427 1 N 0 N;0
L 2.69618996 -1.17483996 2.69618996 -1.06796998 1 N 0 ;0
A 2.83833002 -1.09275 2.82661998 -1.08201998 2.74555758 -1.18224094 1 N 0 N;0
A 2.82661998 -1.08198996 2.80036998 -1.07538996 2.80348839 -1.11848878 1 N 0 N;0
A 2.80036004 -1.07541998 2.76848996 -1.09933002 2.80700217 -1.1174685 1 N 0 N;0
A 2.76848996 -1.09931998 2.76446004 -1.12066004 2.82315728 -1.120694 1 N 0 N;0
A 2.74998002 -1.09273996 2.74528996 -1.11838996 2.8498563 -1.12425591 1 N 0 N;0
A 2.7954 -1.05776998 2.74998996 -1.09273996 2.80799961 -1.12109961 1 N 0 N;0
L 2.79541004 -1.05776998 2.80918996 -1.05776998 1 N 8191 ;0
A 2.85401998 -1.08106004 2.80918996 -1.05776998 2.80626024 -1.1181998 1 N 0 N;0
A 2.83833002 -1.09273996 2.85403002 -1.08106004 2.84418386 -1.08421683 1 N 0 N;0
L 2.76445 -1.12066004 2.76445 -1.12943002 1 N 8191 ;0
A 2.76446004 -1.12943002 2.76836998 -1.14305 2.80607844 -1.12485364 1 N 0 N;0
A 2.76836998 -1.14305 2.78891004 -1.16296998 2.80906152 -1.12164144 1 N 0 N;0
L 2.74528996 -1.13566004 2.74528996 -1.11838996 1 N 8191 ;0
A 2.55606004 -1.0862 2.56885 -1.07366998 2.56205354 -1.0795252 1 N 0 N;0
L 2.60953996 -1.07953996 2.59981998 -1.07953996 1 N 8191 ;0
A 2.5993 -1.05931998 2.59981004 -1.07955 2.6022813 -1.06936624 1 N 0 N;0
L 2.5993 -1.05931998 2.60953996 -1.05931998 1 N 8191 ;0
L 2.60953996 -1.05931998 2.60953996 -1.03491998 1 N 8191 ;0
A 2.62971998 -1.03418002 2.60953996 -1.03491004 2.61966791 -1.03559478 1 N 0 N;0
L 2.62971004 -1.03418996 2.62978002 -1.05931998 1 N 8191 ;0
L 2.62978002 -1.05931998 2.66008002 -1.05931998 1 N 8191 ;0
A 2.66003996 -1.07955 2.66008002 -1.05931998 2.65827421 -1.0694314 1 N 0 N;0
L 2.66003002 -1.07953996 2.62978002 -1.07953996 1 N 8191 ;0
A 2.71926004 -1.06796998 2.6962 -1.06796998 2.70773002 -1.0720561 1 N 0 N;0
A 2.71968996 -1.02341998 2.71968996 -1.02341998 2.70775 -1.02341998 1 N 0 N;0
A 2.57053996 -1.13728996 2.54306998 -1.11513002 2.53584449 -1.15219301 1 N 0 N;0
A 2.54891998 -1.15895 2.55001004 -1.14328002 2.54127923 -1.15054557 1 N 0 N;0
L 2.60953996 -1.16041004 2.60953996 -1.07953996 1 N 0 ;0
L 2.62978002 -1.07953996 2.62978002 -1.15463002 1 N 0 ;0
L 2.98495 -1.09393996 2.98495 -1.17625 1 N 0 ;0
A 2.96473996 -1.17626998 2.98493996 -1.17626998 2.97483996 -1.17442303 1 N 0 N;0
L 2.96473002 -1.17625 2.96473002 -1.17226004 1 N 8191 ;0
A 2.94165 -1.1835 2.96471004 -1.17226004 2.93076516 -1.1318935 1 N 0 N;0
L 2.94165 -1.1835 2.90701004 -1.1835 1 N 8191 ;0
A 2.90671004 -1.10841998 2.90703002 -1.18351004 2.9153065 -1.14592904 1 N 0 N;0
A 2.91853002 -1.12288996 2.91853002 -1.16618996 2.92048209 -1.14453996 1 N 0 N;0
L 2.91853002 -1.1662 2.94456004 -1.1662 1 N 8191 ;0
A 2.94456998 -1.16618996 2.94456998 -1.12288996 2.94406004 -1.14453996 1 N 0 N;0
A 2.96473002 -1.09686004 2.94741998 -1.07955 2.94874833 -1.09553169 1 N 0 N;0
L 2.9474 -1.07953996 2.90986998 -1.07953996 1 N 8191 ;0
A 2.90986998 -1.07953996 2.89821004 -1.0852 2.92433445 -1.12417766 1 N 0 N;0
A 2.89111998 -1.07086004 2.8982 -1.0852 2.8969689 -1.07688996 1 N 0 N;0
A 2.91561998 -1.05931998 2.89111998 -1.07085 2.92146033 -1.103525 1 N 0 N;0
L 2.91563002 -1.05931998 2.95031004 -1.05931998 1 N 8191 ;0
A 2.98496004 -1.09393996 2.95031004 -1.05933002 2.9453438 -1.09895197 1 N 0 N;0
A 2.92878996 -1.10535 2.9067 -1.10841998 2.93158484 -1.20646998 1 N 0 N;0
A 2.96471998 -1.10841004 2.92878002 -1.10536004 2.93215738 -1.27883829 1 N 0 N;0
L 2.96473002 -1.10841004 2.96473002 -1.09686004 1 N 8191 ;0
L 2.94456004 -1.12288002 2.91853002 -1.12288002 1 N 8191 ;0
L 3.04731004 -1.06001004 3.04191998 -1.07631998 1 N 8191 ;0
L 3.04191998 -1.07631998 3.03648002 -1.06001004 1 N 8191 ;0
L 3.03648002 -1.06001004 3.03243002 -1.06001004 1 N 8191 ;0
L 3.03243002 -1.06001004 3.02698002 -1.08543996 1 N 8191 ;0
L 3.02698002 -1.08543996 3.03226004 -1.08543996 1 N 8191 ;0
L 3.03226004 -1.08543996 3.03501004 -1.06886998 1 N 8191 ;0
L 3.03501004 -1.06886998 3.04086004 -1.08543996 1 N 8191 ;0
L 3.04086004 -1.08543996 3.04308996 -1.08543996 1 N 8191 ;0
L 3.04308996 -1.08543996 3.04888996 -1.06871004 1 N 8191 ;0
L 3.04888996 -1.06871004 3.05171004 -1.08543996 1 N 8191 ;0
L 3.05171004 -1.08543996 3.05713002 -1.08543996 1 N 8191 ;0
L 3.05713002 -1.08543996 3.05163996 -1.06001004 1 N 8191 ;0
L 3.05163996 -1.06001004 3.04731004 -1.06001004 1 N 8191 ;0
L 3.01066998 -1.06508002 3.00223002 -1.06508002 1 N 8191 ;0
L 3.00223002 -1.06508002 3.00223002 -1.06001004 1 N 8191 ;0
L 3.00223002 -1.06001004 3.02461004 -1.06001004 1 N 8191 ;0
L 3.02461004 -1.06001004 3.02461004 -1.06508002 1 N 8191 ;0
L 3.02461004 -1.06508002 3.01615 -1.06508002 1 N 8191 ;0
L 3.01615 -1.06508002 3.01615 -1.08533996 1 N 8191 ;0
L 3.01615 -1.08533996 3.01066998 -1.08533996 1 N 8191 ;0
L 3.01066998 -1.08533996 3.01066998 -1.06508002 1 N 8191 ;0
L 3.36933297 -0.955 3.36933297 -0.88 0 N 0 ;0
L 3.36933297 -0.88 3.39173337 -0.88 0 N 0 ;0
L 3.39173337 -0.88 3.3992001 -0.88375157 0 N 0 ;0
L 3.3992001 -0.88375157 3.40480059 -0.8924997 0 N 0 ;0
L 3.40480059 -0.8924997 3.40666693 -0.9024998 0 N 0 ;0
L 3.40666693 -0.9024998 3.40480059 -0.9125 0 N 0 ;0
L 3.40480059 -0.9125 3.40013327 -0.92000069 0 N 0 ;0
L 3.40013327 -0.92000069 3.39173337 -0.92375217 0 N 0 ;0
L 3.39173337 -0.92375217 3.36933297 -0.92375217 0 N 0 ;0
L 3.44619931 -0.95749941 3.47980059 -0.88 0 N 0 ;0
L 3.51653356 -0.955 3.51653356 -0.88 0 N 0 ;0
L 3.51653356 -0.88 3.55946634 -0.955 0 N 0 ;0
L 3.55946634 -0.955 3.55946634 -0.88 0 N 0 ;0
L 3.68799911 -0.95749941 3.68613287 -0.9562497 0 N 0 ;0
L 3.68613287 -0.9562497 3.68613287 -0.9537503 0 N 0 ;0
L 3.68613287 -0.9537503 3.68799911 -0.95250059 0 N 0 ;0
L 3.68799911 -0.95250059 3.68986703 -0.9537503 0 N 0 ;0
L 3.68986703 -0.9537503 3.68986703 -0.9562497 0 N 0 ;0
L 3.68986703 -0.9562497 3.68799911 -0.95749941 0 N 0 ;0
L 3.68799911 -0.92375217 3.68613287 -0.9225001 0 N 0 ;0
L 3.68613287 -0.9225001 3.68613287 -0.92000069 0 N 0 ;0
L 3.68613287 -0.92000069 3.68799911 -0.91875089 0 N 0 ;0
L 3.68799911 -0.91875089 3.68986703 -0.92000069 0 N 0 ;0
L 3.68986703 -0.92000069 3.68986703 -0.9225001 0 N 0 ;0
L 3.68986703 -0.9225001 3.68799911 -0.92375217 0 N 0 ;0
L 3.81933297 -0.955 3.81933297 -0.88 0 N 0 ;0
L 3.81933297 -0.88 3.84266644 -0.88 0 N 0 ;0
L 3.84266644 -0.88 3.85013327 -0.88375157 0 N 0 ;0
L 3.85013327 -0.88375157 3.85480059 -0.88875049 0 N 0 ;0
L 3.85480059 -0.88875049 3.85666693 -0.89875059 0 N 0 ;0
L 3.85666693 -0.89875059 3.85480059 -0.90875079 0 N 0 ;0
L 3.85480059 -0.90875079 3.8492001 -0.91499941 0 N 0 ;0
L 3.8492001 -0.91499941 3.84266644 -0.91875089 0 N 0 ;0
L 3.84266644 -0.91875089 3.81933297 -0.91875089 0 N 0 ;0
L 3.84266644 -0.91875089 3.85666693 -0.955 0 N 0 ;0
L 3.9242001 -0.955 3.9242001 -0.88 0 N 0 ;0
L 3.9242001 -0.88 3.88966565 -0.93375 0 N 0 ;0
L 3.88966565 -0.93375 3.93633425 -0.93375 0 N 0 ;0
L 3.98799911 -0.88 3.98053228 -0.88249951 0 N 0 ;0
L 3.98053228 -0.88249951 3.97493346 -0.88875049 0 N 0 ;0
L 3.97493346 -0.88875049 3.97119931 -0.89624882 0 N 0 ;0
L 3.97119931 -0.89624882 3.9683999 -0.90625128 0 N 0 ;0
L 3.9683999 -0.90625128 3.96746673 -0.91750118 0 N 0 ;0
L 3.96746673 -0.91750118 3.9683999 -0.92875108 0 N 0 ;0
L 3.9683999 -0.92875108 3.97119931 -0.93875128 0 N 0 ;0
L 3.97119931 -0.93875128 3.97493346 -0.94625187 0 N 0 ;0
L 3.97493346 -0.94625187 3.98053228 -0.95250059 0 N 0 ;0
L 3.98053228 -0.95250059 3.98799911 -0.955 0 N 0 ;0
L 3.98799911 -0.955 3.99546585 -0.95250059 0 N 0 ;0
L 3.99546585 -0.95250059 4.00106644 -0.94625187 0 N 0 ;0
L 4.00106644 -0.94625187 4.00480059 -0.93875128 0 N 0 ;0
L 4.00480059 -0.93875128 4.0076 -0.92875108 0 N 0 ;0
L 4.0076 -0.92875108 4.00853317 -0.91750118 0 N 0 ;0
L 4.00853317 -0.91750118 4.0076 -0.90625128 0 N 0 ;0
L 4.0076 -0.90625128 4.00480059 -0.89624882 0 N 0 ;0
L 4.00480059 -0.89624882 4.00106644 -0.88875049 0 N 0 ;0
L 4.00106644 -0.88875049 3.99546585 -0.88249951 0 N 0 ;0
L 3.99546585 -0.88249951 3.98799911 -0.88 0 N 0 ;0
L 4.06299911 -0.88 4.05553228 -0.88249951 0 N 0 ;0
L 4.05553228 -0.88249951 4.04993346 -0.88875049 0 N 0 ;0
L 4.04993346 -0.88875049 4.04619931 -0.89624882 0 N 0 ;0
L 4.04619931 -0.89624882 4.0433999 -0.90625128 0 N 0 ;0
L 4.0433999 -0.90625128 4.04246673 -0.91750118 0 N 0 ;0
L 4.04246673 -0.91750118 4.0433999 -0.92875108 0 N 0 ;0
L 4.0433999 -0.92875108 4.04619931 -0.93875128 0 N 0 ;0
L 4.04619931 -0.93875128 4.04993346 -0.94625187 0 N 0 ;0
L 4.04993346 -0.94625187 4.05553228 -0.95250059 0 N 0 ;0
L 4.05553228 -0.95250059 4.06299911 -0.955 0 N 0 ;0
L 4.06299911 -0.955 4.07046585 -0.95250059 0 N 0 ;0
L 4.07046585 -0.95250059 4.07606644 -0.94625187 0 N 0 ;0
L 4.07606644 -0.94625187 4.07980059 -0.93875128 0 N 0 ;0
L 4.07980059 -0.93875128 4.0826 -0.92875108 0 N 0 ;0
L 4.0826 -0.92875108 4.08353317 -0.91750118 0 N 0 ;0
L 4.08353317 -0.91750118 4.0826 -0.90625128 0 N 0 ;0
L 4.0826 -0.90625128 4.07980059 -0.89624882 0 N 0 ;0
L 4.07980059 -0.89624882 4.07606644 -0.88875049 0 N 0 ;0
L 4.07606644 -0.88875049 4.07046585 -0.88249951 0 N 0 ;0
L 4.07046585 -0.88249951 4.06299911 -0.88 0 N 0 ;0
L 4.12026614 -0.92375217 4.1267998 -0.91499941 0 N 0 ;0
L 4.1267998 -0.91499941 4.1324003 -0.91000049 0 N 0 ;0
L 4.1324003 -0.91000049 4.13986703 -0.90750108 0 N 0 ;0
L 4.13986703 -0.90750108 4.14640069 -0.91000049 0 N 0 ;0
L 4.14640069 -0.91000049 4.15106644 -0.91499941 0 N 0 ;0
L 4.15106644 -0.91499941 4.15480059 -0.9225001 0 N 0 ;0
L 4.15480059 -0.9225001 4.15573376 -0.93125059 0 N 0 ;0
L 4.15573376 -0.93125059 4.15480059 -0.93875128 0 N 0 ;0
L 4.15480059 -0.93875128 4.15106644 -0.94625187 0 N 0 ;0
L 4.15106644 -0.94625187 4.14546585 -0.95250059 0 N 0 ;0
L 4.14546585 -0.95250059 4.13893396 -0.955 0 N 0 ;0
L 4.13893396 -0.955 4.13146713 -0.95250059 0 N 0 ;0
L 4.13146713 -0.95250059 4.12493346 -0.94500217 0 N 0 ;0
L 4.12493346 -0.94500217 4.12119931 -0.93375 0 N 0 ;0
L 4.12119931 -0.93375 4.12026614 -0.92125039 0 N 0 ;0
L 4.12026614 -0.92125039 4.12213238 -0.90500157 0 N 0 ;0
L 4.12213238 -0.90500157 4.12493346 -0.89624882 0 N 0 ;0
L 4.12493346 -0.89624882 4.12959921 -0.88750069 0 N 0 ;0
L 4.12959921 -0.88750069 4.13613287 -0.8812498 0 N 0 ;0
L 4.13613287 -0.8812498 4.14266644 -0.88 0 N 0 ;0
L 4.14266644 -0.88 4.1492001 -0.88249951 0 N 0 ;0
L 4.1492001 -0.88249951 4.15386752 -0.88875049 0 N 0 ;0
L 4.20086663 -0.93000079 4.22513327 -0.93000079 0 N 0 ;0
L 4.29546585 -0.91499941 4.2992001 -0.9112502 0 N 0 ;0
L 4.2992001 -0.9112502 4.30199951 -0.90500157 0 N 0 ;0
L 4.30199951 -0.90500157 4.30386752 -0.89624882 0 N 0 ;0
L 4.30386752 -0.89624882 4.30199951 -0.88875049 0 N 0 ;0
L 4.30199951 -0.88875049 4.29826703 -0.88375157 0 N 0 ;0
L 4.29826703 -0.88375157 4.29173337 -0.88 0 N 0 ;0
L 4.29173337 -0.88 4.26653356 -0.88 0 N 0 ;0
L 4.26653356 -0.88 4.26653356 -0.955 0 N 0 ;0
L 4.26653356 -0.955 4.29733386 -0.955 0 N 0 ;0
L 4.29733386 -0.955 4.30386752 -0.95000108 0 N 0 ;0
L 4.30386752 -0.95000108 4.3076 -0.94250039 0 N 0 ;0
L 4.3076 -0.94250039 4.30946634 -0.93375 0 N 0 ;0
L 4.30946634 -0.93375 4.3076 -0.92500187 0 N 0 ;0
L 4.3076 -0.92500187 4.30199951 -0.91750118 0 N 0 ;0
L 4.30199951 -0.91750118 4.29546585 -0.91499941 0 N 0 ;0
L 4.29546585 -0.91499941 4.26653356 -0.91499941 0 N 0 ;0
L 4.36299911 -0.88 4.35553228 -0.88249951 0 N 0 ;0
L 4.35553228 -0.88249951 4.34993346 -0.88875049 0 N 0 ;0
L 4.34993346 -0.88875049 4.34619931 -0.89624882 0 N 0 ;0
L 4.34619931 -0.89624882 4.3433999 -0.90625128 0 N 0 ;0
L 4.3433999 -0.90625128 4.34246673 -0.91750118 0 N 0 ;0
L 4.34246673 -0.91750118 4.3433999 -0.92875108 0 N 0 ;0
L 4.3433999 -0.92875108 4.34619931 -0.93875128 0 N 0 ;0
L 4.34619931 -0.93875128 4.34993346 -0.94625187 0 N 0 ;0
L 4.34993346 -0.94625187 4.35553228 -0.95250059 0 N 0 ;0
L 4.35553228 -0.95250059 4.36299911 -0.955 0 N 0 ;0
L 4.36299911 -0.955 4.37046585 -0.95250059 0 N 0 ;0
L 4.37046585 -0.95250059 4.37606644 -0.94625187 0 N 0 ;0
L 4.37606644 -0.94625187 4.37980059 -0.93875128 0 N 0 ;0
L 4.37980059 -0.93875128 4.3826 -0.92875108 0 N 0 ;0
L 4.3826 -0.92875108 4.38353317 -0.91750118 0 N 0 ;0
L 4.38353317 -0.91750118 4.3826 -0.90625128 0 N 0 ;0
L 4.3826 -0.90625128 4.37980059 -0.89624882 0 N 0 ;0
L 4.37980059 -0.89624882 4.37606644 -0.88875049 0 N 0 ;0
L 4.37606644 -0.88875049 4.37046585 -0.88249951 0 N 0 ;0
L 4.37046585 -0.88249951 4.36299911 -0.88 0 N 0 ;0
L 4.43799911 -0.88 4.43053228 -0.88249951 0 N 0 ;0
L 4.43053228 -0.88249951 4.42493346 -0.88875049 0 N 0 ;0
L 4.42493346 -0.88875049 4.42119931 -0.89624882 0 N 0 ;0
L 4.42119931 -0.89624882 4.4183999 -0.90625128 0 N 0 ;0
L 4.4183999 -0.90625128 4.41746673 -0.91750118 0 N 0 ;0
L 4.41746673 -0.91750118 4.4183999 -0.92875108 0 N 0 ;0
L 4.4183999 -0.92875108 4.42119931 -0.93875128 0 N 0 ;0
L 4.42119931 -0.93875128 4.42493346 -0.94625187 0 N 0 ;0
L 4.42493346 -0.94625187 4.43053228 -0.95250059 0 N 0 ;0
L 4.43053228 -0.95250059 4.43799911 -0.955 0 N 0 ;0
L 4.43799911 -0.955 4.44546585 -0.95250059 0 N 0 ;0
L 4.44546585 -0.95250059 4.45106644 -0.94625187 0 N 0 ;0
L 4.45106644 -0.94625187 4.45480059 -0.93875128 0 N 0 ;0
L 4.45480059 -0.93875128 4.4576 -0.92875108 0 N 0 ;0
L 4.4576 -0.92875108 4.45853317 -0.91750118 0 N 0 ;0
L 4.45853317 -0.91750118 4.4576 -0.90625128 0 N 0 ;0
L 4.4576 -0.90625128 4.45480059 -0.89624882 0 N 0 ;0
L 4.45480059 -0.89624882 4.45106644 -0.88875049 0 N 0 ;0
L 4.45106644 -0.88875049 4.44546585 -0.88249951 0 N 0 ;0
L 4.44546585 -0.88249951 4.43799911 -0.88 0 N 0 ;0
L 4.51299911 -0.88 4.50553228 -0.88249951 0 N 0 ;0
L 4.50553228 -0.88249951 4.49993346 -0.88875049 0 N 0 ;0
L 4.49993346 -0.88875049 4.49619931 -0.89624882 0 N 0 ;0
L 4.49619931 -0.89624882 4.4933999 -0.90625128 0 N 0 ;0
L 4.4933999 -0.90625128 4.49246673 -0.91750118 0 N 0 ;0
L 4.49246673 -0.91750118 4.4933999 -0.92875108 0 N 0 ;0
L 4.4933999 -0.92875108 4.49619931 -0.93875128 0 N 0 ;0
L 4.49619931 -0.93875128 4.49993346 -0.94625187 0 N 0 ;0
L 4.49993346 -0.94625187 4.50553228 -0.95250059 0 N 0 ;0
L 4.50553228 -0.95250059 4.51299911 -0.955 0 N 0 ;0
L 4.51299911 -0.955 4.52046585 -0.95250059 0 N 0 ;0
L 4.52046585 -0.95250059 4.52606644 -0.94625187 0 N 0 ;0
L 4.52606644 -0.94625187 4.52980059 -0.93875128 0 N 0 ;0
L 4.52980059 -0.93875128 4.5326 -0.92875108 0 N 0 ;0
L 4.5326 -0.92875108 4.53353317 -0.91750118 0 N 0 ;0
L 4.53353317 -0.91750118 4.5326 -0.90625128 0 N 0 ;0
L 4.5326 -0.90625128 4.52980059 -0.89624882 0 N 0 ;0
L 4.52980059 -0.89624882 4.52606644 -0.88875049 0 N 0 ;0
L 4.52606644 -0.88875049 4.52046585 -0.88249951 0 N 0 ;0
L 4.52046585 -0.88249951 4.51299911 -0.88 0 N 0 ;0
L 4.58799911 -0.955 4.58799911 -0.88 0 N 0 ;0
L 4.58799911 -0.88 4.5767998 -0.89499911 0 N 0 ;0
L 4.5767998 -0.955 4.59919843 -0.955 0 N 0 ;0
L 4.65086663 -0.93000079 4.67513327 -0.93000079 0 N 0 ;0
L 4.73799911 -0.88 4.73053228 -0.88249951 0 N 0 ;0
L 4.73053228 -0.88249951 4.72493346 -0.88875049 0 N 0 ;0
L 4.72493346 -0.88875049 4.72119931 -0.89624882 0 N 0 ;0
L 4.72119931 -0.89624882 4.7183999 -0.90625128 0 N 0 ;0
L 4.7183999 -0.90625128 4.71746673 -0.91750118 0 N 0 ;0
L 4.71746673 -0.91750118 4.7183999 -0.92875108 0 N 0 ;0
L 4.7183999 -0.92875108 4.72119931 -0.93875128 0 N 0 ;0
L 4.72119931 -0.93875128 4.72493346 -0.94625187 0 N 0 ;0
L 4.72493346 -0.94625187 4.73053228 -0.95250059 0 N 0 ;0
L 4.73053228 -0.95250059 4.73799911 -0.955 0 N 0 ;0
L 4.73799911 -0.955 4.74546585 -0.95250059 0 N 0 ;0
L 4.74546585 -0.95250059 4.75106644 -0.94625187 0 N 0 ;0
L 4.75106644 -0.94625187 4.75480059 -0.93875128 0 N 0 ;0
L 4.75480059 -0.93875128 4.7576 -0.92875108 0 N 0 ;0
L 4.7576 -0.92875108 4.75853317 -0.91750118 0 N 0 ;0
L 4.75853317 -0.91750118 4.7576 -0.90625128 0 N 0 ;0
L 4.7576 -0.90625128 4.75480059 -0.89624882 0 N 0 ;0
L 4.75480059 -0.89624882 4.75106644 -0.88875049 0 N 0 ;0
L 4.75106644 -0.88875049 4.74546585 -0.88249951 0 N 0 ;0
L 4.74546585 -0.88249951 4.73799911 -0.88 0 N 0 ;0
L 4.79526614 -0.8924997 4.80086663 -0.88500128 0 N 0 ;0
L 4.80086663 -0.88500128 4.8074003 -0.8812498 0 N 0 ;0
L 4.8074003 -0.8812498 4.81486703 -0.88 0 N 0 ;0
L 4.81486703 -0.88 4.8242001 -0.88249951 0 N 0 ;0
L 4.8242001 -0.88249951 4.83073376 -0.88875049 0 N 0 ;0
L 4.83073376 -0.88875049 4.8326 -0.89624882 0 N 0 ;0
L 4.8326 -0.89624882 4.83166693 -0.90375187 0 N 0 ;0
L 4.83166693 -0.90375187 4.82793268 -0.91000049 0 N 0 ;0
L 4.82793268 -0.91000049 4.80926654 -0.9225001 0 N 0 ;0
L 4.80926654 -0.9225001 4.80086663 -0.93125059 0 N 0 ;0
L 4.80086663 -0.93125059 4.79526614 -0.94375246 0 N 0 ;0
L 4.79526614 -0.94375246 4.7933999 -0.955 0 N 0 ;0
L 4.7933999 -0.955 4.8326 -0.955 0 N 0 ;0
L 3.36746673 -1.205 3.36746673 -1.13 0 N 0 ;0
L 3.36746673 -1.13 3.38613287 -1.13 0 N 0 ;0
L 3.38613287 -1.13 3.39359961 -1.13375157 0 N 0 ;0
L 3.39359961 -1.13375157 3.3992001 -1.13875049 0 N 0 ;0
L 3.3992001 -1.13875049 3.40386752 -1.14624882 0 N 0 ;0
L 3.40386752 -1.14624882 3.4076 -1.15500157 0 N 0 ;0
L 3.4076 -1.15500157 3.40853317 -1.16750118 0 N 0 ;0
L 3.40853317 -1.16750118 3.4076 -1.18000079 0 N 0 ;0
L 3.4076 -1.18000079 3.40386752 -1.18875128 0 N 0 ;0
L 3.40386752 -1.18875128 3.3992001 -1.19625187 0 N 0 ;0
L 3.3992001 -1.19625187 3.39359961 -1.20125089 0 N 0 ;0
L 3.39359961 -1.20125089 3.38613287 -1.205 0 N 0 ;0
L 3.38613287 -1.205 3.36746673 -1.205 0 N 0 ;0
L 3.47980059 -1.205 3.47980059 -1.15500157 0 N 0 ;0
L 3.47980059 -1.1637497 3.47606644 -1.15875079 0 N 0 ;0
L 3.47606644 -1.15875079 3.47046585 -1.15625128 0 N 0 ;0
L 3.47046585 -1.15625128 3.46393396 -1.15500157 0 N 0 ;0
L 3.46393396 -1.15500157 3.4574003 -1.15750108 0 N 0 ;0
L 3.4574003 -1.15750108 3.4517998 -1.1625 0 N 0 ;0
L 3.4517998 -1.1625 3.44806555 -1.17000069 0 N 0 ;0
L 3.44806555 -1.17000069 3.44619931 -1.18000079 0 N 0 ;0
L 3.44619931 -1.18000079 3.44806555 -1.19000098 0 N 0 ;0
L 3.44806555 -1.19000098 3.4517998 -1.19750167 0 N 0 ;0
L 3.4517998 -1.19750167 3.4574003 -1.20250059 0 N 0 ;0
L 3.4574003 -1.20250059 3.46393396 -1.205 0 N 0 ;0
L 3.46393396 -1.205 3.47046585 -1.2037503 0 N 0 ;0
L 3.47046585 -1.2037503 3.47606644 -1.20000108 0 N 0 ;0
L 3.47606644 -1.20000108 3.47980059 -1.19500217 0 N 0 ;0
L 3.53799911 -1.13 3.53799911 -1.205 0 N 0 ;0
L 3.52493346 -1.15500157 3.55106644 -1.15500157 0 N 0 ;0
L 3.59900039 -1.17125039 3.62886752 -1.17125039 0 N 0 ;0
L 3.62886752 -1.17125039 3.62606644 -1.1625 0 N 0 ;0
L 3.62606644 -1.1625 3.62140069 -1.15750108 0 N 0 ;0
L 3.62140069 -1.15750108 3.61486703 -1.15500157 0 N 0 ;0
L 3.61486703 -1.15500157 3.60833346 -1.15625128 0 N 0 ;0
L 3.60833346 -1.15625128 3.60273287 -1.16000049 0 N 0 ;0
L 3.60273287 -1.16000049 3.59900039 -1.16875089 0 N 0 ;0
L 3.59900039 -1.16875089 3.59713238 -1.17625157 0 N 0 ;0
L 3.59713238 -1.17625157 3.59713238 -1.18375 0 N 0 ;0
L 3.59713238 -1.18375 3.59900039 -1.19125069 0 N 0 ;0
L 3.59900039 -1.19125069 3.60366604 -1.19875138 0 N 0 ;0
L 3.60366604 -1.19875138 3.60926654 -1.2037503 0 N 0 ;0
L 3.60926654 -1.2037503 3.6158002 -1.205 0 N 0 ;0
L 3.6158002 -1.205 3.62233386 -1.20250059 0 N 0 ;0
L 3.62233386 -1.20250059 3.62886752 -1.19500217 0 N 0 ;0
L 3.68799911 -1.20749941 3.68613287 -1.2062497 0 N 0 ;0
L 3.68613287 -1.2062497 3.68613287 -1.2037503 0 N 0 ;0
L 3.68613287 -1.2037503 3.68799911 -1.20250059 0 N 0 ;0
L 3.68799911 -1.20250059 3.68986703 -1.2037503 0 N 0 ;0
L 3.68986703 -1.2037503 3.68986703 -1.2062497 0 N 0 ;0
L 3.68986703 -1.2062497 3.68799911 -1.20749941 0 N 0 ;0
L 3.68799911 -1.17375217 3.68613287 -1.1725001 0 N 0 ;0
L 3.68613287 -1.1725001 3.68613287 -1.17000069 0 N 0 ;0
L 3.68613287 -1.17000069 3.68799911 -1.16875089 0 N 0 ;0
L 3.68799911 -1.16875089 3.68986703 -1.17000069 0 N 0 ;0
L 3.68986703 -1.17000069 3.68986703 -1.1725001 0 N 0 ;0
L 3.68986703 -1.1725001 3.68799911 -1.17375217 0 N 0 ;0
L 3.82026614 -1.1424997 3.82586663 -1.13500128 0 N 0 ;0
L 3.82586663 -1.13500128 3.8324003 -1.1312498 0 N 0 ;0
L 3.8324003 -1.1312498 3.83986703 -1.13 0 N 0 ;0
L 3.83986703 -1.13 3.8492001 -1.13249951 0 N 0 ;0
L 3.8492001 -1.13249951 3.85573376 -1.13875049 0 N 0 ;0
L 3.85573376 -1.13875049 3.8576 -1.14624882 0 N 0 ;0
L 3.8576 -1.14624882 3.85666693 -1.15375187 0 N 0 ;0
L 3.85666693 -1.15375187 3.85293268 -1.16000049 0 N 0 ;0
L 3.85293268 -1.16000049 3.83426654 -1.1725001 0 N 0 ;0
L 3.83426654 -1.1725001 3.82586663 -1.18125059 0 N 0 ;0
L 3.82586663 -1.18125059 3.82026614 -1.19375246 0 N 0 ;0
L 3.82026614 -1.19375246 3.8183999 -1.205 0 N 0 ;0
L 3.8183999 -1.205 3.8576 -1.205 0 N 0 ;0
L 3.91299911 -1.13 3.90553228 -1.13249951 0 N 0 ;0
L 3.90553228 -1.13249951 3.89993346 -1.13875049 0 N 0 ;0
L 3.89993346 -1.13875049 3.89619931 -1.14624882 0 N 0 ;0
L 3.89619931 -1.14624882 3.8933999 -1.15625128 0 N 0 ;0
L 3.8933999 -1.15625128 3.89246673 -1.16750118 0 N 0 ;0
L 3.89246673 -1.16750118 3.8933999 -1.17875108 0 N 0 ;0
L 3.8933999 -1.17875108 3.89619931 -1.18875128 0 N 0 ;0
L 3.89619931 -1.18875128 3.89993346 -1.19625187 0 N 0 ;0
L 3.89993346 -1.19625187 3.90553228 -1.20250059 0 N 0 ;0
L 3.90553228 -1.20250059 3.91299911 -1.205 0 N 0 ;0
L 3.91299911 -1.205 3.92046585 -1.20250059 0 N 0 ;0
L 3.92046585 -1.20250059 3.92606644 -1.19625187 0 N 0 ;0
L 3.92606644 -1.19625187 3.92980059 -1.18875128 0 N 0 ;0
L 3.92980059 -1.18875128 3.9326 -1.17875108 0 N 0 ;0
L 3.9326 -1.17875108 3.93353317 -1.16750118 0 N 0 ;0
L 3.93353317 -1.16750118 3.9326 -1.15625128 0 N 0 ;0
L 3.9326 -1.15625128 3.92980059 -1.14624882 0 N 0 ;0
L 3.92980059 -1.14624882 3.92606644 -1.13875049 0 N 0 ;0
L 3.92606644 -1.13875049 3.92046585 -1.13249951 0 N 0 ;0
L 3.92046585 -1.13249951 3.91299911 -1.13 0 N 0 ;0
L 3.97026614 -1.1424997 3.97586663 -1.13500128 0 N 0 ;0
L 3.97586663 -1.13500128 3.9824003 -1.1312498 0 N 0 ;0
L 3.9824003 -1.1312498 3.98986703 -1.13 0 N 0 ;0
L 3.98986703 -1.13 3.9992001 -1.13249951 0 N 0 ;0
L 3.9992001 -1.13249951 4.00573376 -1.13875049 0 N 0 ;0
L 4.00573376 -1.13875049 4.0076 -1.14624882 0 N 0 ;0
L 4.0076 -1.14624882 4.00666693 -1.15375187 0 N 0 ;0
L 4.00666693 -1.15375187 4.00293268 -1.16000049 0 N 0 ;0
L 4.00293268 -1.16000049 3.98426654 -1.1725001 0 N 0 ;0
L 3.98426654 -1.1725001 3.97586663 -1.18125059 0 N 0 ;0
L 3.97586663 -1.18125059 3.97026614 -1.19375246 0 N 0 ;0
L 3.97026614 -1.19375246 3.9683999 -1.205 0 N 0 ;0
L 3.9683999 -1.205 4.0076 -1.205 0 N 0 ;0
L 4.04526614 -1.1424997 4.05086663 -1.13500128 0 N 0 ;0
L 4.05086663 -1.13500128 4.0574003 -1.1312498 0 N 0 ;0
L 4.0574003 -1.1312498 4.06486703 -1.13 0 N 0 ;0
L 4.06486703 -1.13 4.0742001 -1.13249951 0 N 0 ;0
L 4.0742001 -1.13249951 4.08073376 -1.13875049 0 N 0 ;0
L 4.08073376 -1.13875049 4.0826 -1.14624882 0 N 0 ;0
L 4.0826 -1.14624882 4.08166693 -1.15375187 0 N 0 ;0
L 4.08166693 -1.15375187 4.07793268 -1.16000049 0 N 0 ;0
L 4.07793268 -1.16000049 4.05926654 -1.1725001 0 N 0 ;0
L 4.05926654 -1.1725001 4.05086663 -1.18125059 0 N 0 ;0
L 4.05086663 -1.18125059 4.04526614 -1.19375246 0 N 0 ;0
L 4.04526614 -1.19375246 4.0433999 -1.205 0 N 0 ;0
L 4.0433999 -1.205 4.0826 -1.205 0 N 0 ;0
L 4.12586663 -1.18000079 4.15013327 -1.18000079 0 N 0 ;0
L 4.21299911 -1.13 4.20553228 -1.13249951 0 N 0 ;0
L 4.20553228 -1.13249951 4.19993346 -1.13875049 0 N 0 ;0
L 4.19993346 -1.13875049 4.19619931 -1.14624882 0 N 0 ;0
L 4.19619931 -1.14624882 4.1933999 -1.15625128 0 N 0 ;0
L 4.1933999 -1.15625128 4.19246673 -1.16750118 0 N 0 ;0
L 4.19246673 -1.16750118 4.1933999 -1.17875108 0 N 0 ;0
L 4.1933999 -1.17875108 4.19619931 -1.18875128 0 N 0 ;0
L 4.19619931 -1.18875128 4.19993346 -1.19625187 0 N 0 ;0
L 4.19993346 -1.19625187 4.20553228 -1.20250059 0 N 0 ;0
L 4.20553228 -1.20250059 4.21299911 -1.205 0 N 0 ;0
L 4.21299911 -1.205 4.22046585 -1.20250059 0 N 0 ;0
L 4.22046585 -1.20250059 4.22606644 -1.19625187 0 N 0 ;0
L 4.22606644 -1.19625187 4.22980059 -1.18875128 0 N 0 ;0
L 4.22980059 -1.18875128 4.2326 -1.17875108 0 N 0 ;0
L 4.2326 -1.17875108 4.23353317 -1.16750118 0 N 0 ;0
L 4.23353317 -1.16750118 4.2326 -1.15625128 0 N 0 ;0
L 4.2326 -1.15625128 4.22980059 -1.14624882 0 N 0 ;0
L 4.22980059 -1.14624882 4.22606644 -1.13875049 0 N 0 ;0
L 4.22606644 -1.13875049 4.22046585 -1.13249951 0 N 0 ;0
L 4.22046585 -1.13249951 4.21299911 -1.13 0 N 0 ;0
L 4.27026614 -1.1424997 4.27586663 -1.13500128 0 N 0 ;0
L 4.27586663 -1.13500128 4.2824003 -1.1312498 0 N 0 ;0
L 4.2824003 -1.1312498 4.28986703 -1.13 0 N 0 ;0
L 4.28986703 -1.13 4.2992001 -1.13249951 0 N 0 ;0
L 4.2992001 -1.13249951 4.30573376 -1.13875049 0 N 0 ;0
L 4.30573376 -1.13875049 4.3076 -1.14624882 0 N 0 ;0
L 4.3076 -1.14624882 4.30666693 -1.15375187 0 N 0 ;0
L 4.30666693 -1.15375187 4.30293268 -1.16000049 0 N 0 ;0
L 4.30293268 -1.16000049 4.28426654 -1.1725001 0 N 0 ;0
L 4.28426654 -1.1725001 4.27586663 -1.18125059 0 N 0 ;0
L 4.27586663 -1.18125059 4.27026614 -1.19375246 0 N 0 ;0
L 4.27026614 -1.19375246 4.2683999 -1.205 0 N 0 ;0
L 4.2683999 -1.205 4.3076 -1.205 0 N 0 ;0
L 4.35086663 -1.18000079 4.37513327 -1.18000079 0 N 0 ;0
L 4.42026614 -1.1424997 4.42586663 -1.13500128 0 N 0 ;0
L 4.42586663 -1.13500128 4.4324003 -1.1312498 0 N 0 ;0
L 4.4324003 -1.1312498 4.43986703 -1.13 0 N 0 ;0
L 4.43986703 -1.13 4.4492001 -1.13249951 0 N 0 ;0
L 4.4492001 -1.13249951 4.45573376 -1.13875049 0 N 0 ;0
L 4.45573376 -1.13875049 4.4576 -1.14624882 0 N 0 ;0
L 4.4576 -1.14624882 4.45666693 -1.15375187 0 N 0 ;0
L 4.45666693 -1.15375187 4.45293268 -1.16000049 0 N 0 ;0
L 4.45293268 -1.16000049 4.43426654 -1.1725001 0 N 0 ;0
L 4.43426654 -1.1725001 4.42586663 -1.18125059 0 N 0 ;0
L 4.42586663 -1.18125059 4.42026614 -1.19375246 0 N 0 ;0
L 4.42026614 -1.19375246 4.4183999 -1.205 0 N 0 ;0
L 4.4183999 -1.205 4.4576 -1.205 0 N 0 ;0
L 4.49246673 -1.19375246 4.49806555 -1.20000108 0 N 0 ;0
L 4.49806555 -1.20000108 4.50459921 -1.2037503 0 N 0 ;0
L 4.50459921 -1.2037503 4.51299911 -1.205 0 N 0 ;0
L 4.51299911 -1.205 4.52140069 -1.20250059 0 N 0 ;0
L 4.52140069 -1.20250059 4.52793268 -1.19750167 0 N 0 ;0
L 4.52793268 -1.19750167 4.5326 -1.18875128 0 N 0 ;0
L 4.5326 -1.18875128 4.53353317 -1.17875108 0 N 0 ;0
L 4.53353317 -1.17875108 4.53166693 -1.16875089 0 N 0 ;0
L 4.53166693 -1.16875089 4.52699951 -1.1625 0 N 0 ;0
L 4.52699951 -1.1625 4.52046585 -1.15750108 0 N 0 ;0
L 4.52046585 -1.15750108 4.51393396 -1.15625128 0 N 0 ;0
L 4.51393396 -1.15625128 4.5074003 -1.15750108 0 N 0 ;0
L 4.5074003 -1.15750108 4.49900039 -1.1625 0 N 0 ;0
L 4.49900039 -1.1625 4.5017998 -1.13 0 N 0 ;0
L 4.5017998 -1.13 4.52699951 -1.13 0 N 0 ;0
L 3.29433297 -1.255 3.29433297 -1.33 0 N 0 ;0
L 3.29433297 -1.33 3.33166693 -1.33 0 N 0 ;0
L 3.40480059 -1.33 3.40480059 -1.28000157 0 N 0 ;0
L 3.40480059 -1.2887497 3.40106644 -1.28375079 0 N 0 ;0
L 3.40106644 -1.28375079 3.39546585 -1.28125128 0 N 0 ;0
L 3.39546585 -1.28125128 3.38893396 -1.28000157 0 N 0 ;0
L 3.38893396 -1.28000157 3.3824003 -1.28250108 0 N 0 ;0
L 3.3824003 -1.28250108 3.3767998 -1.2875 0 N 0 ;0
L 3.3767998 -1.2875 3.37306555 -1.29500069 0 N 0 ;0
L 3.37306555 -1.29500069 3.37119931 -1.30500079 0 N 0 ;0
L 3.37119931 -1.30500079 3.37306555 -1.31500098 0 N 0 ;0
L 3.37306555 -1.31500098 3.3767998 -1.32250167 0 N 0 ;0
L 3.3767998 -1.32250167 3.3824003 -1.32750059 0 N 0 ;0
L 3.3824003 -1.32750059 3.38893396 -1.33 0 N 0 ;0
L 3.38893396 -1.33 3.39546585 -1.3287503 0 N 0 ;0
L 3.39546585 -1.3287503 3.40106644 -1.32500108 0 N 0 ;0
L 3.40106644 -1.32500108 3.40480059 -1.32000217 0 N 0 ;0
L 3.4433999 -1.3524997 3.44900039 -1.35499921 0 N 0 ;0
L 3.44900039 -1.35499921 3.45646713 -1.3524997 0 N 0 ;0
L 3.45646713 -1.3524997 3.46113287 -1.34750079 0 N 0 ;0
L 3.46113287 -1.34750079 3.46486703 -1.3412498 0 N 0 ;0
L 3.46486703 -1.3412498 3.47046585 -1.32125187 0 N 0 ;0
L 3.47046585 -1.32125187 3.4826 -1.28000157 0 N 0 ;0
L 3.45273287 -1.28000157 3.47046585 -1.32125187 0 N 0 ;0
L 3.52400039 -1.29625039 3.55386752 -1.29625039 0 N 0 ;0
L 3.55386752 -1.29625039 3.55106644 -1.2875 0 N 0 ;0
L 3.55106644 -1.2875 3.54640069 -1.28250108 0 N 0 ;0
L 3.54640069 -1.28250108 3.53986703 -1.28000157 0 N 0 ;0
L 3.53986703 -1.28000157 3.53333346 -1.28125128 0 N 0 ;0
L 3.53333346 -1.28125128 3.52773287 -1.28500049 0 N 0 ;0
L 3.52773287 -1.28500049 3.52400039 -1.29375089 0 N 0 ;0
L 3.52400039 -1.29375089 3.52213238 -1.30125157 0 N 0 ;0
L 3.52213238 -1.30125157 3.52213238 -1.30875 0 N 0 ;0
L 3.52213238 -1.30875 3.52400039 -1.31625069 0 N 0 ;0
L 3.52400039 -1.31625069 3.52866604 -1.32375138 0 N 0 ;0
L 3.52866604 -1.32375138 3.53426654 -1.3287503 0 N 0 ;0
L 3.53426654 -1.3287503 3.5408002 -1.33 0 N 0 ;0
L 3.5408002 -1.33 3.54733386 -1.32750059 0 N 0 ;0
L 3.54733386 -1.32750059 3.55386752 -1.32000217 0 N 0 ;0
L 3.59993346 -1.33 3.59993346 -1.28000157 0 N 0 ;0
L 3.59993346 -1.28999941 3.60459921 -1.28500049 0 N 0 ;0
L 3.60459921 -1.28500049 3.60926654 -1.28125128 0 N 0 ;0
L 3.60926654 -1.28125128 3.6158002 -1.28000157 0 N 0 ;0
L 3.6158002 -1.28000157 3.62046585 -1.28125128 0 N 0 ;0
L 3.62046585 -1.28125128 3.62606644 -1.28500049 0 N 0 ;0
L 3.68799911 -1.33249941 3.68613287 -1.3312497 0 N 0 ;0
L 3.68613287 -1.3312497 3.68613287 -1.3287503 0 N 0 ;0
L 3.68613287 -1.3287503 3.68799911 -1.32750059 0 N 0 ;0
L 3.68799911 -1.32750059 3.68986703 -1.3287503 0 N 0 ;0
L 3.68986703 -1.3287503 3.68986703 -1.3312497 0 N 0 ;0
L 3.68986703 -1.3312497 3.68799911 -1.33249941 0 N 0 ;0
L 3.68799911 -1.29875217 3.68613287 -1.2975001 0 N 0 ;0
L 3.68613287 -1.2975001 3.68613287 -1.29500069 0 N 0 ;0
L 3.68613287 -1.29500069 3.68799911 -1.29375089 0 N 0 ;0
L 3.68799911 -1.29375089 3.68986703 -1.29500069 0 N 0 ;0
L 3.68986703 -1.29500069 3.68986703 -1.2975001 0 N 0 ;0
L 3.68986703 -1.2975001 3.68799911 -1.29875217 0 N 0 ;0
L 3.36933297 -1.08 3.36933297 -1.005 0 N 0 ;0
L 3.36933297 -1.005 3.39266644 -1.005 0 N 0 ;0
L 3.39266644 -1.005 3.40013327 -1.00875157 0 N 0 ;0
L 3.40013327 -1.00875157 3.40480059 -1.01375049 0 N 0 ;0
L 3.40480059 -1.01375049 3.40666693 -1.02375059 0 N 0 ;0
L 3.40666693 -1.02375059 3.40480059 -1.03375079 0 N 0 ;0
L 3.40480059 -1.03375079 3.3992001 -1.03999941 0 N 0 ;0
L 3.3992001 -1.03999941 3.39266644 -1.04375089 0 N 0 ;0
L 3.39266644 -1.04375089 3.36933297 -1.04375089 0 N 0 ;0
L 3.39266644 -1.04375089 3.40666693 -1.08 0 N 0 ;0
L 3.44900039 -1.04625039 3.47886752 -1.04625039 0 N 0 ;0
L 3.47886752 -1.04625039 3.47606644 -1.0375 0 N 0 ;0
L 3.47606644 -1.0375 3.47140069 -1.03250108 0 N 0 ;0
L 3.47140069 -1.03250108 3.46486703 -1.03000157 0 N 0 ;0
L 3.46486703 -1.03000157 3.45833346 -1.03125128 0 N 0 ;0
L 3.45833346 -1.03125128 3.45273287 -1.03500049 0 N 0 ;0
L 3.45273287 -1.03500049 3.44900039 -1.04375089 0 N 0 ;0
L 3.44900039 -1.04375089 3.44713238 -1.05125157 0 N 0 ;0
L 3.44713238 -1.05125157 3.44713238 -1.05875 0 N 0 ;0
L 3.44713238 -1.05875 3.44900039 -1.06625069 0 N 0 ;0
L 3.44900039 -1.06625069 3.45366604 -1.07375138 0 N 0 ;0
L 3.45366604 -1.07375138 3.45926654 -1.0787503 0 N 0 ;0
L 3.45926654 -1.0787503 3.4658002 -1.08 0 N 0 ;0
L 3.4658002 -1.08 3.47233386 -1.07750059 0 N 0 ;0
L 3.47233386 -1.07750059 3.47886752 -1.07000217 0 N 0 ;0
L 3.52119931 -1.03000157 3.53799911 -1.08 0 N 0 ;0
L 3.53799911 -1.08 3.55480059 -1.03000157 0 N 0 ;0
L 3.68799911 -1.08249941 3.68613287 -1.0812497 0 N 0 ;0
L 3.68613287 -1.0812497 3.68613287 -1.0787503 0 N 0 ;0
L 3.68613287 -1.0787503 3.68799911 -1.07750059 0 N 0 ;0
L 3.68799911 -1.07750059 3.68986703 -1.0787503 0 N 0 ;0
L 3.68986703 -1.0787503 3.68986703 -1.0812497 0 N 0 ;0
L 3.68986703 -1.0812497 3.68799911 -1.08249941 0 N 0 ;0
L 3.68799911 -1.04875217 3.68613287 -1.0475001 0 N 0 ;0
L 3.68613287 -1.0475001 3.68613287 -1.04500069 0 N 0 ;0
L 3.68613287 -1.04500069 3.68799911 -1.04375089 0 N 0 ;0
L 3.68799911 -1.04375089 3.68986703 -1.04500069 0 N 0 ;0
L 3.68986703 -1.04500069 3.68986703 -1.0475001 0 N 0 ;0
L 3.68986703 -1.0475001 3.68799911 -1.04875217 0 N 0 ;0
L 3.83799911 -1.005 3.83053228 -1.00749951 0 N 0 ;0
L 3.83053228 -1.00749951 3.82493346 -1.01375049 0 N 0 ;0
L 3.82493346 -1.01375049 3.82119931 -1.02124882 0 N 0 ;0
L 3.82119931 -1.02124882 3.8183999 -1.03125128 0 N 0 ;0
L 3.8183999 -1.03125128 3.81746673 -1.04250118 0 N 0 ;0
L 3.81746673 -1.04250118 3.8183999 -1.05375108 0 N 0 ;0
L 3.8183999 -1.05375108 3.82119931 -1.06375128 0 N 0 ;0
L 3.82119931 -1.06375128 3.82493346 -1.07125187 0 N 0 ;0
L 3.82493346 -1.07125187 3.83053228 -1.07750059 0 N 0 ;0
L 3.83053228 -1.07750059 3.83799911 -1.08 0 N 0 ;0
L 3.83799911 -1.08 3.84546585 -1.07750059 0 N 0 ;0
L 3.84546585 -1.07750059 3.85106644 -1.07125187 0 N 0 ;0
L 3.85106644 -1.07125187 3.85480059 -1.06375128 0 N 0 ;0
L 3.85480059 -1.06375128 3.8576 -1.05375108 0 N 0 ;0
L 3.8576 -1.05375108 3.85853317 -1.04250118 0 N 0 ;0
L 3.85853317 -1.04250118 3.8576 -1.03125128 0 N 0 ;0
L 3.8576 -1.03125128 3.85480059 -1.02124882 0 N 0 ;0
L 3.85480059 -1.02124882 3.85106644 -1.01375049 0 N 0 ;0
L 3.85106644 -1.01375049 3.84546585 -1.00749951 0 N 0 ;0
L 3.84546585 -1.00749951 3.83799911 -1.005 0 N 0 ;0
L 3.91299911 -1.08 3.91299911 -1.005 0 N 0 ;0
L 3.91299911 -1.005 3.9017998 -1.01999911 0 N 0 ;0
L 3.9017998 -1.08 3.92419843 -1.08 0 N 0 ;0

### steps/pcb/layers/l05_vcc1/features
#
#Num Features
#
F 3165

#
#Units
#
U INCH

#
#Feature symbol names
#
$0 r5
$1 r6
$2 r10
$3 r26
$4 r28
$5 r30
$6 r32
$7 r33
$8 r39
$9 r56
$10 r82
$11 r86
$12 r99
$13 r102
$14 r125
$15 r143
$16 r150
$17 r189
$18 oval74x47 I
$19 oval86x47 I
$20 ths102x92.01x45x4x14 I

#
#Feature attribute names
#
@0 .nomenclature
@1 .geometry
@2 .sip

#
#Feature attribute text strings
#
&0 V010C020P_TP030B
&1 V008C018P-ANTI28-NSM
&2 V010C020P
&3 TPV010CT020B030
&4 V008C018P_ANTI026_TP030B
&5 V008C018P_NATI28_TP030B_NSMT
&6 016C024P
&7 V008C018P_TP030B
&8 V008C018P
&9 V008C018P_ANTI28
&10 059C086P
&11 V008C018P_ANTI026_NSM
&12 076S104P
&13 076C104P
&14 079C100P
&15 V010C020P_SM014-NTH
&16 V012C024-NTH
&17 024X063OB035X075P
&18 166CT244CB198P
&19 024X051OB071X075P_R
&20 024X051OB071X075P_L
&21 033C057P
&22 063C090P
&23 MTH100C090N
&24 MTH125C115N
&25 MTH118C108N

#
#Layer features
#
S P 0;0,2=1
OB -24.76435 -17.98935 I
OS -24.76435 16.38535
OS 21.05735 16.38535
OS 21.05735 -17.98935
OS -24.76435 -17.98935
OE
OB -0.00110019685 0.21653976378 H
OC 0.039369783465 0.176069783465 0.039369783465 0.21653976378 N
OS 0.551194094488 0.176069980315
OC 0.59165 0.216525885827 0.551180019685 0.21653996063 N
OS 0.59165019685 0.46260019685
OC 0.629906200787 0.500870177165 0.629920177165 0.46260019685 Y
OS 1.273619980315 0.500869980315
OC 1.31188996063 0.462613779528 1.273619980315 0.4626 Y
OS 1.31188976378 0.21653976378
OC 1.35235984252 0.176069783465 1.352359744094 0.21653976378 N
OS 1.588594094488 0.176069980315
OC 1.62905 0.216525885827 1.588580019685 0.21653996063 N
OS 1.62905019685 0.430120177165
OC 1.77055019685 0.430134055118 1.69980019685 0.430120177165 Y
OS 1.770550098425 0.019702952756
OC 1.770872244094 0.018912204724 1.77165 0.019690059055 N
OS 1.790547933071 -0.000763484252
OC 1.791339862205 -0.001100098425 1.79133996063 -0.000000098425 N
OS 2.192896850394 -0.001100098425
OC 2.193511712598 -0.000920767717 2.192909645669 -0.00000019685 N
OC 2.193677066929 -0.000788484252 2.192910728346 -0.000000098425 N
OS 2.213388188976 0.018922637795
OC 2.213699901575 0.019689862205 2.212599901575 0.019689862205 N
OS 2.2137 0.29331003937
OC 2.2863 0.29331003937 2.25 0.29331003937 Y
OS 2.286300098425 0.019690059055
OC 2.286636712598 0.018898129921 2.287400098425 0.01969015748 N
OS 2.306298129921 -0.000763287402
OC 2.307090059055 -0.001099901575 2.30709015748 0.000000098425 N
OS 3.102347047244 -0.001099901575
OC 3.102961909449 -0.000920570866 3.10235984252 0 N
OC 3.10312726378 -0.000788287402 3.102360925197 0.000000098425 N
OS 3.122837893701 0.01892234252
OC 3.122970570866 0.019087992126 3.122049901575 0.019689468504 N
OC 3.123149901575 0.019702952756 3.12205 0.019690059055 N
OS 3.12314980315 0.462613779528
OC 3.161419783465 0.500869783465 3.161419783465 0.46259980315 Y
OS 6.561034055118 0.500869980315
OC 6.60148996063 0.541325885827 6.561019980315 0.54133996063 N
OS 6.60149015748 2.374999901575
OC 6.580710531496 2.39579015748 6.580705216535 2.375005216535 N
OS 6.572096555118 2.39578996063
OC 6.553530019685 2.414369980315 6.57211003937 2.414369980315 Y
OS 6.553529822835 2.826783759843
OC 6.572110137795 2.84535984252 6.57211476378 2.826774901575 Y
OS 6.572111122047 2.84535984252
OS 6.580724409449 2.84536003937
OC 6.60148996063 2.866125590551 6.58071003937 2.86613996063 N
OS 6.60149015748 4.33661023622
OC 6.561020177165 4.377080216535 6.561020177165 4.33661023622 N
OS 0.039355905512 4.377080019685
OC -0.0011 4.336624114173 0.039369980315 4.33661003937 N
OS -0.00110019685 0.21653976378
OE
SE
S P 0
OB -0.00110019685 0.21653976378 I
OS -0.0011 4.336624114173
OC 0.039355905512 4.377080019685 0.039369980315 4.33661003937 Y
OS 6.561020177165 4.377080216535
OC 6.60149015748 4.33661023622 6.561020177165 4.33661023622 Y
OS 6.60148996063 2.866125590551
OC 6.580724409449 2.84536003937 6.58071003937 2.86613996063 Y
OS 6.580725 2.84536003937
OS 6.580710629921 2.845359940945
OS 6.572123917323 2.845359940945
OS 6.572111122047 2.84535984252
OS 6.572110137795 2.84535984252
OC 6.553529822835 2.826783759843 6.57211476378 2.826774901575 N
OS 6.553530019685 2.414369980315
OC 6.572096555118 2.39578996063 6.57211003937 2.414369980315 N
OS 6.580710531496 2.39579015748
OC 6.60149015748 2.374999901575 6.580705216535 2.375005216535 Y
OS 6.60148996063 0.541325885827
OC 6.561034055118 0.500869980315 6.561019980315 0.54133996063 Y
OS 6.561034744094 0.500869980315
OS 6.561020570866 0.50086988189
OS 3.161433858268 0.50086988189
OS 3.161419783465 0.500869783465
OC 3.12314980315 0.462613779528 3.161419783465 0.46259980315 N
OS 3.123149901575 0.019702952756
OC 3.122970570866 0.019087992126 3.12205 0.019690059055 Y
OC 3.122837893701 0.01892234252 3.122049901575 0.019689468504 Y
OS 3.10312726378 -0.000788287402
OC 3.102961909449 -0.000920570866 3.102360925197 0.000000098425 Y
OC 3.102347047244 -0.001099901575 3.10235984252 0 Y
OS 2.307090059055 -0.001099901575
OC 2.306298129921 -0.000763287402 2.30709015748 0.000000098425 Y
OS 2.286636712598 0.018898129921
OC 2.286300098425 0.019690059055 2.287400098425 0.01969015748 Y
OS 2.2863 0.29331003937
OC 2.2137 0.29331003937 2.25 0.29331003937 N
OS 2.213699901575 0.019689862205
OC 2.213388188976 0.018922637795 2.212599901575 0.019689862205 Y
OS 2.193677066929 -0.000788484252
OC 2.193511712598 -0.000920767717 2.192910728346 -0.000000098425 Y
OC 2.192896850394 -0.001100098425 2.192909645669 -0.00000019685 Y
OS 1.791339862205 -0.001100098425
OC 1.790547933071 -0.000763484252 1.79133996063 -0.000000098425 Y
OS 1.770872244094 0.018912204724
OC 1.770550098425 0.019702952756 1.77165 0.019690059055 Y
OS 1.77055019685 0.430134055118
OC 1.62905019685 0.430120177165 1.69980019685 0.430120177165 N
OS 1.62905 0.216525885827
OC 1.588594094488 0.176069980315 1.588580019685 0.21653996063 Y
OS 1.588594783465 0.176069980315
OS 1.588580610236 0.17606988189
OS 1.352373917323 0.17606988189
OS 1.35235984252 0.176069783465
OC 1.31188976378 0.21653976378 1.352359744094 0.21653976378 Y
OS 1.31188996063 0.462613779528
OC 1.273619980315 0.500869980315 1.273619980315 0.4626 N
OS 0.629906200787 0.500870177165
OC 0.59165019685 0.46260019685 0.629920177165 0.46260019685 N
OS 0.59165 0.216525885827
OC 0.551194094488 0.176069980315 0.551180019685 0.21653996063 Y
OS 0.551194783465 0.176069980315
OS 0.551180610236 0.17606988189
OS 0.039383858268 0.17606988189
OS 0.039369783465 0.176069783465
OC -0.00110019685 0.21653976378 0.039369783465 0.21653976378 Y
OE
OB 5.731219980315 2.26793996063 H
OS 5.773319980315 2.22585
OS 5.7738 2.2257
OC 5.7937 2.2058 5.765 2.197 Y
OS 5.79385 2.205319980315
OS 5.80885 2.19031003937
OC 5.815180019685 2.1912 5.81167992126 2.193138484252 N
OC 5.99 2.294019980315 5.99 2.093990944882 Y
OC 5.99 1.893980019685 5.99 2.094 Y
OS 5.98998996063 1.893980019685
OC 5.85338996063 1.94788996063 5.989992224409 2.094002952756 Y
OS 5.85281003937 1.948430019685
OS 5.850019980315 1.948430019685
OS 5.850019980315 1.94238996063
OS 5.85063996063 1.9418
OC 5.860019980315 1.92 5.82999734252 1.92 Y
OC 5.850019980315 1.897630019685 5.829999114173 1.92 Y
OS 5.850019980315 0.581969980315
OS 6.275469980315 0.581969980315
OC 6.27898996063 0.587869980315 6.275469783465 0.58597007874 N
OC 6.26236003937 0.65353996063 6.400386811024 0.65355246063 Y
OC 6.40038996063 0.79156003937 6.400390059055 0.653530019685 Y
OC 6.513119980315 0.733180019685 6.40038996063 0.653530905512 Y
OC 6.52038996063 0.735480019685 6.516389862205 0.735483956693 N
OS 6.52038996063 2.32916003937
OC 6.472430019685 2.414369980315 6.572105807087 2.414369980315 Y
OS 6.472430019685 2.82678996063
OC 6.52038996063 2.91198996063 6.57211496063 2.826774901575 Y
OS 6.52038996063 4.09641003937
OC 6.513119980315 4.09871003937 6.516389862205 4.096406102362 N
OC 6.40038996063 4.040319980315 6.400383956693 4.178346948819 Y
OC 6.26236003937 4.17835 6.40038996063 4.178349901575 Y
OC 6.31758996063 4.288780019685 6.400387007874 4.178344094488 Y
OC 6.31518996063 4.295980019685 6.31518996063 4.291980019685 N
OS 6.09801003937 4.295980019685
OS 6.08 4.277969980315
OS 6.08 3.918280019685
OS 6.14913996063 3.84913996063
OC 6.155 3.835 6.135010334646 3.834999901575 Y
OS 6.155 3.275
OC 6.14913996063 3.26086003937 6.135010334646 3.275000098425 Y
OS 6.06413996063 3.17586003937
OC 6.05 3.17 6.049999901575 3.189989665354 Y
OS 5.903280019685 3.17
OS 5.81 3.076719980315
OS 5.81 2.38745
OC 5.819019980315 2.366 5.789005413386 2.366 Y
OC 5.8027 2.33928996063 5.78900265748 2.365999901575 Y
OS 5.802419980315 2.33913996063
OS 5.731219980315 2.26793996063
OE
OB 4.135 1.52413996063 H
OS 4.139780019685 1.51936003937
OS 4.1411 1.52011003937
OC 4.147530019685 1.52181003937 4.147530019685 1.508799704724 Y
OC 4.16055 1.50878996063 4.147530019685 1.508790059055 Y
OC 4.15885 1.50236003937 4.14753976378 1.508790059055 Y
OS 4.1581 1.50103996063
OS 4.17915 1.47998996063
OS 4.180469980315 1.48073996063
OC 4.1869 1.48243996063 4.1869 1.469429724409 Y
OC 4.199919980315 1.469419980315 4.1869 1.469419980315 Y
OS 4.199919980315 1.4691
OC 4.20391003937 1.465 4.203917125984 1.468998425197 N
OS 4.681680019685 1.465
OC 4.685680019685 1.4691 4.681681200787 1.469000098425 N
OS 4.685680019685 1.469419980315
OC 4.6987 1.48243996063 4.6987 1.469419980315 Y
OS 4.738069980315 1.48243996063
OC 4.7511 1.469419980315 4.738080019685 1.469419980315 Y
OC 4.75108996063 1.4691 4.738077755906 1.469668405512 Y
OC 4.75508996063 1.465 4.755088779528 1.469000098425 N
OS 5.14403996063 1.465
OC 5.145 1.465019980315 5.145040452756 1.440000885827 Y
OC 5.14596003937 1.465 5.144959547244 1.440000885827 Y
OS 5.15586003937 1.465
OS 5.17 1.47913996063
OS 5.17 1.69586003937
OS 5.13586003937 1.73
OS 4.99238996063 1.73
OC 4.94761003937 1.73 4.97 1.750005610236 Y
OS 4.87328996063 1.73
OC 4.827369980315 1.73 4.850330019685 1.749339862205 Y
OS 4.17913996063 1.73
OS 4.15966003937 1.710519980315
OS 4.16 1.709380019685
OC 4.16055 1.70563996063 4.147530610236 1.705635826772 Y
OC 4.147530019685 1.692619980315 4.147530019685 1.70563996063 Y
OC 4.14378996063 1.693169980315 4.147534153543 1.705639370079 Y
OS 4.14265 1.69351003937
OS 4.135 1.68586003937
OS 4.135 1.52413996063
OE
OB 3.780019980315 1.74 H
OS 4.085 1.74
OC 4.092069980315 1.737069980315 4.084999901575 1.73000511811 Y
OS 4.110719980315 1.718419980315
OS 4.11126003937 1.718280019685
OC 4.1208 1.70873996063 4.10816003937 1.705640059055 Y
OS 4.12093996063 1.7082
OS 4.125 1.70413996063
OS 4.167930019685 1.747069980315
OC 4.175 1.75 4.175000098425 1.74000511811 Y
OS 4.8 1.75
OS 4.8 1.904
OC 4.8 1.956 4.814993307087 1.93 Y
OS 4.8 2.00795
OS 4.7983 2.00821003937
OC 4.7983 2.06755 4.802881692913 2.037880019685 Y
OS 4.8 2.06781003937
OS 4.8 2.10261003937
OC 4.8 2.14738996063 4.820005610236 2.125 Y
OS 4.8 2.61086003937
OS 4.71976003937 2.6911
OC 4.713180019685 2.68965 4.716933858268 2.688269980315 N
OC 4.685 2.669980019685 4.685 2.700000885827 Y
OC 4.65571003937 2.69343996063 4.685 2.699994389764 Y
OS 4.65536003937 2.695
OS 4.36 2.695
OC 4.352930019685 2.697930019685 4.360000098425 2.70499488189 Y
OS 4.292930019685 2.757930019685
OC 4.29 2.765 4.29999488189 2.765000098425 Y
OS 4.29 2.94086003937
OS 4.25586003937 2.975
OS 4.13106003937 2.975
OC 4.13 2.974980019685 4.129964370079 3.004999311024 Y
OC 4.12893996063 2.975 4.130035629921 3.004999311024 Y
OS 4.07606003937 2.975
OC 4.075 2.974980019685 4.074964370079 3.004999311024 Y
OC 4.07393996063 2.975 4.075035629921 3.004999311024 Y
OS 3.98413996063 2.975
OS 3.860019980315 2.850880019685
OS 3.860019980315 2.73085
OS 3.780019980315 2.65085
OS 3.780019980315 2.56388996063
OC 3.783019980315 2.552 3.757997440945 2.552009940945 Y
OC 3.780019980315 2.54011003937 3.757997440945 2.551990059055 Y
OS 3.780019980315 2.29463996063
OS 3.781580019685 2.29428996063
OC 3.805019980315 2.265 3.775 2.265 Y
OC 3.801 2.25 3.775001673228 2.265006200787 Y
OC 3.805019980315 2.235 3.775001673228 2.234993799213 Y
OC 3.80228996063 2.2225 3.775001673228 2.235007972441 Y
OC 3.805019980315 2.21 3.775001673228 2.209992027559 Y
OC 3.80228996063 2.1975 3.775001673228 2.210007972441 Y
OC 3.805019980315 2.185 3.775001673228 2.184992027559 Y
OC 3.781580019685 2.15571003937 3.775 2.185 Y
OS 3.780019980315 2.15536003937
OS 3.780019980315 1.74
OE
OB 3.67 1.52913996063 H
OS 3.70913996063 1.49
OS 4.08086003937 1.49
OS 4.0957 1.50483996063
OS 4.09546003937 1.505919980315
OC 4.09513996063 1.50878996063 4.108170177165 1.508790354331 Y
OC 4.10816003937 1.52181003937 4.10816003937 1.50878996063 Y
OC 4.111030019685 1.52148996063 4.108159645669 1.508779822835 Y
OS 4.11211003937 1.52125
OS 4.115 1.52413996063
OS 4.115 1.68586003937
OS 4.10826003937 1.6926
OS 4.10748996063 1.69263996063
OC 4.09516003937 1.704969980315 4.10816003937 1.70563996063 Y
OS 4.095119980315 1.70573996063
OS 4.08086003937 1.72
OS 4.00355 1.72
OC 4.000380019685 1.713569980315 4.003552755906 1.71600226378 N
OC 4.00306003937 1.70563996063 3.990034645669 1.705655807087 Y
OC 3.99003996063 1.692619980315 3.990040059055 1.70563996063 Y
OS 3.950669980315 1.692619980315
OC 3.93763996063 1.70563996063 3.950659940945 1.70563996063 Y
OC 3.940330019685 1.713569980315 3.950673622047 1.705639862205 Y
OC 3.93716003937 1.72 3.937157283465 1.71600226378 N
OS 3.70913996063 1.72
OS 3.70011003937 1.710969980315
OS 3.70101003937 1.7096
OC 3.706019980315 1.693 3.676013976378 1.693000098425 Y
OC 3.676 1.662980019685 3.676 1.693 Y
OC 3.674230019685 1.663030019685 3.675962401575 1.693001082677 Y
OC 3.67 1.65903996063 3.673999015748 1.65903769685 N
OS 3.67 1.52913996063
OE
OB 3.475 1.46413996063 H
OS 3.48913996063 1.45
OS 3.56 1.45
OC 3.567069980315 1.447069980315 3.559999901575 1.44000511811 Y
OS 3.587069980315 1.427069980315
OC 3.59 1.42 3.58000511811 1.419999901575 Y
OS 3.59 1.30606003937
OC 3.590019980315 1.305 3.560000688976 1.304964370079 Y
OC 3.59 1.30393996063 3.560000688976 1.305035629921 Y
OS 3.59 1.23413996063
OS 3.62913996063 1.195
OS 4.168380019685 1.195
OC 4.201619980315 1.195 4.185 1.169997637795 Y
OS 4.30893996063 1.195
OC 4.31 1.195019980315 4.310035629921 1.165000688976 Y
OC 4.31106003937 1.195 4.309964370079 1.165000688976 Y
OS 4.608380019685 1.195
OC 4.641619980315 1.195 4.625 1.169997637795 Y
OS 5.46586003937 1.195
OS 5.505 1.23413996063
OS 5.505 1.70086003937
OS 5.42586003937 1.78
OS 5.19413996063 1.78
OS 5.15415 1.74001003937
OS 5.190019980315 1.70415
OS 5.190019980315 1.47085
OS 5.16415 1.444980019685
OS 4.5149 1.444980019685
OC 4.511830019685 1.438419980315 4.514899114173 1.440982086614 N
OC 4.514880019685 1.43005 4.501852362205 1.430043405512 Y
OC 4.50185 1.417019980315 4.50185 1.43005 Y
OS 4.462480019685 1.417019980315
OC 4.44946003937 1.43005 4.46248996063 1.430049901575 Y
OC 4.4525 1.438419980315 4.46248257874 1.430057283465 Y
OC 4.449430019685 1.444980019685 4.449430905512 1.440982086614 N
OS 4.18585 1.444980019685
OS 4.12498996063 1.50585
OS 4.092069980315 1.472930019685
OC 4.085 1.47 4.084999901575 1.47999488189 Y
OS 4.003180019685 1.47
OS 4.00301003937 1.46818996063
OC 3.99003996063 1.4564 3.990040059055 1.469429035433 Y
OS 3.950669980315 1.4564
OC 3.9377 1.46818996063 3.950669980315 1.469429035433 Y
OS 3.937530019685 1.47
OS 3.705 1.47
OC 3.697930019685 1.472930019685 3.705000098425 1.47999488189 Y
OS 3.652930019685 1.517930019685
OC 3.65 1.525 3.65999488189 1.525000098425 Y
OS 3.65 1.534519980315
OS 3.64993996063 1.53476003937
OC 3.648980019685 1.542280019685 3.678998622047 1.542290649606 Y
OC 3.64993996063 1.5498 3.678998622047 1.542269389764 Y
OS 3.65 1.55003996063
OS 3.65 1.58
OS 3.50913996063 1.58
OS 3.475 1.54586003937
OS 3.475 1.46413996063
OE
OB 3.25 1.29913996063 H
OS 3.30913996063 1.24
OS 3.569980019685 1.24
OS 3.569980019685 1.41585
OS 3.55585 1.429980019685
OS 3.48085 1.429980019685
OS 3.454980019685 1.45585
OS 3.454980019685 1.55415
OS 3.50085 1.600019980315
OS 3.649980019685 1.600019980315
OS 3.649980019685 1.661980019685
OC 3.647919980315 1.663969980315 3.647981594488 1.66197253937 N
OC 3.647 1.66396003937 3.647135433071 1.694000295276 Y
OC 3.647 1.72403996063 3.647 1.694 Y
OC 3.662430019685 1.719769980315 3.646993307087 1.694001870079 Y
OC 3.676 1.723019980315 3.67601496063 1.693002755906 Y
OS 3.676019980315 1.723019980315
OC 3.681980019685 1.722419980315 3.676007972441 1.692999212598 Y
OS 3.68303996063 1.7222
OS 3.70085 1.740019980315
OS 3.76 1.740019980315
OS 3.76 2.159
OC 3.744980019685 2.185 3.774993307087 2.185 Y
OC 3.74771003937 2.1975 3.774998326772 2.184992027559 Y
OC 3.744980019685 2.21 3.774998326772 2.210007972441 Y
OC 3.74771003937 2.2225 3.774998326772 2.209992027559 Y
OC 3.744980019685 2.235 3.774998326772 2.235007972441 Y
OC 3.749 2.25 3.774998326772 2.234993799213 Y
OC 3.744980019685 2.265 3.774998326772 2.265006200787 Y
OC 3.76 2.291 3.774993307087 2.265 Y
OS 3.76 2.655
OC 3.762930019685 2.662069980315 3.76999488189 2.654999901575 Y
OS 3.84 2.73913996063
OS 3.84 2.85086003937
OS 3.78786003937 2.903
OS 3.786769980315 2.90275
OC 3.78 2.901980019685 3.780014271654 2.932001574803 Y
OC 3.77668996063 2.90216003937 3.779972834646 2.932001476378 Y
OC 3.748 2.880980019685 3.747999901575 2.911001476378 Y
OC 3.72691003937 2.88963996063 3.748 2.910990649606 Y
OC 3.72408996063 2.88963996063 3.7255 2.888218011811 N
OC 3.68191003937 2.88963996063 3.703 2.910990649606 Y
OC 3.67908996063 2.88963996063 3.6805 2.888218011811 N
OC 3.658 2.880980019685 3.658 2.910990649606 Y
OC 3.62811003937 2.90818996063 3.658 2.911001968504 Y
OS 3.62793996063 2.91
OS 3.33463996063 2.91
OS 3.33428996063 2.90843996063
OC 3.305 2.884980019685 3.305 2.914994389764 Y
OC 3.27815 2.901569980315 3.305 2.91500265748 Y
OC 3.27175 2.90261003937 3.274574409449 2.899778641732 N
OS 3.25 2.88086003937
OS 3.25 2.656
OC 3.25 2.604 3.235006692913 2.63 Y
OS 3.25 2.5752
OS 3.251419980315 2.574769980315
OC 3.251419980315 2.519230019685 3.243002165354 2.547 Y
OS 3.25 2.5188
OS 3.25 2.38723996063
OC 3.25 2.33276003937 3.240003740157 2.36 Y
OS 3.25 2.30331003937
OC 3.25 2.24668996063 3.239993602362 2.275 Y
OS 3.25 2.23581003937
OC 3.25 2.17918996063 3.239993602362 2.2075 Y
OS 3.25 1.917
OS 3.273119980315 1.917
OS 3.273119980315 1.888980019685
OS 3.25 1.888980019685
OS 3.25 1.29913996063
OE
OB 2.27 0.40898996063 H
OC 2.3674 0.29331003937 2.250004625984 0.293309940945 Y
OS 2.3674 0.262
OS 3.04205 0.262
OS 3.04205 0.4626
OC 3.161419980315 0.581969980315 3.161419980315 0.4626 Y
OS 5.83 0.581969980315
OS 5.83 0.78823996063
OS 5.82993996063 0.788480019685
OC 5.828980019685 0.796 5.858998622047 0.796010629921 Y
OC 5.82993996063 0.803519980315 5.858998622047 0.795989370079 Y
OS 5.83 0.80376003937
OS 5.83 1.97396003937
OC 5.789980019685 2.09398996063 5.990001968504 2.093993996063 Y
OS 5.789980019685 2.094
OC 5.8038 2.16706003937 5.99000738189 2.094000098425 Y
OS 5.7152 2.25566003937
OS 5.71413996063 2.255430019685
OC 5.710019980315 2.255 5.71001476378 2.275001574803 Y
OS 5.688030019685 2.255
OC 5.645969980315 2.255 5.667 2.275005610236 Y
OS 5.60973996063 2.255
OC 5.58026003937 2.255 5.595 2.280013287402 Y
OS 5.54631003937 2.255
OC 5.516130019685 2.255 5.53122007874 2.279800885827 Y
OS 5.49573996063 2.255
OC 5.467419980315 2.255 5.481580019685 2.280323818898 Y
OS 5.335 2.255
OC 5.32086003937 2.26086003937 5.335000098425 2.274989665354 Y
OS 5.28086003937 2.30086003937
OC 5.275 2.315 5.294989665354 2.315000098425 Y
OS 5.275 2.56536003937
OS 5.27491003937 2.56566003937
OC 5.273480019685 2.5748 5.30349773622 2.574814665354 Y
OC 5.27491003937 2.58393996063 5.30349773622 2.574785334646 Y
OS 5.275 2.58423996063
OS 5.275 2.96276003937
OC 5.275 3.01723996063 5.284996259843 2.99 Y
OS 5.275 3.159
OC 5.275 3.219 5.275996555118 3.189 Y
OS 5.275 3.597969980315
OS 5.23586003937 3.63711003937
OC 5.23346003937 3.64 5.249978346457 3.651276279528 Y
OS 4.41463996063 3.64
OS 4.41428996063 3.63843996063
OC 4.35571003937 3.63843996063 4.385 3.644994389764 Y
OS 4.35536003937 3.64
OS 4.351630019685 3.64
OS 4.35113996063 3.63968996063
OC 4.335 3.634980019685 4.335000098425 3.664988877953 Y
OC 4.318380019685 3.64 4.335 3.665002362205 Y
OS 4.22738996063 3.64
OC 4.18261003937 3.64 4.205 3.660005610236 Y
OS 3.89331003937 3.64
OC 3.865 3.619980019685 3.865000098425 3.650006397638 Y
OC 3.840730019685 3.632330019685 3.865 3.65000246063 Y
OC 3.834269980315 3.632330019685 3.8375 3.629972834646 N
OC 3.81 3.619980019685 3.81 3.65000246063 Y
OC 3.78168996063 3.64 3.809999901575 3.650006397638 Y
OS 2.92413996063 3.64
OS 2.855 3.57086003937
OS 2.855 3.44413996063
OS 3.282069980315 3.017069980315
OC 3.285 3.01 3.27500511811 3.009999901575 Y
OS 3.285 2.945019980315
OC 3.290880019685 2.94148996063 3.289000295276 2.945021161417 N
OC 3.305 2.945019980315 3.305003543307 2.915000885827 Y
OC 3.331 2.930019980315 3.305 2.914986712598 Y
OS 3.598630019685 2.930019980315
OC 3.621 2.940019980315 3.621 2.909999114173 Y
OC 3.63886003937 2.934130019685 3.621000098425 2.909996948819 Y
OC 3.658 2.941019980315 3.658 2.91099015748 Y
OC 3.67908996063 2.93236003937 3.658 2.911009350394 Y
OC 3.68191003937 2.93236003937 3.6805 2.933781988189 N
OC 3.72408996063 2.93236003937 3.703 2.911009350394 Y
OC 3.72691003937 2.93236003937 3.7255 2.933781988189 N
OC 3.748 2.941019980315 3.748 2.911009350394 Y
OC 3.771230019685 2.930019980315 3.748 2.910991240157 Y
OS 3.78915 2.930019980315
OS 3.85 2.869169980315
OS 3.97585 2.995019980315
OS 4.26415 2.995019980315
OS 4.310019980315 2.94915
OS 4.310019980315 2.76915
OS 4.36415 2.715019980315
OS 4.659 2.715019980315
OC 4.711 2.715019980315 4.685 2.699986712598 Y
OS 4.72415 2.715019980315
OS 4.820019980315 2.61915
OS 4.820019980315 2.155019980315
OC 4.820019980315 2.094980019685 4.82 2.125 Y
OS 4.820019980315 2.062530019685
OC 4.820019980315 2.013230019685 4.802872145669 2.037880019685 Y
OS 4.820019980315 1.95963996063
OS 4.821580019685 1.95928996063
OC 4.821580019685 1.90071003937 4.815 1.93 Y
OS 4.820019980315 1.90036003937
OS 4.820019980315 1.83331003937
OS 4.82113996063 1.83276003937
OC 4.82113996063 1.80756003937 4.815006397638 1.82016003937 Y
OS 4.820019980315 1.80701003937
OS 4.820019980315 1.7709
OC 4.82711003937 1.768369980315 4.82401742126 1.770902854331 N
OC 4.850330019685 1.77936003937 4.85033011811 1.74933503937 Y
OC 4.88025 1.75185 4.850330019685 1.749334448819 Y
OS 4.8804 1.750019980315
OS 4.94 1.750019980315
OC 5 1.750019980315 4.97 1.75 Y
OS 5.13585 1.750019980315
OS 5.18585 1.800019980315
OS 5.43415 1.800019980315
OS 5.525019980315 1.70915
OS 5.525019980315 1.22585
OS 5.47415 1.174980019685
OS 4.427519980315 1.174980019685
OS 4.427519980315 1.150980019685
OS 4.3575 1.150980019685
OS 4.3575 1.174980019685
OS 4.067519980315 1.174980019685
OS 4.067519980315 1.145980019685
OS 3.997480019685 1.145980019685
OS 3.997480019685 1.174980019685
OS 3.62085 1.174980019685
OS 3.57585 1.219980019685
OS 3.38655 1.219980019685
OC 3.383880019685 1.216480019685 3.375010925197 1.226014173228 Y
OS 3.38323996063 1.215019980315
OC 3.38523996063 1.213019980315 3.385240255906 1.215020275591 N
OS 3.390019980315 1.213019980315
OS 3.390019980315 1.142980019685
OS 3.359980019685 1.142980019685
OS 3.359980019685 1.213019980315
OS 3.36476003937 1.213019980315
OC 3.36676003937 1.215019980315 3.364759744094 1.215020275591 N
OS 3.366119980315 1.216480019685
OC 3.36345 1.219980019685 3.374989074803 1.226014173228 Y
OS 3.30915 1.219980019685
OS 2.86456003937 0.7754
OS 2.86456003937 0.748980019685
OS 2.80453996063 0.748980019685
OS 2.80453996063 0.759980019685
OS 2.79928996063 0.759980019685
OS 2.798819980315 0.75865
OC 2.774280019685 0.75865 2.78655 0.762997440945 Y
OS 2.77381003937 0.759980019685
OS 2.74381003937 0.759980019685
OS 2.74333996063 0.75865
OC 2.7188 0.75865 2.731069980315 0.762997440945 Y
OS 2.718330019685 0.759980019685
OS 2.713080019685 0.759980019685
OS 2.713080019685 0.748980019685
OS 2.65306003937 0.748980019685
OS 2.65306003937 0.759980019685
OS 2.64781003937 0.759980019685
OS 2.64733996063 0.75865
OC 2.6228 0.75865 2.635069980315 0.762997440945 Y
OS 2.622330019685 0.759980019685
OS 2.54696003937 0.759980019685
OS 2.54648996063 0.75865
OC 2.52195 0.75865 2.534219980315 0.762997440945 Y
OS 2.521480019685 0.759980019685
OS 2.51623996063 0.759980019685
OS 2.51623996063 0.748980019685
OS 2.4562 0.748980019685
OS 2.4562 0.759980019685
OS 2.45096003937 0.759980019685
OS 2.45048996063 0.75865
OC 2.42595 0.75865 2.438219980315 0.762997440945 Y
OS 2.425480019685 0.759980019685
OS 2.417819980315 0.759980019685
OS 2.41735 0.75865
OC 2.41613996063 0.756130019685 2.405076279528 0.762993110236 Y
OC 2.419530019685 0.750019980315 2.419534645669 0.754018011811 N
OS 2.4201 0.750019980315
OS 2.4201 0.679980019685
OS 2.39006003937 0.679980019685
OS 2.39006003937 0.750019980315
OS 2.390630019685 0.750019980315
OC 2.394019980315 0.756130019685 2.390625295276 0.754018011811 N
OC 2.39281003937 0.75865 2.405083759843 0.76299261811 Y
OS 2.39233996063 0.759980019685
OS 2.319 0.759980019685
OC 2.31501003937 0.755869980315 2.319005511811 0.755982972441 N
OC 2.315019980315 0.755 2.284998917323 0.755092027559 Y
OC 2.285 0.724980019685 2.285 0.755 Y
OS 2.284980019685 0.724980019685
OC 2.27528996063 0.72658996063 2.284989173228 0.755001771654 Y
OC 2.27 0.72281003937 2.273998425197 0.722805807087 N
OS 2.27 0.40898996063
OE
OB 1.531919980315 3.18285 H
OS 1.57375 3.141019980315
OS 1.70065 3.141019980315
OS 1.98175 3.422119980315
OS 2.25855 3.422119980315
OS 2.318519980315 3.36215
OS 2.318519980315 3.34823996063
OS 2.320469980315 3.34623996063
OC 2.33413996063 3.34038996063 2.320005216535 3.326257185039 Y
OS 2.355330019685 3.3192
OC 2.3558 3.318730019685 2.3485 3.3119 Y
OS 2.37413996063 3.30038996063
OC 2.37753996063 3.29586003937 2.360006200787 3.286240748031 Y
OS 2.377669980315 3.29561003937
OS 2.37788996063 3.29538996063
OC 2.38363996063 3.283380019685 2.363754330709 3.281240846457 Y
OS 2.383819980315 3.281919980315
OS 2.49225 3.281919980315
OS 2.53735 3.236819980315
OS 2.53833996063 3.236969980315
OC 2.55906003937 3.238480019685 2.55906023622 3.095566633858 Y
OC 2.701080019685 3.09646003937 2.55906003937 3.09646003937 Y
OC 2.699569980315 3.07573996063 2.558166633858 3.09646023622 Y
OS 2.699419980315 3.07475
OS 2.87915 2.895019980315
OS 3.23585 2.895019980315
OS 3.264980019685 2.92415
OS 3.264980019685 3.00585
OS 2.834980019685 3.43585
OS 2.834980019685 3.57915
OS 2.91585 3.660019980315
OS 3.7817 3.660019980315
OC 3.81 3.680019980315 3.81 3.64999773622 Y
OC 3.834269980315 3.667669980315 3.81 3.64999753937 Y
OC 3.840730019685 3.667669980315 3.8375 3.670027165354 N
OC 3.865 3.680019980315 3.865 3.64999753937 Y
OC 3.8933 3.660019980315 3.865 3.64999773622 Y
OS 4.175 3.660019980315
OC 4.235 3.660019980315 4.205 3.66 Y
OS 4.359 3.660019980315
OC 4.411 3.660019980315 4.385 3.644986712598 Y
OS 4.70091003937 3.660019980315
OC 4.714 3.663019980315 4.713991732283 3.632998129921 Y
OC 4.72708996063 3.660019980315 4.714008267717 3.632998129921 Y
OS 5.232030019685 3.660019980315
OC 5.23586003937 3.66538996063 5.250002952756 3.651251968504 Y
OS 5.25858996063 3.688119980315
OS 5.191719980315 3.755
OS 5.07463996063 3.755
OS 5.07428996063 3.75343996063
OC 5.01571003937 3.75343996063 5.045 3.759994389764 Y
OS 5.01536003937 3.755
OS 3.824919980315 3.755
OS 3.82465 3.75331003937
OC 3.76535 3.75331003937 3.795 3.757998425197 Y
OS 3.765080019685 3.755
OS 3.44963996063 3.755
OS 3.44928996063 3.75343996063
OC 3.42 3.729980019685 3.42 3.759994389764 Y
OC 3.4025 3.73561003937 3.42 3.759993011811 Y
OC 3.385 3.729980019685 3.385 3.759993011811 Y
OC 3.35571003937 3.75343996063 3.385 3.759994389764 Y
OS 3.35536003937 3.755
OS 3.34463996063 3.755
OS 3.34428996063 3.75343996063
OC 3.28571003937 3.75343996063 3.315 3.759994389764 Y
OS 3.28536003937 3.755
OS 2.26106003937 3.755
OC 2.26 3.754980019685 2.259964370079 3.784999311024 Y
OC 2.25893996063 3.755 2.260035629921 3.784999311024 Y
OS 2.21606003937 3.755
OC 2.215 3.754980019685 2.214964370079 3.784999311024 Y
OC 2.21393996063 3.755 2.215035629921 3.784999311024 Y
OS 1.918280019685 3.755
OS 1.80913996063 3.64586003937
OC 1.795 3.64 1.794999901575 3.659989665354 Y
OS 1.77288996063 3.64
OS 1.751319980315 3.618419980315
OS 1.751319980315 3.41765
OS 1.66895 3.335280019685
OS 1.54375 3.335280019685
OS 1.531919980315 3.32345
OS 1.531919980315 3.262519980315
OC 1.540019980315 3.242 1.509997047244 3.242007480315 Y
OC 1.531919980315 3.221480019685 1.509997047244 3.241992519685 Y
OS 1.531919980315 3.18285
OE
OB 1.365 3.68 H
OS 1.786719980315 3.68
OS 1.89586003937 3.78913996063
OC 1.91 3.795 1.910000098425 3.775010334646 Y
OS 2.18668996063 3.795
OC 2.215 3.815019980315 2.214999901575 3.784993602362 Y
OC 2.23608996063 3.80636003937 2.215 3.785009350394 Y
OC 2.23891003937 3.80636003937 2.2375 3.807781988189 N
OC 2.26 3.815019980315 2.26 3.785009350394 Y
OC 2.28831003937 3.795 2.260000098425 3.784993602362 Y
OS 5.2 3.795
OC 5.21413996063 3.78913996063 5.199999901575 3.775010334646 Y
OS 5.29686003937 3.706419980315
OS 5.29711003937 3.70628996063
OC 5.30503996063 3.69836003937 5.2875 3.68875 Y
OS 5.305169980315 3.69811003937
OS 5.30913996063 3.69413996063
OC 5.315 3.68 5.295010334646 3.679999901575 Y
OS 5.315 2.88463996063
OS 5.31656003937 2.88428996063
OC 5.31656003937 2.82571003937 5.310005610236 2.855 Y
OS 5.315 2.82536003937
OS 5.315 2.602530019685
OC 5.315 2.547069980315 5.303499901575 2.5748 Y
OS 5.315 2.323280019685
OS 5.343280019685 2.295
OS 5.45653996063 2.295
OC 5.481580019685 2.30935 5.48157992126 2.280328248031 Y
OC 5.5036 2.299230019685 5.481580019685 2.280333464567 Y
OC 5.50961003937 2.29916003937 5.506635728346 2.301834547244 N
OC 5.531219980315 2.30881003937 5.53122007874 2.279788484252 Y
OC 5.555930019685 2.295 5.531219980315 2.279798425197 Y
OS 5.57016003937 2.295
OC 5.61983996063 2.295 5.595 2.280004822835 Y
OS 5.645969980315 2.295
OC 5.688030019685 2.295 5.667 2.274994389764 Y
OS 5.701719980315 2.295
OS 5.761230019685 2.35451003937
OS 5.7608 2.35571003937
OC 5.758980019685 2.366 5.788999409449 2.366003543307 Y
OC 5.77 2.38923996063 5.788995374016 2.366 Y
OS 5.77 3.085
OC 5.77586003937 3.09913996063 5.789989665354 3.084999901575 Y
OS 5.864219980315 3.1875
OS 5.78586003937 3.26586003937
OC 5.78 3.28 5.799989665354 3.280000098425 Y
OS 5.78 3.54771003937
OC 5.772980019685 3.567 5.802993110236 3.567 Y
OC 5.77956003937 3.58576003937 5.803012992126 3.567 Y
OS 5.78 3.58631003937
OS 5.78 3.59656003937
OS 5.7795 3.597130019685
OC 5.7795 3.636869980315 5.801991141732 3.617 Y
OS 5.78 3.63743996063
OS 5.78 3.645530019685
OS 5.77943996063 3.64611003937
OC 5.77943996063 3.68788996063 5.801001476378 3.667 Y
OS 5.78 3.688469980315
OS 5.78 3.69
OC 5.78586003937 3.70413996063 5.799989665354 3.689999901575 Y
OS 5.8467 3.764980019685
OS 5.8467 3.990519980315
OS 5.782219980315 4.055
OS 5.40336003937 4.055
OC 5.36663996063 4.055 5.385 4.078746161417 Y
OS 5.32831003937 4.055
OC 5.27168996063 4.055 5.3 4.065006397638 Y
OS 5.125 4.055
OC 5.11086003937 4.06086003937 5.125000098425 4.074989665354 Y
OS 5.08518996063 4.086530019685
OC 5.07848996063 4.0847 5.082362401575 4.083702165354 N
OC 4.94093996063 3.97806003937 4.940940059055 4.120089665354 Y
OC 4.798919980315 4.120080019685 4.94093996063 4.120080019685 Y
OC 4.822719980315 4.198780019685 4.940939566929 4.120080019685 Y
OC 4.81938996063 4.205 4.819390059055 4.200998622047 N
OS 3.65028996063 4.205
OC 3.61171003937 4.205 3.631 4.227993110236 Y
OS 3.376119980315 4.205
OC 3.349880019685 4.205 3.363 4.231989074803 Y
OS 2.68061003937 4.205
OC 2.677280019685 4.198780019685 2.680609940945 4.200998622047 N
OC 2.701080019685 4.120080019685 2.559060433071 4.120080019685 Y
OC 2.41703996063 4.120080019685 2.55906003937 4.120080019685 Y
OC 2.44083996063 4.198780019685 2.559059547244 4.120080019685 Y
OC 2.43751003937 4.205 2.43751003937 4.200998622047 N
OS 1.463280019685 4.205
OS 1.45783996063 4.19956003937
OS 1.4589 4.198169980315
OC 1.465019980315 4.18 1.434987007874 4.18 Y
OC 1.435 4.149980019685 1.435 4.18 Y
OC 1.415480019685 4.1572 1.43500738189 4.179997244094 Y
OS 1.380830019685 4.12255
OS 1.38073996063 4.121880019685
OC 1.37293996063 4.10551003937 1.351003444882 4.126005708661 Y
OC 1.382019980315 4.084 1.352002066929 4.084 Y
OC 1.365 4.05693996063 1.351998720472 4.083999901575 Y
OS 1.365 3.98831003937
OC 1.385019980315 3.96 1.354993602362 3.960000098425 Y
OC 1.372669980315 3.935730019685 1.35499753937 3.96 Y
OC 1.372669980315 3.929269980315 1.375027165354 3.9325 N
OC 1.385019980315 3.905 1.35499753937 3.905 Y
OC 1.365 3.87668996063 1.354993602362 3.904999901575 Y
OS 1.365 3.85831003937
OC 1.365 3.80168996063 1.354993602362 3.83 Y
OS 1.365 3.68
OE
OB 0.925 2.857819980315 H
OS 1.88025 2.857819980315
OS 2.2985 3.276069980315
OS 2.2985 3.302430019685
OC 2.2985 3.315069980315 2.306251082677 3.30875 Y
OS 2.2985 3.35386003937
OS 2.25026003937 3.4021
OS 1.99003996063 3.4021
OS 1.711869980315 3.123930019685
OC 1.7048 3.121 1.704799901575 3.13099488189 Y
OS 1.5696 3.121
OC 1.562530019685 3.123930019685 1.569600098425 3.13099488189 Y
OS 1.549630019685 3.136830019685
OC 1.531830019685 3.154630019685 1.56 3.165 Y
OS 1.514830019685 3.171630019685
OC 1.5119 3.1787 1.52189488189 3.178700098425 Y
OS 1.5119 3.3276
OC 1.514830019685 3.334669980315 1.52189488189 3.327599901575 Y
OS 1.532530019685 3.352369980315
OC 1.5396 3.3553 1.539600098425 3.34530511811 Y
OS 1.66066003937 3.3553
OS 1.7313 3.42593996063
OS 1.7313 3.62331003937
OS 1.71461003937 3.64
OS 1.353280019685 3.64
OS 1.26413996063 3.55086003937
OC 1.25 3.545 1.249999901575 3.564989665354 Y
OS 0.973280019685 3.545
OS 0.925 3.496719980315
OS 0.925 2.857819980315
OE
OB 0.925 2.518280019685 H
OS 2.26413996063 1.17913996063
OC 2.27 1.165 2.250010334646 1.164999901575 Y
OS 2.27 0.79788996063
OS 2.28788996063 0.78
OS 2.84086003937 0.78
OS 3.29085 1.22998996063
OS 3.229980019685 1.29085
OS 3.229980019685 1.888980019685
OS 3.213080019685 1.888980019685
OS 3.213080019685 1.917
OS 3.229980019685 1.917
OS 3.229980019685 2.184569980315
OC 3.229980019685 2.230430019685 3.240006200787 2.2075 Y
OS 3.229980019685 2.2467
OC 3.229980019685 2.3033 3.24000226378 2.275 Y
OS 3.229980019685 2.33276003937
OC 3.229980019685 2.38723996063 3.240006791339 2.36 Y
OS 3.229980019685 2.52106003937
OC 3.229980019685 2.57293996063 3.24300757874 2.547 Y
OS 3.229980019685 2.60036003937
OS 3.228419980315 2.60071003937
OC 3.228419980315 2.65928996063 3.235 2.63 Y
OS 3.229980019685 2.65963996063
OS 3.229980019685 2.875
OS 2.875 2.875
OC 2.867930019685 2.877930019685 2.875000098425 2.88499488189 Y
OS 2.6984 3.04746003937
OC 2.69183996063 3.04605 2.695577362205 3.04462726378 N
OC 2.55906003937 2.95443996063 2.559059940945 3.096470964567 Y
OC 2.41703996063 3.09646003937 2.55906003937 3.09646003937 Y
OC 2.50865 3.22923996063 2.559070964567 3.096459940945 Y
OC 2.51006003937 3.2358 2.50722726378 3.232977362205 N
OS 2.48396003937 3.2619
OS 2.368819980315 3.2619
OS 2.368580019685 3.26183996063
OC 2.36375 3.26125 2.363758070866 3.281250787402 Y
OC 2.358919980315 3.26183996063 2.363741929134 3.281250787402 Y
OS 2.358680019685 3.2619
OS 2.347319980315 3.2619
OS 2.347 3.26178996063
OC 2.34375 3.26125 2.343758267717 3.271251181102 Y
OC 2.3405 3.26178996063 2.343741732283 3.271251181102 Y
OS 2.340180019685 3.2619
OS 2.31263996063 3.2619
OS 1.891469980315 2.840730019685
OC 1.8844 2.8378 1.884399901575 2.84779488189 Y
OS 0.925 2.8378
OS 0.925 2.518280019685
OE
OB 0.6 2.238280019685 H
OS 1.69413996063 1.14413996063
OC 1.7 1.13 1.680010334646 1.129999901575 Y
OS 1.7 0.581969980315
OC 1.85165 0.430119980315 1.699799901575 0.430119980315 Y
OS 1.85165 0.262
OS 2.1326 0.262
OS 2.1326 0.29331003937
OC 2.23 0.40898996063 2.249995374016 0.293309940945 Y
OS 2.23 0.55286003937
OS 2.22843996063 0.55321003937
OC 2.22843996063 0.61178996063 2.234994389764 0.5825 Y
OS 2.23 0.61213996063
OS 2.23 1.156719980315
OS 0.94695 2.439769980315
OC 0.93033996063 2.43475 0.930329822835 2.464772933071 Y
OS 0.930319980315 2.43475
OC 0.9003 2.464769980315 0.930319980315 2.464769980315 Y
OS 0.9003 2.464780019685
OC 0.9045 2.48008996063 0.930321456693 2.464775295276 Y
OS 0.90528996063 2.481430019685
OS 0.89086003937 2.49586003937
OC 0.885 2.51 0.904989665354 2.510000098425 Y
OS 0.885 3.496719980315
OS 0.76586003937 3.61586003937
OC 0.76 3.63 0.779989665354 3.630000098425 Y
OS 0.76 3.821719980315
OS 0.736719980315 3.845
OS 0.613280019685 3.845
OS 0.6 3.831719980315
OS 0.6 2.906619980315
OC 0.6 2.873380019685 0.574997637795 2.89 Y
OS 0.6 2.281619980315
OC 0.605019980315 2.265 0.574997637795 2.265 Y
OC 0.60031003937 2.248869980315 0.575013779528 2.265009153543 Y
OS 0.6 2.248380019685
OS 0.6 2.238280019685
OE
OB 0.565 3.883280019685 H
OS 0.58 3.868280019685
OS 0.59086003937 3.87913996063
OC 0.605 3.885 0.605000098425 3.865010334646 Y
OS 0.745 3.885
OC 0.75913996063 3.87913996063 0.744999901575 3.865010334646 Y
OS 0.79413996063 3.84413996063
OC 0.8 3.83 0.780010334646 3.829999901575 Y
OS 0.8 3.638280019685
OS 0.81543996063 3.62283996063
OS 0.816830019685 3.62388996063
OC 0.835 3.630019980315 0.835007874016 3.600002854331 Y
OC 0.865019980315 3.6 0.835 3.6 Y
OC 0.8589 3.581830019685 0.834987007874 3.6 Y
OS 0.85783996063 3.58043996063
OS 0.888330019685 3.54995
OS 0.88921003937 3.549980019685
OC 0.89 3.55 0.890110531496 3.530002362205 Y
OS 0.921719980315 3.55
OS 0.95086003937 3.57913996063
OC 0.965 3.585 0.965000098425 3.565010334646 Y
OS 1.241719980315 3.585
OS 1.325 3.668280019685
OS 1.325 3.829030019685
OC 1.324980019685 3.83 1.35499773622 3.830133169291 Y
OC 1.325 3.830969980315 1.35499773622 3.829866830709 Y
OS 1.325 3.904030019685
OC 1.324980019685 3.905 1.35499773622 3.905133169291 Y
OC 1.325 3.905969980315 1.35499773622 3.904866830709 Y
OS 1.325 3.959030019685
OC 1.324980019685 3.96 1.35499773622 3.960133169291 Y
OC 1.325 3.960969980315 1.35499773622 3.959866830709 Y
OS 1.325 4.070880019685
OC 1.321980019685 4.084 1.351989074803 4.084 Y
OS 1.321980019685 4.08401003937
OC 1.32481003937 4.096730019685 1.352001279528 4.084005511811 Y
OS 1.325 4.09713996063
OS 1.325 4.110980019685
OS 1.32475 4.11143996063
OS 1.32451003937 4.111880019685
OC 1.320980019685 4.126 1.350998917323 4.126003543307 Y
OC 1.351 4.156019980315 1.351 4.126 Y
OC 1.3561 4.155580019685 1.350979330709 4.126001476378 Y
OS 1.357119980315 4.1554
OS 1.44086003937 4.23913996063
OC 1.455 4.245 1.455000098425 4.225010334646 Y
OS 2.49148996063 4.245
OC 2.55905 4.2621 2.559052755906 4.120078149606 Y
OS 2.559069980315 4.2621
OC 2.626630019685 4.245 2.559067224409 4.120078149606 Y
OS 3.184330019685 4.245
OS 3.18481003937 4.24631003937
OC 3.24118996063 4.24631003937 3.213 4.236005807087 Y
OS 3.241669980315 4.245
OS 3.33593996063 4.245
OC 3.39006003937 4.245 3.363 4.231998720472 Y
OS 3.60626003937 4.245
OC 3.65573996063 4.245 3.631 4.22800511811 Y
OS 4.139369980315 4.245
OS 4.139730019685 4.24655
OC 4.168 4.269019980315 4.168 4.240001476378 Y
OC 4.192330019685 4.255819980315 4.168000098425 4.23999773622 Y
OC 4.19903996063 4.255819980315 4.19568503937 4.257995570866 N
OC 4.223369980315 4.269019980315 4.22336988189 4.23999773622 Y
OC 4.25163996063 4.24655 4.223369980315 4.240001476378 Y
OS 4.252 4.245
OS 4.873369980315 4.245
OC 4.940930019685 4.2621 4.940932775591 4.120078149606 Y
OS 4.94093996063 4.2621
OC 5.080169980315 4.14811003937 4.940940059055 4.120075688976 Y
OS 5.133280019685 4.095
OS 5.299030019685 4.095
OC 5.3 4.095019980315 5.300133169291 4.06500226378 Y
OC 5.300969980315 4.095 5.299866830709 4.06500226378 Y
OS 5.35976003937 4.095
OC 5.41023996063 4.095 5.385 4.078752952756 Y
OS 5.7905 4.095
OC 5.80463996063 4.08913996063 5.790499901575 4.075010334646 Y
OS 5.88083996063 4.01293996063
OC 5.8867 3.9988 5.866710334646 3.998799901575 Y
OS 5.8867 3.75921003937
OC 5.97175 3.67843996063 5.88778769685 3.675192027559 Y
OS 5.971819980315 3.676819980315
OS 5.971819980315 3.34448996063
OC 5.88778996063 3.26046003937 5.887790059055 3.34448996063 Y
OC 5.84973996063 3.269569980315 5.887789862205 3.34447726378 Y
OC 5.8451 3.263180019685 5.84793011811 3.266004527559 N
OS 5.898280019685 3.21
OS 6.041719980315 3.21
OS 6.115 3.283280019685
OS 6.115 3.826719980315
OS 6.04586003937 3.89586003937
OC 6.04 3.91 6.059989665354 3.910000098425 Y
OS 6.04 4.275469980315
OS 6.01948996063 4.295980019685
OS 0.58801003937 4.295980019685
OS 0.565 4.272969980315
OS 0.565 3.883280019685
OE
OB 0.08 0.257169980315 H
OS 0.201819980315 0.257169980315
OC 0.20445 0.264180019685 0.201818503937 0.261168897638 N
OC 0.15726003937 0.36808996063 0.295283661417 0.368101968504 Y
OS 0.15726003937 0.36811003937
OC 0.4333 0.36811003937 0.295280019685 0.36811003937 Y
OS 0.4333 0.36808996063
OC 0.38611003937 0.264180019685 0.295276377953 0.368101968504 Y
OC 0.38873996063 0.257169980315 0.388741535433 0.261168897638 N
OS 0.51055 0.257169980315
OS 0.51055 0.4626
OC 0.629919980315 0.581969980315 0.629919980315 0.4626 Y
OS 1.16536003937 0.581969980315
OS 1.16571003937 0.583530019685
OC 1.22428996063 0.583530019685 1.195 0.576937204724 Y
OS 1.22463996063 0.581969980315
OS 1.273619980315 0.581969980315
OC 1.39298996063 0.4626 1.273619980315 0.4626 Y
OS 1.39298996063 0.257169980315
OS 1.54795 0.257169980315
OS 1.54795 0.430119980315
OC 1.66 0.57666003937 1.699798129921 0.43012007874 Y
OS 1.66 1.121719980315
OS 0.92171003937 1.86001003937
OS 0.920369980315 1.85921003937
OC 0.90501003937 1.854980019685 0.905004822835 1.885001377953 Y
OS 0.905 1.854980019685
OC 0.874980019685 1.885 0.905 1.885 Y
OS 0.874980019685 1.88501003937
OC 0.87921003937 1.900369980315 0.905001377953 1.885004822835 Y
OS 0.88001003937 1.90171003937
OS 0.56586003937 2.21586003937
OC 0.56 2.23 0.579989665354 2.230000098425 Y
OS 0.56 2.239
OC 0.56 2.291 0.574993307087 2.265 Y
OS 0.56 2.864
OC 0.56 2.916 0.574993307087 2.89 Y
OS 0.56 3.831719980315
OS 0.53086003937 3.86086003937
OC 0.525 3.875 0.544989665354 3.875000098425 Y
OS 0.525 4.270469980315
OS 0.49948996063 4.295980019685
OS 0.08 4.295980019685
OS 0.08 2.58718996063
OC 0.08 2.46321003937 0.060393208661 2.5252 Y
OS 0.08 2.38718996063
OC 0.08 2.26321003937 0.060393208661 2.3252 Y
OS 0.08 2.016319980315
OC 0.08 1.89233996063 0.060393208661 1.954330019685 Y
OS 0.08 1.816319980315
OC 0.08 1.69233996063 0.060393208661 1.754330019685 Y
OS 0.08 1.44545
OC 0.08 1.321469980315 0.060393208661 1.38346003937 Y
OS 0.08 1.24545
OC 0.08 1.121469980315 0.060393208661 1.18346003937 Y
OS 0.08 0.87458996063
OC 0.08 0.75061003937 0.060393208661 0.8126 Y
OS 0.08 0.67458996063
OC 0.12541003937 0.6126 0.060393208661 0.612599901575 Y
OC 0.08 0.55061003937 0.060393208661 0.612600098425 Y
OS 0.08 0.257169980315
OE
OB 0.43331003937 3.73031003937 I
OC 0.43331003937 3.73031003937 0.295280019685 3.73031003937 Y
OE
OB 0.688980019685 3.560980019685 I
OS 0.688980019685 3.589019980315
OS 0.749019980315 3.589019980315
OS 0.749019980315 3.560980019685
OS 0.688980019685 3.560980019685
OE
OB 1.043980019685 3.795980019685 I
OS 1.043980019685 3.854019980315
OS 1.134019980315 3.854019980315
OS 1.134019980315 3.795980019685
OS 1.043980019685 3.795980019685
OE
OB 1.3307 1.840430019685 I
OC 1.3307 1.840430019685 1.260669980315 1.840430019685 Y
OE
OB 1.4977 1.060430019685 I
OC 1.4977 1.060430019685 1.435669980315 1.060430019685 Y
OE
OB 1.5227 2.680430019685 I
OC 1.5227 2.680430019685 1.460669980315 2.680430019685 Y
OE
OB 2.7477 1.121430019685 I
OC 2.7477 1.121430019685 2.685669980315 1.121430019685 Y
OE
OB 2.7477 2.559430019685 I
OC 2.7477 2.559430019685 2.685669980315 2.559430019685 Y
OE
OB 2.629380019685 0.338980019685 I
OS 2.629380019685 0.399019980315
OS 2.6574 0.399019980315
OS 2.6574 0.338980019685
OS 2.629380019685 0.338980019685
OE
OB 2.783 1.971980019685 I
OS 2.783 2.002019980315
OS 2.853019980315 2.002019980315
OS 2.853019980315 1.971980019685
OS 2.783 1.971980019685
OE
OB 2.78686003937 0.338980019685 I
OS 2.78686003937 0.399019980315
OS 2.814880019685 0.399019980315
OS 2.814880019685 0.338980019685
OS 2.78686003937 0.338980019685
OE
OB 2.9307 1.040430019685 I
OC 2.9307 1.040430019685 2.860669980315 1.040430019685 Y
OE
OB 2.829980019685 1.823980019685 I
OS 2.829980019685 1.894019980315
OS 2.860019980315 1.894019980315
OS 2.860019980315 1.823980019685
OS 2.829980019685 1.823980019685
OE
OB 2.94433996063 0.338980019685 I
OS 2.94433996063 0.399019980315
OS 2.97236003937 0.399019980315
OS 2.97236003937 0.338980019685
OS 2.94433996063 0.338980019685
OE
OB 2.94433996063 0.434980019685 I
OS 2.94433996063 0.495019980315
OS 2.97236003937 0.495019980315
OS 2.97236003937 0.434980019685
OS 2.94433996063 0.434980019685
OE
OB 3.10516003937 0.875 I
OS 3.125 0.89483996063
OS 3.167469980315 0.852369980315
OS 3.147630019685 0.832530019685
OS 3.10516003937 0.875
OE
OB 3.398980019685 1.069980019685 I
OS 3.398980019685 1.100019980315
OS 3.469019980315 1.100019980315
OS 3.469019980315 1.069980019685
OS 3.398980019685 1.069980019685
OE
OB 3.439 1.884980019685 I
OS 3.439 1.945
OS 3.467019980315 1.945
OS 3.467019980315 1.884980019685
OS 3.439 1.884980019685
OE
OB 3.49563996063 1.03206003937 I
OS 3.49563996063 1.062080019685
OS 3.56566003937 1.062080019685
OS 3.56566003937 1.03206003937
OS 3.49563996063 1.03206003937
OE
OB 3.610980019685 0.905980019685 I
OS 3.610980019685 0.934019980315
OS 3.671019980315 0.934019980315
OS 3.671019980315 0.905980019685
OS 3.610980019685 0.905980019685
OE
OB 3.637 1.869580019685 I
OS 3.637 1.9296
OS 3.665019980315 1.9296
OS 3.665019980315 1.869580019685
OS 3.637 1.869580019685
OE
OB 3.871930019685 1.417019980315 I
OC 3.871930019685 1.443080019685 3.871930019685 1.43005 Y
OS 3.9113 1.443080019685
OC 3.9113 1.417019980315 3.9113 1.43005 Y
OS 3.871930019685 1.417019980315
OE
OB 3.871930019685 1.49576003937 I
OC 3.871930019685 1.521819980315 3.871930019685 1.508790059055 Y
OS 3.9113 1.521819980315
OC 3.9113 1.49576003937 3.9113 1.508790059055 Y
OS 3.871930019685 1.49576003937
OE
OB 3.871930019685 1.5745 I
OC 3.871930019685 1.60056003937 3.871930019685 1.587530019685 Y
OS 3.9113 1.60056003937
OC 3.9113 1.5745 3.9113 1.587530019685 Y
OS 3.871930019685 1.5745
OE
OB 3.871930019685 1.65323996063 I
OC 3.871930019685 1.6793 3.871930019685 1.666269980315 Y
OS 3.9113 1.6793
OC 3.9113 1.65323996063 3.9113 1.666269980315 Y
OS 3.871930019685 1.65323996063
OE
OB 3.950669980315 1.53513996063 I
OC 3.950669980315 1.561180019685 3.950669980315 1.54816003937 Y
OS 3.99003996063 1.561180019685
OC 3.99003996063 1.53513996063 3.99003996063 1.54816003937 Y
OS 3.950669980315 1.53513996063
OE
OB 3.950669980315 1.613880019685 I
OC 3.950669980315 1.639919980315 3.950669980315 1.6269 Y
OS 3.99003996063 1.639919980315
OC 3.99003996063 1.613880019685 3.99003996063 1.6269 Y
OS 3.950669980315 1.613880019685
OE
OB 4.029419980315 1.49576003937 I
OC 4.029419980315 1.521819980315 4.029419980315 1.508790059055 Y
OS 4.06878996063 1.521819980315
OC 4.06878996063 1.49576003937 4.06878996063 1.508790059055 Y
OS 4.029419980315 1.49576003937
OE
OB 4.029419980315 1.65323996063 I
OC 4.029419980315 1.6793 4.029419980315 1.666269980315 Y
OS 4.06878996063 1.6793
OC 4.06878996063 1.65323996063 4.06878996063 1.666269980315 Y
OS 4.029419980315 1.65323996063
OE
OB 4.42311003937 1.850080019685 I
OC 4.42311003937 1.87613996063 4.42311003937 1.86311003937 Y
OS 4.462480019685 1.87613996063
OC 4.462480019685 1.850080019685 4.462480019685 1.86311003937 Y
OS 4.42311003937 1.850080019685
OE
OB 4.5223 1.20666003937 I
OS 4.5223 1.236680019685
OS 4.592319980315 1.236680019685
OS 4.592319980315 1.20666003937
OS 4.5223 1.20666003937
OE
OB 4.61996003937 1.2989 I
OC 4.61996003937 1.32496003937 4.61996003937 1.311930019685 Y
OS 4.659330019685 1.32496003937
OC 4.659330019685 1.2989 4.659330019685 1.311930019685 Y
OS 4.61996003937 1.2989
OE
OB 4.72503996063 1.3513 I
OS 4.72503996063 1.390669980315
OC 4.7511 1.390669980315 4.738069980315 1.390669980315 Y
OS 4.7511 1.3513
OC 4.72503996063 1.3513 4.738069980315 1.3513 Y
OE
OB 5.082969980315 3.09646003937 I
OC 5.082969980315 3.09646003937 4.94093996063 3.09646003937 Y
OE
OB 5.974969980315 1.045 I
OC 5.984369980315 1.1056 6.174999507874 1.045001377953 Y
OC 5.97846003937 1.12348996063 6.008502165354 1.123493208661 Y
OS 5.97846003937 1.1235
OC 6.00696003937 1.1535 6.008499507874 1.1235 Y
OC 6.175 1.245030019685 6.175000098425 1.045012598425 Y
OC 6.375030019685 1.045 6.175 1.045 Y
OC 6.362830019685 0.97621003937 6.174992913386 1.045 Y
OC 6.365 0.96501003937 6.334998523622 0.965007480315 Y
OS 6.365 0.965
OC 6.342730019685 0.93601003937 6.334996161417 0.965 Y
OC 6.175 0.844969980315 6.174999901575 1.045000984252 Y
OC 5.974969980315 1.045 6.175 1.045 Y
OE
OB 6.1856 2.230719980315 I
OS 6.1856 2.29076003937
OS 6.213619980315 2.29076003937
OS 6.213619980315 2.230719980315
OS 6.1856 2.230719980315
OE
OB 6.424580019685 3.34448996063 I
OC 6.424580019685 3.34448996063 6.34055 3.34448996063 Y
OE
OB 6.424580019685 3.67518996063 I
OC 6.424580019685 3.67518996063 6.34055 3.67518996063 Y
OE
SE
P 4.31 4.065 6 P 0 8 0;1=0
P 4.31 4.115 6 P 0 8 0;1=0
P 4.61 2.3 6 P 0 8 0;1=0
P 4.50185 2.05996004 4 P 0 8 0;1=1
P 4.49 2.275 6 P 0 8 0;1=0
P 4.435 2.315 6 P 0 8 0;1=0
P 4.49 2.325 6 P 0 8 0;1=0
P 4.435 2.365 6 P 0 8 0;1=0
P 3.655 2.465 6 P 0 8 0;1=0
P 3.125 1.605 6 P 0 8 0;1=0
P 3.65 2.68 6 P 0 8 0;1=2
P 3.12 2.645 6 P 0 8 0;1=2
P 4.1869 2.09933002 4 P 0 8 0;1=1
P 3.765 2.69 6 P 0 8 0;1=0
P 4.50185 1.50878996 4 P 0 8 0;1=1
P 4.3 3.865 4 P 0 8 0;1=3
P 3.36525 3.305 3 P 0 8 0;1=4
P 3.37 3.44 4 P 0 8 0;1=3
P 4.795 0.925 4 P 0 8 0;1=3
P 4.08 3.27 4 P 0 8 0;1=3
P 3.95 3.82 4 P 0 8 0;1=3
P 3.746 1.782 4 P 0 8 0;1=3
P 4.06878996 1.58753002 4 P 0 8 0;1=1
P 4.205 0.82 4 P 0 8 0;1=3
P 3.82286004 0.86213996 6 P 0 8 0;1=0
P 3.705 0.84 4 P 0 8 0;1=3
P 0.496 2.13455 6 P 0 8 0;1=0
P 0.528 2.72 6 P 0 8 0;1=0
P 0.575 1.015 6 P 0 8 0;1=0
P 0.48956998 1.53618996 6 P 0 8 0;1=0
P 4.65933002 1.98121998 4 P 0 8 0;1=1
P 4.06878996 1.90248002 4 P 0 8 0;1=1
P 4.50185 1.39066998 4 P 0 8 0;1=1
P 4.06878996 2.1387 4 P 0 8 0;1=1
P 4.22626998 2.05996004 4 P 0 8 0;1=1
P 3.95066998 2.05996004 4 P 0 8 0;1=1
P 4.22626998 2.02058996 4 P 0 8 0;1=1
P 4.26563996 2.09933002 4 P 0 8 0;1=1
P 4.26563996 2.05996004 4 P 0 8 0;1=1
P 4.50185 1.90248002 4 P 0 8 0;1=1
P 4.73806998 2.09933002 4 P 0 8 0;1=1
P 4.02941998 2.02058996 4 P 0 8 0;1=1
P 4.50185 1.86311004 4 P 0 8 0;1=1
P 4.6987 2.05996004 4 P 0 8 0;1=1
P 4.61996004 1.94185 4 P 0 8 0;1=1
P 4.61996004 1.98121998 4 P 0 8 0;1=1
P 4.26563996 2.02058996 4 P 0 8 0;1=1
P 4.61996004 1.90248002 4 P 0 8 0;1=1
P 4.58058996 1.98121998 4 P 0 8 0;1=1
P 4.54121998 2.02058996 4 P 0 8 0;1=1
P 4.34436998 2.09933002 4 P 0 8 0;1=1
P 4.06878996 2.09933002 4 P 0 8 0;1=5
P 4.6987 1.50878996 4 P 0 8 0;1=1
P 4.54121998 1.98121998 4 P 0 8 0;1=1
P 4.06878996 2.05996004 4 P 0 8 0;1=1
P 4.65933002 1.50878996 4 P 0 8 0;1=1
P 3.95066998 2.09933002 4 P 0 8 0;1=1
P 4.61996004 1.54816004 4 P 0 8 0;1=1
P 3.99005 2.09933002 4 P 0 8 0;1=5
P 4.58058996 1.54816004 4 P 0 8 0;1=1
P 4.6987 1.94185 4 P 0 8 0;1=1
P 4.50185 2.02058996 4 P 0 8 0;1=1
P 4.46248002 2.02058996 4 P 0 8 0;1=1
P 4.42311004 1.98121998 4 P 0 8 0;1=1
P 4.46248002 1.94185 4 P 0 8 0;1=1
P 4.38373996 1.86311004 4 P 0 8 0;1=1
P 4.38373996 1.82373996 4 P 0 8 0;1=1
P 4.46248002 1.98121998 4 P 0 8 0;1=1
P 4.10816004 1.94185 4 P 0 8 0;1=1
P 4.02941998 1.98121998 4 P 0 8 0;1=1
P 4.58058996 2.17806998 4 P 0 8 0;1=1
P 4.73806998 1.90248002 4 P 0 8 0;1=1
P 4.54121998 2.1387 4 P 0 8 0;1=1
P 4.10816004 2.02058996 4 P 0 8 0;1=1
P 4.50185 2.1387 4 P 0 8 0;1=1
P 3.99005 1.94185 4 P 0 8 0;1=1
P 4.02941998 1.94185 4 P 0 8 0;1=1
P 4.50185 2.09933002 4 P 0 8 0;1=1
P 4.14753002 2.02058996 4 P 0 8 0;1=1
P 4.61996004 2.17806998 4 P 0 8 0;1=1
P 4.02941998 1.86311004 4 P 0 8 0;1=1
P 4.06878996 1.43005 4 P 0 8 0;1=1
P 4.54121998 1.54816004 4 P 0 8 0;1=1
P 4.26563996 1.50878996 4 P 0 8 0;1=1
P 4.1869 1.94185 4 P 0 8 0;1=1
P 4.14753002 1.46941998 4 P 0 8 0;1=1
P 4.1869 1.46941998 4 P 0 8 0;1=1
P 4.1869 2.1387 4 P 0 8 0;1=1
P 4.6987 1.43005 4 P 0 8 0;1=1
P 4.10816004 1.39066998 4 P 0 8 0;1=1
P 4.65933002 1.43005 4 P 0 8 0;1=1
P 4.14753002 1.39066998 4 P 0 8 0;1=1
P 4.61996004 1.43005 4 P 0 8 0;1=1
P 4.10816004 1.43005 4 P 0 8 0;1=1
P 4.58058996 1.43005 4 P 0 8 0;1=1
P 4.14753002 1.43005 4 P 0 8 0;1=1
P 4.1869 1.43005 4 P 0 8 0;1=1
P 4.22626998 1.43005 4 P 0 8 0;1=1
P 4.54121998 1.46941998 4 P 0 8 0;1=1
P 4.22626998 1.39066998 4 P 0 8 0;1=1
P 4.50185 1.46941998 4 P 0 8 0;1=1
P 4.26563996 1.39066998 4 P 0 8 0;1=1
P 4.61996004 1.46941998 4 P 0 8 0;1=1
P 4.26563996 1.31193002 4 P 0 8 0;1=1
P 4.61996004 1.50878996 4 P 0 8 0;1=1
P 4.34436998 1.31193002 4 P 0 8 0;1=1
P 4.58058996 1.46941998 4 P 0 8 0;1=1
P 4.34436998 1.3513 4 P 0 8 0;1=1
P 4.54121998 1.50878996 4 P 0 8 0;1=1
P 4.34436998 1.39066998 4 P 0 8 0;1=1
P 4.1869 1.50878996 4 P 0 8 0;1=1
P 4.46248002 1.50878996 4 P 0 8 0;1=1
P 4.22626998 1.50878996 4 P 0 8 0;1=1
P 4.26563996 1.43005 4 P 0 8 0;1=5
P 4.26563996 1.46941998 4 P 0 8 0;1=1
P 4.38373996 1.39066998 4 P 0 8 0;1=1
P 4.38373996 1.43005 4 P 0 8 0;1=1
P 4.54121998 1.31193002 4 P 0 8 0;1=1
P 4.49876004 1.31501998 4 P 0 8 0;1=1
P 4.34436998 1.98121998 4 P 0 8 0;1=1
P 4.57843996 1.35345 4 P 0 8 0;1=1
P 3.9113 1.3513 4 P 0 8 0;1=1
P 4.54121998 1.3513 4 P 0 8 0;1=1
P 3.95066998 1.3513 4 P 0 8 0;1=1
P 4.45938996 1.35438996 4 P 0 8 0;1=1
P 3.99 1.31188002 4 P 0 8 0;1=1
P 4.46248002 1.39066998 4 P 0 8 0;1=1
P 4.65933002 1.3513 4 P 0 8 0;1=1
P 3.99 1.35125 4 P 0 8 0;1=1
P 4.61996004 1.3513 4 P 0 8 0;1=1
P 4.6987 1.86311004 4 P 0 8 0;1=1
P 4.46248002 2.05996004 4 P 0 8 0;1=1
P 4.06873996 1.31188002 4 P 0 8 0;1=1
P 4.65933002 1.82373996 4 P 0 8 0;1=1
P 4.42311004 2.05996004 4 P 0 8 0;1=1
P 4.10811004 1.31188002 4 P 0 8 0;1=1
P 4.58058996 1.39066998 4 P 0 8 0;1=1
P 4.02941998 1.39066998 4 P 0 8 0;1=1
P 4.54121998 1.39066998 4 P 0 8 0;1=1
P 4.06878996 1.39066998 4 P 0 8 0;1=1
P 4.73806998 1.78436998 4 P 0 8 0;1=1
P 4.73806998 1.31193002 4 P 0 8 0;1=1
P 4.1869 1.31193002 4 P 0 8 0;1=1
P 4.73806998 1.70563996 4 P 0 8 0;1=1
P 4.6987 1.31193002 4 P 0 8 0;1=1
P 4.22626998 1.31193002 4 P 0 8 0;1=1
P 4.10816004 1.3513 4 P 0 8 0;1=1
P 4.14753002 1.3513 4 P 0 8 0;1=1
P 4.6987 1.39066998 4 P 0 8 0;1=1
P 4.1869 1.3513 4 P 0 8 0;1=1
P 4.65933002 1.39066998 4 P 0 8 0;1=1
P 4.22626998 1.3513 4 P 0 8 0;1=1
P 4.73806998 2.17806998 4 P 0 8 0;1=1
P 4.73806998 2.1387 4 P 0 8 0;1=1
P 4.58058996 2.09933002 4 P 0 8 0;1=1
P 4.54121998 2.09933002 4 P 0 8 0;1=1
P 4.58058996 1.86311004 4 P 0 8 0;1=1
P 4.65933002 2.05996004 4 P 0 8 0;1=1
P 4.58058996 2.05996004 4 P 0 8 0;1=1
P 4.54121998 1.90248002 4 P 0 8 0;1=1
P 4.58058996 2.02058996 4 P 0 8 0;1=1
P 4.22626998 1.98121998 4 P 0 8 0;1=1
P 4.26563996 1.94185 4 P 0 8 0;1=1
P 4.10816004 1.98121998 4 P 0 8 0;1=1
P 4.14753002 1.98121998 4 P 0 8 0;1=1
P 4.61996004 2.1387 4 P 0 8 0;1=1
P 4.6987 1.70563996 4 P 0 8 0;1=1
P 4.6987 1.66626998 4 P 0 8 0;1=1
P 1.45 3.59 6 P 0 8 0;1=0
P 1.56 3.165 6 P 0 8 0;1=2
P 1.56 3.205 6 P 0 8 0;1=0
P 0.72 3.463 6 P 0 8 0;1=2
P 0.42326004 3.4315 8 P 0 8 0;1=6
P 0.40553996 3.4008 8 P 0 8 0;1=6
P 0.2815 3.4315 8 P 0 8 0;1=6
P 0.26378002 3.4008 8 P 0 8 0;1=6
P 0.71 3.305 4 P 0 8 0;1=3
P 1.14 3.52 6 P 0 8 0;1=0
P 1.245 3.52 6 P 0 8 0;1=0
P 4.705 3.95 3 P 0 8 0;1=4
P 4.705 3.91 6 P 0 8 0;1=2
P 1.566 2.95 6 P 0 8 0;1=0
P 1.045 3.77 6 P 0 8 0;1=2
P 6.145 4.035 6 P 0 8 0;1=0
P 2.19 3.488 6 P 0 8 0;1=2
P 5.275 3.891 6 P 0 8 0;1=0
P 5.275 3.931 6 P 0 8 0;1=2
P 5.275 3.971 6 P 0 8 0;1=0
P 5.321 3.99 6 P 0 8 0;1=2
P 5.762 3.425 5 P 0 8 0;1=7
P 5.567 3.203 6 P 0 8 0;1=2
P 5.617 3.203 6 P 0 8 0;1=0
P 5.62 3.316 6 P 0 8 0;1=2
P 5.625 3.261 6 P 0 8 0;1=0
P 5.625 3.361 6 P 0 8 0;1=2
P 5.6 3.421 6 P 0 8 0;1=0
P 5.552 3.71141004 5 P 0 8 0;1=8
P 5.552 3.74683996 5 P 0 8 0;1=8
P 5.552 3.78226998 5 P 0 8 0;1=8
P 5.552 3.67596998 5 P 0 8 0;1=8
P 5.52 3.78226998 5 P 0 8 0;1=8
P 5.52 3.74683996 5 P 0 8 0;1=8
P 5.52 3.71141004 5 P 0 8 0;1=8
P 5.52 3.67596998 5 P 0 8 0;1=8
P 0.978 3.918 4 P 0 8 0;1=3
P 0.928 3.961 6 P 0 8 0;1=2
P 0.968 3.961 6 P 0 8 0;1=2
P 0.968 4.021 6 P 0 8 0;1=2
P 0.928 4.021 6 P 0 8 0;1=0
P 0.928 4.081 6 P 0 8 0;1=2
P 0.968 4.081 6 P 0 8 0;1=0
P 0.928 4.141 6 P 0 8 0;1=0
P 0.968 4.141 6 P 0 8 0;1=2
P 0.603 3.951 6 P 0 8 0;1=0
P 0.643 3.956 6 P 0 8 0;1=2
P 0.603 4.011 6 P 0 8 0;1=2
P 0.643 4.016 6 P 0 8 0;1=0
P 0.603 4.071 6 P 0 8 0;1=0
P 0.643 4.076 6 P 0 8 0;1=2
P 0.603 4.131 6 P 0 8 0;1=2
P 0.643 4.136 6 P 0 8 0;1=0
P 0.854 3.942 6 P 0 8 0;1=2
P 0.807 3.942 6 P 0 8 0;1=2
P 0.76 3.942 6 P 0 8 0;1=2
P 0.713 3.942 6 P 0 8 0;1=2
P 0.76 4.042 6 P 0 8 0;1=2
P 0.76 3.992 6 P 0 8 0;1=2
P 0.713 3.992 6 P 0 8 0;1=2
P 0.713 4.042 6 P 0 8 0;1=2
P 0.713 4.092 6 P 0 8 0;1=2
P 0.76 4.092 6 P 0 8 0;1=2
P 0.807 4.092 6 P 0 8 0;1=2
P 0.807 4.042 6 P 0 8 0;1=2
P 0.807 3.992 6 P 0 8 0;1=2
P 0.854 3.992 6 P 0 8 0;1=2
P 0.854 4.042 6 P 0 8 0;1=2
P 0.854 4.092 6 P 0 8 0;1=2
P 0.74 1.005 6 P 0 8 0;1=0
P 0.79 1.005 6 P 0 8 0;1=0
P 0.84 1.005 6 P 0 8 0;1=0
P 1.568 3.011 6 P 0 8 0;1=0
P 1.738 3.241 6 P 0 8 0;1=0
P 1.765 2.9 6 P 0 8 0;1=0
P 1.78 3.095 6 P 0 8 0;1=0
P 1.795 2.946 6 P 0 8 0;1=0
P 5.2 0.87 6 P 0 8 0;1=0
P 4.47 3.21998002 6 P 0 8 0;1=0
P 4.385 3.645 6 P 0 8 0;1=0
P 0.78 3.305 4 P 0 8 0;1=3
P 1.03 3.515 6 P 0 8 0;1=0
P 1.19 3.52 6 P 0 8 0;1=0
P 0.95 2.915 4 P 0 8 0;1=3
P 0.945 2.99 4 P 0 8 0;1=3
P 0.885 3.03 4 P 0 8 0;1=3
P 0.875 2.955 4 P 0 8 0;1=3
P 0.795 3.085 4 P 0 8 0;1=3
P 0.55 3.36 6 P 0 8 0;1=0
P 0.3701 3.4008 8 P 0 8 0;1=6
P 0.55 3.554 6 P 0 8 0;1=0
P 0.31693996 3.4315 8 P 0 8 0;1=6
P 5.92 1.57063002 6 P 0 8 0;1=0
P 6.22 1.57 6 P 0 8 0;1=0
P 5.92 1.46 6 P 0 8 0;1=0
P 6.22 1.465 6 P 0 8 0;1=0
P 5.92 1.68 6 P 0 8 0;1=0
P 6.22035 1.67063002 6 P 0 8 0;1=0
P 5.92 1.78 6 P 0 8 0;1=0
P 6.22 1.755 6 P 0 8 0;1=0
P 6.09423996 4.13778996 6 P 0 8 0;1=0
P 3.51 3.08 6 P 0 8 0;1=0
P 1.025 2.9 6 P 0 8 0;1=2
P 4.42311004 1.94185 4 P 0 8 0;1=1
P 3.46 3.065 6 P 0 8 0;1=0
P 1.125 2.9 6 P 0 8 0;1=2
P 4.42311004 1.90248002 4 P 0 8 0;1=1
P 3.035 1.64 6 P 0 8 0;1=2
P 3.445 2.65 4 P 0 8 0;1=3
P 1.1288 0.7302 5 P 0 8 0;1=7
P 3.075 1.605 6 P 0 8 0;1=2
P 3.365 2.95 3 P 0 8 0;1=4
P 0.755 0.62 4 P 0 8 0;1=3
P 0.715 0.77 6 P 0 8 0;1=0
P 0.83 3.445 6 P 0 8 0;1=0
P 0.795 3.485 6 P 0 8 0;1=0
P 0.83 3.525 6 P 0 8 0;1=0
P 0.951 3.519 6 P 0 8 0;1=0
P 0.82951004 3.2794 6 P 0 8 0;1=0
P 0.79 3.155 6 P 0 8 0;1=0
P 0.78635 3.24491998 6 P 0 8 0;1=0
P 1.26 3.18 6 P 0 8 0;1=0
P 1.295 3.28 6 P 0 8 0;1=0
P 1.075 3.02 6 P 0 8 0;1=0
P 1.125 3.02 6 P 0 8 0;1=0
P 1.073 3.825 4 P 0 8 0;1=9
P 0.703 3.575 4 P 0 8 0;1=9
P 0.35238002 3.4315 8 P 0 8 0;1=6
P 0.33466004 3.4008 8 P 0 8 0;1=6
P 0.735 3.575 4 P 0 8 0;1=9
P 1.105 3.825 4 P 0 8 0;1=9
P 0.38781998 3.4315 8 P 0 8 0;1=6
P 0.29921998 3.4008 8 P 0 8 0;1=6
P 0.995 3.7 4 P 0 8 0;1=3
P 4.285 3.46 6 P 0 8 0;1=2
P 2.15 3.438 6 P 0 8 0;1=0
P 2.05 3.538 6 P 0 8 0;1=0
P 2.05 3.488 6 P 0 8 0;1=0
P 1.29 3.215 6 P 0 8 0;1=2
P 1.0541 3.185 6 P 0 8 0;1=0
P 1.3 3.49663996 6 P 0 8 0;1=2
P 1.04018996 3.47425 6 P 0 8 0;1=2
P 4.205 3.66 6 P 0 8 0;1=0
P 0.975 3.41 6 P 0 8 0;1=2
P 4.225 3.545 6 P 0 8 0;1=0
P 1.015 3.41 6 P 0 8 0;1=2
P 3.95 3.6 6 P 0 8 0;1=0
P 0.835 3.6 6 P 0 8 0;1=2
P 3.95 3.7 6 P 0 8 0;1=0
P 0.915 3.595 6 P 0 8 0;1=2
P 4.1184 3.5362 6 P 0 8 0;1=2
P 4.085 3.11 6 P 0 8 0;1=0
P 4.51 3.065 6 P 0 8 0;1=2
P 4.33381998 3.60466004 6 P 0 8 0;1=0
P 4.34 3.28 6 P 0 8 0;1=2
P 4.335 3.665 6 P 0 8 0;1=0
P 4.09 3.71338996 6 P 0 8 0;1=0
P 3.38 1.025 6 P 0 8 0;1=2
P 4.585 0.865 6 P 0 8 0;1=0
P 0.62 3.235 6 P 0 8 0;1=2
P 3.925 3.239 6 P 0 8 0;1=0
P 0.825 3.39 6 P 0 8 0;1=2
P 0.795 3.4179 6 P 0 8 0;1=2
P 3.795 3.758 6 P 0 8 0;1=0
P 3.62 1.28 6 P 0 8 0;1=2
P 5.195 0.755 6 P 0 8 0;1=0
P 4.96 0.85 6 P 0 8 0;1=2
P 0.66 3.185 6 P 0 8 0;1=2
P 3.62 1.235 6 P 0 8 0;1=2
P 5.195 0.815 6 P 0 8 0;1=0
P 4.937 0.79161004 6 P 0 8 0;1=2
P 0.66 3.235 6 P 0 8 0;1=2
P 4.205 3.81 6 P 0 8 0;1=2
P 5.814 2.821 5 P 0 8 0;1=7
P 4.19 3.735 6 P 0 8 0;1=2
P 5.814 2.721 5 P 0 8 0;1=7
P 3.895 3.7 6 P 0 8 0;1=2
P 5.815 3.021 5 P 0 8 0;1=7
P 4.135 3.735 6 P 0 8 0;1=2
P 5.814 2.621 5 P 0 8 0;1=7
P 2.3 3.475 6 P 0 8 0;1=2
P 5.045 3.405 6 P 0 8 0;1=2
P 6.33 2.67 5 P 0 8 0;1=7
P 1.35 3.12 6 P 0 8 0;1=2
P 2.255 3.475 6 P 0 8 0;1=2
P 5.09 3.405 6 P 0 8 0;1=2
P 6.33 2.865 6 P 0 8 0;1=0
P 1.46 3.34 6 P 0 8 0;1=2
P 4.575 2.235 6 P 0 8 0;1=2
P 4.50185 1.94185 4 P 0 8 0;1=1
P 4.705 0.825 6 P 0 8 0;1=0
P 4.575 2.275 6 P 0 8 0;1=2
P 4.38373996 1.98121998 4 P 0 8 0;1=1
P 4.755 0.825 6 P 0 8 0;1=0
P 1.26 0.72 6 P 0 8 0;1=0
P 4.6987 1.82373996 4 P 0 8 0;1=1
P 0.842 0.75 6 P 0 8 0;1=0
P 4.73806998 1.82373996 4 P 0 8 0;1=1
P 4.10816004 1.90248002 4 P 0 8 0;1=5
P 3.73648996 1.85735 6 P 0 8 0;1=2
P 4.10816004 1.82373996 4 P 0 8 0;1=1
P 4.345 3.02 6 P 0 8 0;1=2
P 4.075 3.005 6 P 0 8 0;1=2
P 3.925 3.291 6 P 0 8 0;1=0
P 4.14753002 1.82373996 4 P 0 8 0;1=1
P 4.39 3.02 6 P 0 8 0;1=2
P 4.13 3.005 6 P 0 8 0;1=2
P 3.795 3.81 6 P 0 8 0;1=0
P 4.615 3.11 6 P 0 8 0;1=2
P 4.6987 1.90248002 4 P 0 8 0;1=1
P 4.4 3.325 6 P 0 8 0;1=0
P 4.615 2.68408996 6 P 0 8 0;1=2
P 4.15 2.468 6 P 0 8 0;1=2
P 6.22 1.415 6 P 0 8 0;1=0
P 4.685 2.7 6 P 0 8 0;1=2
P 4.209 2.468 6 P 0 8 0;1=2
P 4.34436998 2.1387 4 P 0 8 0;1=1
P 6.22 1.516 6 P 0 8 0;1=0
P 4.975 2.26 6 P 0 8 0;1=2
P 4.093 2.468 6 P 0 8 0;1=2
P 6.22 1.62 6 P 0 8 0;1=0
P 4.925 2.26 6 P 0 8 0;1=0
P 4.037 2.468 6 P 0 8 0;1=2
P 6.22 1.815 6 P 0 8 0;1=0
P 5.92 1.41 6 P 0 8 0;1=0
P 5.09 2.155 6 P 0 8 0;1=2
P 3.801 2.468 6 P 0 8 0;1=2
P 4.10816004 2.09933002 4 P 0 8 0;1=1
P 5.92 1.515 6 P 0 8 0;1=0
P 5.135 2.155 6 P 0 8 0;1=2
P 3.86 2.468 6 P 0 8 0;1=2
P 4.14753002 2.09933002 4 P 0 8 0;1=1
P 5.92 1.63 6 P 0 8 0;1=0
P 5.115 2.065 6 P 0 8 0;1=2
P 3.919 2.468 6 P 0 8 0;1=2
P 5.92 1.73 6 P 0 8 0;1=0
P 5.13 2.105 6 P 0 8 0;1=2
P 3.978 2.468 6 P 0 8 0;1=2
P 4.685 2.645 6 P 0 8 0;1=2
P 4.1 3.38 6 P 0 8 0;1=0
P 4.53 2.5 6 P 0 8 0;1=2
P 3.9 3.385 6 P 0 8 0;1=0
P 4.485 3.115 6 P 0 8 0;1=0
P 4.575 2.374 6 P 0 8 0;1=2
P 4.485 2.5 6 P 0 8 0;1=2
P 4.29441998 3.10075 6 P 0 8 0;1=0
P 4.61 2.345 6 P 0 8 0;1=2
P 4.54 3.125 6 P 0 8 0;1=0
P 4.085 3.21998002 6 P 0 8 0;1=0
P 4.35 2.505 6 P 0 8 0;1=2
P 5.365 0.79 6 P 0 8 0;1=0
P 5.365 0.845 6 P 0 8 0;1=0
P 4.0661 3.5341 6 P 0 8 0;1=0
P 3.83 3.466 5 P 0 8 0;1=7
P 4.35143002 3.06643002 6 P 0 8 0;1=2
P 3.7 3.325 6 P 0 8 0;1=0
P 3.5825 3.4005 3 P 0 8 0;1=4
P 4.33 3.1432 6 P 0 8 0;1=2
P 3.83 3.235 6 P 0 8 0;1=0
P 4.085 3.165 6 P 0 8 0;1=2
P 3.415 3.335 3 P 0 8 0;1=4
P 0.74 1.3 6 P 0 8 0;1=2
P 1.26 0.62 5 P 0 8 0;1=7
P 0.785 0.8225 6 P 0 8 0;1=2
P 0.695 1.3 6 P 0 8 0;1=2
P 1.26 0.67 5 P 0 8 0;1=7
P 0.76321004 0.783 6 P 0 8 0;1=2
P 3.32 3.015 4 P 0 8 0;1=3
P 3.24 3.01 4 P 0 8 0;1=3
P 0.606 1.57 6 P 0 8 0;1=0
P 0.835 1.73 6 P 0 8 0;1=0
P 0.355 3.27 6 P 0 8 0;1=0
P 0.28 3.27 6 P 0 8 0;1=0
P 0.13 3.187 6 P 0 8 0;1=0
P 0.69023002 1.98523996 6 P 0 8 0;1=2
P 0.125 2.195 6 P 0 8 0;1=0
P 0.69 1.93 6 P 0 8 0;1=2
P 0.125 2.145 6 P 0 8 0;1=0
P 0.69 1.875 6 P 0 8 0;1=2
P 0.125 2.045 6 P 0 8 0;1=0
P 0.13 2.73326998 6 P 0 8 0;1=0
P 0.287 2.743 6 P 0 8 0;1=0
P 0.125 2.615 6 P 0 8 0;1=0
P 0.735 1.19 6 P 0 8 0;1=2
P 0.125 1.06 6 P 0 8 0;1=0
P 0.68 1.19 6 P 0 8 0;1=2
P 0.125 1.01 6 P 0 8 0;1=0
P 0.675 1.145 6 P 0 8 0;1=2
P 0.125 0.91 6 P 0 8 0;1=0
P 0.125 1.62 6 P 0 8 0;1=0
P 0.13 1.57 6 P 0 8 0;1=0
P 0.1362 1.4872 6 P 0 8 0;1=0
P 2.937 3.173 6 P 0 8 0;1=0
P 3.01 3.17 6 P 0 8 0;1=2
P 0.896 2.489 3 P 0 8 0;1=4
P 4.31168996 4.01168996 3 P 0 8 0;1=4
P 4.319 3.922 3 P 0 8 0;1=4
P 4.5 4.115 6 P 0 8 0;1=0
P 1.315 2.905 5 P 0 8 0;1=8
P 2.932 3.295 5 P 0 8 0;1=8
P 0.915 1.4 6 P 0 8 0;1=2
P 1.42 0.69535 5 P 0 8 0;1=7
P 4.5 4.165 6 P 0 8 0;1=0
P 1.36 2.905 5 P 0 8 0;1=8
P 2.896 3.301 5 P 0 8 0;1=8
P 0.965 1.4 6 P 0 8 0;1=2
P 1.4207 0.779 5 P 0 8 0;1=7
P 4.65933002 2.02058996 4 P 0 8 0;1=5
P 4.33 3.535 6 P 0 8 0;1=2
P 4.44 4.065 3 P 0 8 0;1=4
P 4.61996004 2.05996004 4 P 0 8 0;1=1
P 4.395 3.415 5 P 0 8 0;1=8
P 4.44 4.115 3 P 0 8 0;1=4
P 4.61996004 2.09933002 4 P 0 8 0;1=1
P 4.425 3.36088996 5 P 0 8 0;1=8
P 0.638 2.74 5 P 0 8 0;1=8
P 0.825 2.305 3 P 0 8 0;1=4
P 0.755 2.825 5 P 0 8 0;1=8
P 0.795 2.345 3 P 0 8 0;1=4
P 5.97613002 4.13778996 6 P 0 8 0;1=0
P 5.90748002 4.18725 6 P 0 8 0;1=0
P 4.06878996 2.02058996 4 P 0 8 0;1=1
P 0.905 1.935 6 P 0 8 0;1=0
P 3.99005 2.05996004 4 P 0 8 0;1=1
P 0.945 1.97 6 P 0 8 0;1=0
P 4.02941998 2.05996004 4 P 0 8 0;1=1
P 0.905 1.885 6 P 0 8 0;1=0
P 0.63 2.15 6 P 0 8 0;1=2
P 3.95066998 2.02058996 4 P 0 8 0;1=1
P 0.985 2.185 6 P 0 8 0;1=0
P 0.287 2.62508002 6 P 0 8 0;1=2
P 0.43 2.555 6 P 0 8 0;1=0
P 3.95066998 1.98121998 4 P 0 8 0;1=1
P 0.63 2.105 6 P 0 8 0;1=2
P 0.99 2.015 6 P 0 8 0;1=2
P 0.242 2.62508002 6 P 0 8 0;1=0
P 3.99005 1.98121998 4 P 0 8 0;1=1
P 0.63 2.06 6 P 0 8 0;1=2
P 0.99 1.975 6 P 0 8 0;1=2
P 4.02941998 1.82373996 4 P 0 8 0;1=1
P 0.935 1.3 6 P 0 8 0;1=0
P 3.95066998 1.90248002 4 P 0 8 0;1=1
P 0.87 1.255 6 P 0 8 0;1=0
P 3.95066998 1.86311004 4 P 0 8 0;1=1
P 0.935 1.25 6 P 0 8 0;1=0
P 4.06878996 1.94185 4 P 0 8 0;1=1
P 0.92 1.73 6 P 0 8 0;1=0
P 0.281 1.48798002 6 P 0 8 0;1=2
P 4.06878996 1.86311004 4 P 0 8 0;1=1
P 0.985 1.655 6 P 0 8 0;1=0
P 0.371 1.48798002 6 P 0 8 0;1=2
P 4.06878996 1.82373996 4 P 0 8 0;1=1
P 0.985 1.59 6 P 0 8 0;1=0
P 0.236 1.48798002 6 P 0 8 0;1=2
P 0.345 3.09 6 P 0 8 0;1=2
P 3.84091004 2.00091004 6 P 0 8 0;1=0
P 0.99 1.885 6 P 0 8 0;1=2
P 0.395 3.09 6 P 0 8 0;1=2
P 3.87193002 2.09933002 4 P 0 8 0;1=5
P 0.99 2.065 6 P 0 8 0;1=2
P 0.445 3.09 6 P 0 8 0;1=0
P 3.9113 2.09933002 4 P 0 8 0;1=1
P 0.975 2.14 6 P 0 8 0;1=2
P 0.53 2.005 6 P 0 8 0;1=0
P 0.552 2.535 6 P 0 8 0;1=0
P 0.455 1.825 6 P 0 8 0;1=0
P 0.16038996 1.85433002 10 P 0 8 0;1=10
P 0.46 2.195 6 P 0 8 0;1=0
P 0.16038996 2.4252 10 P 0 8 0;1=10
P 0.445 0.735 6 P 0 8 0;1=0
P 0.16038996 0.7126 10 P 0 8 0;1=10
P 0.455 1.0439 6 P 0 8 0;1=0
P 0.16038996 1.28346004 10 P 0 8 0;1=10
P 0.535 1.835 6 P 0 8 0;1=0
P 0.532 2.40186998 6 P 0 8 0;1=0
P 0.505 0.60228002 6 P 0 8 0;1=0
P 0.5374 1.26 6 P 0 8 0;1=0
P 0.48 2.005 6 P 0 8 0;1=0
P 0.485 2.525 6 P 0 8 0;1=0
P 0.515 0.835 6 P 0 8 0;1=0
P 0.475 1.405 6 P 0 8 0;1=0
P 6.335 0.965 6 P 0 8 0;1=0
P 6.335 1.02 6 P 0 8 0;1=0
P 6.335 1.08 6 P 0 8 0;1=0
P 2.085 3.017 5 P 0 8 0;1=7
P 2.135 3.017 5 P 0 8 0;1=7
P 2.185 3.017 5 P 0 8 0;1=7
P 6.0085 1.1235 6 P 0 8 0;1=0
P 2.22 3.3 5 P 0 8 0;1=7
P 5.8 1.048 4 P 0 8 0;1=3
P 4.34436998 2.02058996 4 P 0 8 0;1=1
P 5.285 2.99 5 P 0 8 0;1=8
P 3.125 3.075 6 P 0 8 0;1=2
P 4.34436998 2.17806998 4 P 0 8 0;1=1
P 2.017 3.279 4 P 0 8 0;1=3
P 0.636 2.915 4 P 0 8 0;1=3
P 4.38373996 2.17806998 4 P 0 8 0;1=1
P 2.97 3.105 6 P 0 8 0;1=0
P 5.91 2.785 6 P 0 8 0;1=0
P 5.91 2.615 5 P 0 8 0;1=7
P 5.91 2.915 6 P 0 8 0;1=0
P 5.91 2.715 6 P 0 8 0;1=0
P 0.54 2.135 6 P 0 8 0;1=2
P 0.67 1.09 6 P 0 8 0;1=0
P 4.61996004 1.66626998 4 P 0 8 0;1=1
P 0.45 2.13 6 P 0 8 0;1=2
P 4.6987 2.09933002 4 P 0 8 0;1=1
P 0.965 2.355 6 P 0 8 0;1=0
P 4.5806 1.70563996 4 P 0 8 0;1=1
P 0.735 1.125 6 P 0 8 0;1=0
P 0.48231998 2.6453 6 P 0 8 0;1=2
P 3.755 3.505 5 P 0 8 0;1=8
P 4.6987 2.1387 4 P 0 8 0;1=1
P 0.525 2.78 6 P 0 8 0;1=2
P 4.6 0.76 6 P 0 8 0;1=2
P 4.61996004 1.78436998 4 P 0 8 0;1=1
P 0.905 1.05 6 P 0 8 0;1=2
P 4.175 0.75 6 P 0 8 0;1=2
P 0.51765 0.966 3 P 0 8 0;1=4
P 2.078 0.8301 6 P 0 8 0;1=2
P 0.46 0.82 3 P 0 8 0;1=4
P 4.65933002 1.78436998 4 P 0 8 0;1=1
P 0.5413 1.525 6 P 0 8 0;1=0
P 4.61996004 1.70563996 4 P 0 8 0;1=1
P 0.625 1.005 6 P 0 8 0;1=2
P 4.65933002 1.70563996 4 P 0 8 0;1=1
P 0.935 1.105 6 P 0 8 0;1=0
P 0.4839 1.28311998 6 P 0 8 0;1=2
P 1.128 0.666 3 P 0 8 0;1=4
P 5.97613002 4.27558002 6 P 0 8 0;1=0
P 4.14753002 1.86311004 4 P 0 8 0;1=1
P 0.945 1.63 6 P 0 8 0;1=2
P 0.635 0.845 4 P 0 8 0;1=3
P 4.1869 1.86311004 4 P 0 8 0;1=1
P 0.975 1.72 6 P 0 8 0;1=2
P 0.644 0.7 4 P 0 8 0;1=3
P 0.555 0.59 6 P 0 8 0;1=0
P 3.935 3.91 5 P 0 8 0;1=7
P 0.835 1.885 6 P 0 8 0;1=2
P 3.885 3.91 5 P 0 8 0;1=7
P 0.835 1.93 6 P 0 8 0;1=2
P 3.985 3.91 5 P 0 8 0;1=7
P 0.835 1.78 6 P 0 8 0;1=2
P 0.645 1.295 4 P 0 8 0;1=3
P 4.1869 1.90248002 4 P 0 8 0;1=1
P 0.955 1.92 6 P 0 8 0;1=2
P 0.565 1.13 4 P 0 8 0;1=3
P 4.14753002 1.90248002 4 P 0 8 0;1=1
P 0.885 1.49 6 P 0 8 0;1=0
P 0.99 1.755 6 P 0 8 0;1=2
P 3.935 4 5 P 0 8 0;1=8
P 0.332 2.62508002 6 P 0 8 0;1=0
P 3.885 4 5 P 0 8 0;1=8
P 0.405 2.62 6 P 0 8 0;1=0
P 3.985 4 5 P 0 8 0;1=8
P 0.19 2.625 6 P 0 8 0;1=0
P 0.62 1.995 4 P 0 8 0;1=3
P 4.34436998 1.82373996 4 P 0 8 0;1=1
P 0.75 1.417 6 P 0 8 0;1=2
P 4.26563996 1.82373996 4 P 0 8 0;1=1
P 0.952 1.51 6 P 0 8 0;1=0
P 0.545 1.71 4 P 0 8 0;1=3
P 0.415 1.275 6 P 0 8 0;1=2
P 0.87 1.2 6 P 0 8 0;1=2
P 0.7558 4.19003996 5 P 0 8 0;1=7
P 3.98 4.185 5 P 0 8 0;1=8
P 0.465 1.33 6 P 0 8 0;1=2
P 0.87 1.3 6 P 0 8 0;1=2
P 0.705 4.19 5 P 0 8 0;1=7
P 4.03 4.185 5 P 0 8 0;1=8
P 0.41408996 1.32591004 6 P 0 8 0;1=2
P 0.89 1.105 6 P 0 8 0;1=2
P 0.805 4.205 6 P 0 8 0;1=0
P 3.93 4.185 5 P 0 8 0;1=8
P 0.647 2.517 4 P 0 8 0;1=3
P 4.22626998 1.82373996 4 P 0 8 0;1=1
P 0.939 1.552 6 P 0 8 0;1=2
P 0.575 2.265 4 P 0 8 0;1=3
P 4.22626998 1.86311004 4 P 0 8 0;1=1
P 0.957 2.275 6 P 0 8 0;1=0
P 4.168 4.24 5 P 0 8 0;1=8
P 0.855 4.205 5 P 0 8 0;1=8
P 0.15 2.79 6 P 0 8 0;1=0
P 0.326 1.487 6 P 0 8 0;1=2
P 0.09 2.86 6 P 0 8 0;1=0
P 0.9 4.205 5 P 0 8 0;1=8
P 4.22336998 4.24 5 P 0 8 0;1=8
P 0.416 1.48798002 6 P 0 8 0;1=2
P 0.09 2.79 6 P 0 8 0;1=0
P 0.98 4.2 5 P 0 8 0;1=8
P 4.14 4.19 5 P 0 8 0;1=8
P 0.191 1.48798002 6 P 0 8 0;1=2
P 4.10463002 3.83 5 P 0 8 0;1=7
P 0.33 3.145 6 P 0 8 0;1=2
P 4.05463002 3.83 5 P 0 8 0;1=7
P 0.43 3.145 6 P 0 8 0;1=2
P 4.15463002 3.83 5 P 0 8 0;1=7
P 0.18 3.145 6 P 0 8 0;1=2
P 0.869 2.672 6 P 0 8 0;1=2
P 0.871 2.713 3 P 0 8 0;1=4
P 0.686 2.74 5 P 0 8 0;1=8
P 0.64248002 2.58 6 P 0 8 0;1=2
P 0.736 2.525 5 P 0 8 0;1=8
P 0.714 2.329 6 P 0 8 0;1=2
P 3.429 2.468 3 P 0 8 0;1=4
P 3.51 2.33243002 6 P 0 8 0;1=2
P 3.278 2.468 3 P 0 8 0;1=4
P 3.243 2.547 3 P 0 8 0;1=4
P 3.385 2.135 4 P 0 8 0;1=3
P 3.24 2.36 3 P 0 8 0;1=4
P 3.285 2.38645 3 P 0 8 0;1=4
P 0.832 2.603 6 P 0 8 0;1=0
P 0.77963996 2.601 3 P 0 8 0;1=4
P 0.695 2.578 6 P 0 8 0;1=0
P 0.72 2.714 3 P 0 8 0;1=4
P 0.825 2.732 3 P 0 8 0;1=4
P 6.01953002 2.18853002 6 P 0 8 0;1=0
P 4.415 2.975 3 P 0 8 0;1=4
P 6.09423996 4.27558002 6 P 0 8 0;1=0
P 0.959 2.789 6 P 0 8 0;1=2
P 0.845 2.18 6 P 0 8 0;1=0
P 5.955 2.39 4 P 0 8 0;1=3
P 5.94153002 2.205 5 P 0 8 0;1=7
P 6.01901998 2.001 5 P 0 8 0;1=7
P 5.87 1.84 4 P 0 8 0;1=3
P 3.4593 2.17 5 P 0 8 0;1=7
P 3.44 2.12 6 P 0 8 0;1=0
P 4.34436998 1.94185 4 P 0 8 0;1=1
P 3.18 2.685 3 P 0 8 0;1=4
P 3.523 1.75 5 P 0 8 0;1=8
P 4.712 1.157 4 P 0 8 0;1=3
P 4.42311004 1.50878996 4 P 0 8 0;1=1
P 4.61996004 1.6269 4 P 0 8 0;1=3
P 4.29 1.235 4 P 0 8 0;1=3
P 4.38373996 1.46941998 4 P 0 8 0;1=1
P 4.15 1.235 4 P 0 8 0;1=3
P 4.34436998 1.50878996 4 P 0 8 0;1=1
P 5.035 1.49 4 P 0 8 0;1=3
P 4.65933002 1.58753002 4 P 0 8 0;1=1
P 4.185 1.17 4 P 0 8 0;1=3
P 4.34436998 1.46941998 4 P 0 8 0;1=1
P 4.816 1.258 4 P 0 8 0;1=3
P 4.665 1.104 4 P 0 8 0;1=3
P 4.38373996 1.3513 4 P 0 8 0;1=1
P 4.91 1.54 4 P 0 8 0;1=3
P 4.768 1.207 4 P 0 8 0;1=3
P 4.42311004 1.46941998 4 P 0 8 0;1=1
P 5.03 1.55 4 P 0 8 0;1=3
P 4.58058996 1.6269 4 P 0 8 0;1=1
P 4.828 1.103 4 P 0 8 0;1=3
P 4.42311004 1.43005 4 P 0 8 0;1=1
P 4.83 1.33 4 P 0 8 0;1=3
P 4.22 1.235 4 P 0 8 0;1=3
P 3.83128002 1.78371998 5 P 0 8 0;1=8
P 6.02558996 4.175 6 P 0 8 0;1=0
P 6.1437 4.175 6 P 0 8 0;1=0
P 3.87193002 1.86311004 4 P 0 8 0;1=1
P 4.14753002 2.05996004 4 P 0 8 0;1=1
P 5.83 2.97 6 P 0 8 0;1=2
P 5.89953002 2.366 5 P 0 8 0;1=7
P 3.61123996 3.49876004 3 P 0 8 0;1=4
P 4.54121998 1.94185 4 P 0 8 0;1=1
P 4.22626998 1.94185 4 P 0 8 0;1=1
P 1.96496998 0.76501998 5 P 0 8 0;1=7
P 4.1869 1.98121998 4 P 0 8 0;1=1
P 3.12 2.565 6 P 0 8 0;1=2
P 3.119 2.299 6 P 0 8 0;1=0
P 4.26563996 1.90248002 4 P 0 8 0;1=1
P 3.385 2.59 6 P 0 8 0;1=0
P 5.155 2.01 6 P 0 8 0;1=2
P 6.025 1.83 6 P 0 8 0;1=0
P 4.1869 2.05996004 4 P 0 8 0;1=1
P 4.34436998 1.90248002 4 P 0 8 0;1=1
P 2.554 2.901 6 P 0 8 0;1=0
P 4.75 1.63 4 P 0 8 0;1=5
P 3.205 1.7 6 P 0 8 0;1=0
P 4.775 1.705 6 P 0 8 0;1=2
P 4.84 1.855 6 P 0 8 0;1=0
P 4.58058996 1.82373996 4 P 0 8 0;1=1
P 4.65933002 1.86311004 4 P 0 8 0;1=1
P 4.815 1.93 6 P 0 8 0;1=0
P 4.885 3.46 6 P 0 8 0;1=2
P 4.61996004 1.86311004 4 P 0 8 0;1=1
P 4.83501004 3.46 6 P 0 8 0;1=0
P 3.125 2.254 6 P 0 8 0;1=2
P 4.26563996 1.86311004 4 P 0 8 0;1=5
P 3.12 2.69 6 P 0 8 0;1=2
P 4.565 3.055 6 P 0 8 0;1=2
P 4.3 3.81 6 P 0 8 0;1=0
P 1.3825 3.7225 5 P 0 8 0;1=8
P 5.905 3.015 5 P 0 8 0;1=7
P 5.41 0.96 4 P 0 8 0;1=3
P 4.85033002 1.74933996 6 P 0 8 0;1=2
P 4.54121998 1.78436998 4 P 0 8 0;1=1
P 5.26 2.955 6 P 0 8 0;1=2
P 3.625 0.92 4 P 0 8 0;1=9
P 6.19961004 2.27673996 4 P 0 8 0;1=9
P 3.657 0.92 4 P 0 8 0;1=9
P 6.19961004 2.24473996 4 P 0 8 0;1=9
P 3.3255 2.1355 6 P 0 8 0;1=0
P 3.35153002 2.17875 6 P 0 8 0;1=2
P 3.44 2.95 3 P 0 8 0;1=4
P 3.27923002 2.21576998 6 P 0 8 0;1=2
P 3.3435 2.82 3 P 0 8 0;1=4
P 4.46 2.94 6 P 0 8 0;1=0
P 4.47 2.83 6 P 0 8 0;1=0
P 3.106 3.26 6 P 0 8 0;1=2
P 3.222 3.385 5 P 0 8 0;1=8
P 3.106 3.35 5 P 0 8 0;1=8
P 1.959 3.325 6 P 0 8 0;1=2
P 3.222 3.205 5 P 0 8 0;1=8
P 3.49 2.955 6 P 0 8 0;1=2
P 3.98 3.365 6 P 0 8 0;1=2
P 3.7 3.37 6 P 0 8 0;1=2
P 3.55 3.37 6 P 0 8 0;1=2
P 4.175 3.37 6 P 0 8 0;1=2
P 3.71 3.26 6 P 0 8 0;1=2
P 3.55 3.28 5 P 0 8 0;1=8
P 3.414 3.235 6 P 0 8 0;1=2
P 3.41 3.04 6 P 0 8 0;1=2
P 3.548 2.856 5 P 0 8 0;1=8
P 3.5768 2.7178 6 P 0 8 0;1=2
P 3.395 2.82 6 P 0 8 0;1=2
P 3.58 2.615 4 P 0 8 0;1=3
P 3.485 2.6 6 P 0 8 0;1=2
P 3.525 2.6 6 P 0 8 0;1=2
P 3.335 2.589 6 P 0 8 0;1=2
P 3.24 2.2075 6 P 0 8 0;1=2
P 4.905 2.1675 6 P 0 8 0;1=2
P 4.85 2.02738996 6 P 0 8 0;1=2
P 4.965 1.975 6 P 0 8 0;1=2
P 3.49128002 1.86628002 6 P 0 8 0;1=2
P 4.65933002 1.66626998 4 P 0 8 0;1=1
P 3.758 2.552 6 P 0 8 0;1=2
P 3.735 2.47 6 P 0 8 0;1=2
P 5.0395 1.335 6 P 0 8 0;1=2
P 4.97 1.75 6 P 0 8 0;1=0
P 4.96 1.63 6 P 0 8 0;1=2
P 3.839 3.846 6 P 0 8 0;1=2
P 4.384 3.824 6 P 0 8 0;1=2
P 4.95 3.46 6 P 0 8 0;1=2
P 5.19 3.075 6 P 0 8 0;1=2
P 5.375 3.04 6 P 0 8 0;1=2
P 5.41 2.815 6 P 0 8 0;1=2
P 5.544 2.675 6 P 0 8 0;1=2
P 5.62 2.5487 6 P 0 8 0;1=2
P 5.42 2.9645 6 P 0 8 0;1=2
P 4.645 2.985 6 P 0 8 0;1=2
P 4.61 3.025 6 P 0 8 0;1=2
P 4.43 3.865 5 P 0 8 0;1=8
P 5.221 4.165 6 P 0 8 0;1=2
P 4.32 3.965 5 P 0 8 0;1=8
P 4.535 3.815 6 P 0 8 0;1=2
P 4.509 3.309 6 P 0 8 0;1=2
P 4.235 4.155 6 P 0 8 0;1=2
P 4.505 3.685 6 P 0 8 0;1=2
P 5.975 4.219 6 P 0 8 0;1=2
P 5.84 4.219 6 P 0 8 0;1=2
P 4.655 0.785 6 P 0 8 0;1=2
P 4.635 0.92 6 P 0 8 0;1=2
P 5.249 0.99 6 P 0 8 0;1=2
P 5.53 1.085 6 P 0 8 0;1=2
P 5.33 0.82 6 P 0 8 0;1=2
P 5.265 0.675 6 P 0 8 0;1=2
P 2.964 0.702 6 P 0 8 0;1=2
P 5.515 0.59596998 6 P 0 8 0;1=2
P 2.0477 0.6778 6 P 0 8 0;1=2
P 2.285 0.755 6 P 0 8 0;1=2
P 1.826 2.895 6 P 0 8 0;1=2
P 1.401 3.069 6 P 0 8 0;1=2
P 0.78 2.915 6 P 0 8 0;1=2
P 0.674 2.271 6 P 0 8 0;1=2
P 0.857 2.365 6 P 0 8 0;1=2
P 0.677 2.402 6 P 0 8 0;1=2
P 4.6987 1.54816004 4 P 0 8 0;1=1
P 4.58058996 1.50878996 4 P 0 8 0;1=1
P 4.14753002 1.50878996 4 P 0 8 0;1=1
P 4.73806998 1.43005 4 P 0 8 0;1=1
P 4.61996004 1.39066998 4 P 0 8 0;1=1
P 4.50185 1.3513 4 P 0 8 0;1=1
P 4.46248002 1.46941998 4 P 0 8 0;1=1
P 4.38373996 1.31193002 4 P 0 8 0;1=1
P 4.34436998 1.43005 4 P 0 8 0;1=1
P 4.1869 1.39066998 4 P 0 8 0;1=1
P 4.06878996 1.3513 4 P 0 8 0;1=1
P 3.95066998 1.31193002 4 P 0 8 0;1=1
P 5.039 1.2869 6 P 0 8 0;1=2
P 5.0386 1.2415 6 P 0 8 0;1=2
P 4.625 1.17 6 P 0 8 0;1=2
P 4.485 1.005 6 P 0 8 0;1=2
P 3.69171998 1.02828002 6 P 0 8 0;1=2
P 3.6931 1.095 6 P 0 8 0;1=2
P 6.04 3.98 6 P 0 8 0;1=2
P 5.445 0.795 4 P 0 8 0;1=3
P 5.494 0.816 6 P 0 8 0;1=2
P 5.443 0.871 6 P 0 8 0;1=2
P 5.49 0.78223002 6 P 0 8 0;1=2
P 3.795 4.175 6 P 0 8 0;1=2
P 3.66 3.5085 6 P 0 8 0;1=2
P 3.105 3.21 6 P 0 8 0;1=2
P 5.55 4.02 6 P 0 8 0;1=2
P 5.01 2.635 6 P 0 8 0;1=0
P 5 2.78798996 5 P 0 8 0;1=7
P 5.226 2.762 5 P 0 8 0;1=7
P 3.775 2.235 6 P 0 8 0;1=2
P 3.775 2.265 6 P 0 8 0;1=0
P 3.775 2.21 6 P 0 8 0;1=2
P 3.775 2.185 6 P 0 8 0;1=2
P 4.42311004 1.78436998 4 P 0 8 0;1=1
P 4.46248002 1.70563996 4 P 0 8 0;1=1
P 4.34436998 1.78436998 4 P 0 8 0;1=1
P 4.22626998 1.78436998 4 P 0 8 0;1=1
P 4.22626998 1.66626998 4 P 0 8 0;1=1
P 4.14753002 1.78436998 4 P 0 8 0;1=1
P 4.02941998 1.78436998 4 P 0 8 0;1=1
P 5.765 0.98 4 P 0 8 0;1=3
P 1.385 3.875 5 P 0 8 0;1=7
P 5.31 2.855 6 P 0 8 0;1=2
P 4.608 2.942 6 P 0 8 0;1=2
P 4.25 3.81 6 P 0 8 0;1=2
P 0.99 2.60025 6 P 0 8 0;1=2
P 0.985 2.56661004 6 P 0 8 0;1=2
P 3.555 2.23 6 P 0 8 0;1=2
P 3.555 2.255 6 P 0 8 0;1=2
P 3.555 2.205 6 P 0 8 0;1=2
P 3.555 2.18 6 P 0 8 0;1=2
P 5.345 2.536 4 P 0 8 0;1=3
P 5.22 2.47 6 P 0 8 0;1=2
P 5.254 2.47 6 P 0 8 0;1=2
P 5.239 2.571 6 P 0 8 0;1=2
P 5.243 2.617 6 P 0 8 0;1=2
P 5.224 2.707 5 P 0 8 0;1=7
P 5.005 2.711 5 P 0 8 0;1=7
P 3.793 3.05 3 P 0 8 0;1=4
P 3.96981004 3.04481998 6 P 0 8 0;1=0
P 3.948 2.813 6 P 0 8 0;1=0
P 4.831 2.728 4 P 0 8 0;1=3
P 3.894 2.811 6 P 0 8 0;1=0
P 3.916 3.048 3 P 0 8 0;1=4
P 5.589 2.025 6 P 0 8 0;1=0
P 5.546 2.024 6 P 0 8 0;1=2
P 5.69943002 2.233 6 P 0 8 0;1=0
P 5.48158002 2.28033002 5 P 0 8 0;1=7
P 5.145 1.44 6 P 0 8 0;1=0
P 5.76 2.465 4 P 0 8 0;1=3
P 4.2136 3.5997 3 P 0 8 0;1=4
P 3.755 3.092 6 P 0 8 0;1=2
P 5.58 1.615 4 P 0 8 0;1=3
P 5.654 2.447 6 P 0 8 0;1=2
P 5.667 2.275 5 P 0 8 0;1=7
P 5.595 2.28 5 P 0 8 0;1=7
P 5.483 2.226 6 P 0 8 0;1=0
P 5.6695 2.2 6 P 0 8 0;1=2
P 5.771 2.279 5 P 0 8 0;1=7
P 5.789 2.366 6 P 0 8 0;1=2
P 5.6 2.4 6 P 0 8 0;1=2
P 5.6 4.01 4 P 0 8 0;1=3
P 5.55568996 3.88051004 3 P 0 8 0;1=4
P 5.765 2.197 6 P 0 8 0;1=0
P 5.71 2.179 6 P 0 8 0;1=2
P 5.41 2.164 6 P 0 8 0;1=0
P 5.458 2.165 6 P 0 8 0;1=2
P 5.465 2.405 6 P 0 8 0;1=2
P 5.53121998 2.27978996 5 P 0 8 0;1=7
P 3.817 0.924 5 P 0 8 0;1=7
P 4.25 0.877 6 P 0 8 0;1=0
P 5.495 0.694 5 P 0 8 0;1=7
P 5.49 0.635 6 P 0 8 0;1=0
P 5.725 0.60301004 5 P 0 8 0;1=7
P 5.686 0.76 5 P 0 8 0;1=7
P 5.7287 0.6757 5 P 0 8 0;1=7
P 5.38558002 4.13778996 6 P 0 8 0;1=0
P 5.485 4.11 6 P 0 8 0;1=0
P 5.725 4.135 6 P 0 8 0;1=0
P 5.6218 4.13778996 6 P 0 8 0;1=0
P 5.323 4.257 5 P 0 8 0;1=7
P 3.83 3.335 3 P 0 8 0;1=4
P 3.415 3.285 3 P 0 8 0;1=4
P 3.83 3.285 3 P 0 8 0;1=4
P 3.415 3.385 3 P 0 8 0;1=4
P 4.83871004 1.98241004 6 P 0 8 0;1=0
P 4.80288002 2.03788002 6 P 0 8 0;1=0
P 4.97 3.41 6 P 0 8 0;1=0
P 4.38373996 1.90248002 4 P 0 8 0;1=1
P 4.81 3.41 6 P 0 8 0;1=2
P 4.42311004 2.09933002 4 P 0 8 0;1=5
P 3.48863002 4.105 6 P 0 8 0;1=0
P 2.987 3.235 5 P 0 8 0;1=8
P 0.7595 1.642 5 P 0 8 0;1=7
P 2.987 3.27 5 P 0 8 0;1=8
P 0.761 1.544 5 P 0 8 0;1=7
P 4.54121998 1.82373996 4 P 0 8 0;1=1
P 4.79246004 1.78463996 6 P 0 8 0;1=0
P 4.54121998 2.17806998 4 P 0 8 0;1=5
P 0.955 1.455 6 P 0 8 0;1=0
P 1.512 0.75191004 6 P 0 8 0;1=2
P 1.8091 0.6339 5 P 0 8 0;1=7
P 1.459 0.752 5 P 0 8 0;1=8
P 0.905 1.445 6 P 0 8 0;1=2
P 2.40508002 0.731 5 P 0 8 0;1=8
P 4.06878996 1.66626998 3 P 0 8 0;1=11
P 2.40508002 0.699 5 P 0 8 0;1=8
P 4.02941998 1.66626998 3 P 0 8 0;1=11
P 4.4085 1.16598996 5 P 0 8 0;1=8
P 4.46248002 1.43005 3 P 0 8 0;1=11
P 4.3765 1.16598996 5 P 0 8 0;1=8
P 4.50185 1.43005 3 P 0 8 0;1=11
P 4.0485 1.16098996 5 P 0 8 0;1=8
P 4.06878996 1.50878996 3 P 0 8 0;1=11
P 4.0165 1.16098996 5 P 0 8 0;1=8
P 4.02941998 1.50878996 3 P 0 8 0;1=11
P 4.82 2.125 4 P 0 8 0;1=3
P 4.38373996 1.78436998 4 P 0 8 0;1=1
P 3.54663996 1.04706998 5 P 0 8 0;1=8
P 4.6987 1.46941998 3 P 0 8 0;1=11
P 3.51463996 1.04706998 5 P 0 8 0;1=8
P 4.73806998 1.46941998 3 P 0 8 0;1=11
P 3.44998996 1.085 5 P 0 8 0;1=8
P 4.73806998 1.39066998 3 P 0 8 0;1=11
P 3.41798996 1.085 5 P 0 8 0;1=8
P 4.73806998 1.3513 3 P 0 8 0;1=11
P 3.445 1.815 6 P 0 8 0;1=2
P 4.58058996 1.90248002 4 P 0 8 0;1=1
P 4.65933002 1.94185 4 P 0 8 0;1=1
P 4.785 3.46 6 P 0 8 0;1=0
P 3.9113 1.70563996 4 P 0 8 0;1=1
P 3.674 1.744 6 P 0 8 0;1=2
P 3.95066998 1.58753002 4 P 0 8 0;1=1
P 3.9113 1.54816004 4 P 0 8 0;1=1
P 3.9113 1.6269 4 P 0 8 0;1=1
P 3.95066998 1.43005 4 P 0 8 0;1=1
P 3.9113 1.46941998 4 P 0 8 0;1=1
P 3.82 1.42 6 P 0 8 0;1=0
P 3.79 1.41 6 P 0 8 0;1=2
P 3.74 1.41 6 P 0 8 0;1=2
P 3.765 1.41 6 P 0 8 0;1=2
P 4.54121998 1.6269 4 P 0 8 0;1=1
P 4.9097 1.385 5 P 0 8 0;1=7
P 4.54121998 1.66626998 4 P 0 8 0;1=1
P 4.84 1.66 6 P 0 8 0;1=0
P 4.81 1.725 6 P 0 8 0;1=0
P 3.375 1.194 5 P 0 8 0;1=8
P 4.5413 1.22166998 5 P 0 8 0;1=8
P 4.61996004 1.31193002 3 P 0 8 0;1=11
P 3.375 1.162 5 P 0 8 0;1=8
P 4.5733 1.22166998 5 P 0 8 0;1=8
P 4.65933002 1.31193002 3 P 0 8 0;1=11
P 5.3 4.065 4 P 0 8 0;1=3
P 4.10816004 1.70563996 4 P 0 8 0;1=1
P 4.365 2.33 6 P 0 8 0;1=2
P 4.38373996 2.02058996 4 P 0 8 0;1=5
P 4.38373996 2.05996004 4 P 0 8 0;1=1
P 4.485 2.375 6 P 0 8 0;1=0
P 4.38373996 2.09933002 4 P 0 8 0;1=1
P 4.54121998 1.58753002 4 P 0 8 0;1=1
P 4.9097 1.335 5 P 0 8 0;1=7
P 4.26563996 1.78436998 4 P 0 8 0;1=1
P 4.365 2.375 6 P 0 8 0;1=0
P 3.465 1.74 6 P 0 8 0;1=2
P 3.44 1.03 6 P 0 8 0;1=0
P 6.285 1.895 6 P 0 8 0;1=2
P 6.258 2.15873996 5 P 0 8 0;1=8
P 6.275 2.05373996 6 P 0 8 0;1=2
P 6.335 2.05906004 5 P 0 8 0;1=7
P 1.77 3.98 6 P 0 8 0;1=0
P 1.75 3.945 6 P 0 8 0;1=2
P 1.5315 3.9459 5 P 0 8 0;1=7
P 1.517 4.113 6 P 0 8 0;1=0
P 1.511 3.863 5 P 0 8 0;1=7
P 1.5153 4.063 5 P 0 8 0;1=7
P 1.521 3.993 5 P 0 8 0;1=7
P 1.579 3.874 6 P 0 8 0;1=0
P 1.585 4.052 6 P 0 8 0;1=2
P 1.435 4.18 6 P 0 8 0;1=2
P 1.522 4.163 5 P 0 8 0;1=7
P 1.4 4.01 6 P 0 8 0;1=2
P 5.18 3.825 6 P 0 8 0;1=2
P 5.675 4.03 6 P 0 8 0;1=2
P 2.2 3.96 6 P 0 8 0;1=2
P 2.25 3.96 4 P 0 8 0;1=3
P 1.351 4.126 6 P 0 8 0;1=2
P 2.165 3.96 6 P 0 8 0;1=2
P 2.155 3.925 6 P 0 8 0;1=2
P 2.19 3.925 6 P 0 8 0;1=2
P 3.23 4.015 6 P 0 8 0;1=0
P 3.2 3.985 6 P 0 8 0;1=2
P 5.9065 2.4568 6 P 0 8 0;1=2
P 3.745 4.185 4 P 0 8 0;1=3
P 3.47 3.912 6 P 0 8 0;1=0
P 3.69 4.135 4 P 0 8 0;1=3
P 3.48278996 4.05678002 6 P 0 8 0;1=2
P 3.476 3.988 6 P 0 8 0;1=0
P 3.437 4.099 6 P 0 8 0;1=0
P 3.598 3.977 6 P 0 8 0;1=2
P 3.477 3.816 6 P 0 8 0;1=0
P 3.405 3.916 6 P 0 8 0;1=2
P 5.68326004 3.712 6 P 0 8 0;1=0
P 5.686 3.807 6 P 0 8 0;1=0
P 5.50643002 4.009 3 P 0 8 0;1=4
P 5.686 3.76 6 P 0 8 0;1=0
P 5.675 3.865 6 P 0 8 0;1=0
P 5.718 3.965 4 P 0 8 0;1=3
P 6.05315 3.67518996 20 P 0 8 0;1=12
P 6.05315 3.50983996 20 P 0 8 0;1=13
P 6.05315 3.34448996 20 P 0 8 0;1=13
P 5.66 3.47 4 P 0 8 0;1=3
P 5.68 3.567 3 P 0 8 0;1=4
P 5.406 3.863 6 P 0 8 0;1=0
P 1.6055 4.134 6 P 0 8 0;1=2
P 1.60581998 4.1 6 P 0 8 0;1=2
P 1.606 4.174 5 P 0 8 0;1=7
P 1.636 3.786 6 P 0 8 0;1=2
P 1.591 3.826 6 P 0 8 0;1=2
P 1.633 3.829 5 P 0 8 0;1=7
P 3.408 4.152 6 P 0 8 0;1=2
P 3.363 4.192 6 P 0 8 0;1=2
P 3.363 4.152 6 P 0 8 0;1=2
P 3.363 4.232 6 P 0 8 0;1=0
P 3.393 3.877 6 P 0 8 0;1=2
P 3.393 3.84 6 P 0 8 0;1=2
P 3.392 3.803 6 P 0 8 0;1=2
P 3.607 4.062 6 P 0 8 0;1=2
P 1.352 4.084 6 P 0 8 0;1=0
P 1.95 0.5455 5 P 0 8 0;1=7
P 5.681 3.617 6 P 0 8 0;1=0
P 5.681 3.664 6 P 0 8 0;1=0
P 5.40318002 2.70436004 5 P 0 8 0;1=7
P 0.55921998 1.40543002 6 P 0 8 0;1=0
P 0.57 0.835 6 P 0 8 0;1=0
P 3.584 1.827 5 P 0 8 0;1=7
P 1.535 3.905 5 P 0 8 0;1=8
P 1.98135 0.365 5 P 0 8 0;1=8
P 1.7317 0.7084 6 P 0 8 0;1=0
P 1.91535 0.412 5 P 0 8 0;1=8
P 1.8039 0.7072 5 P 0 8 0;1=7
P 3.2271 1.90298996 4 P 0 8 0;1=9
P 3.45301004 1.89898996 4 P 0 8 0;1=9
P 3.2591 1.90298996 4 P 0 8 0;1=9
P 3.45301004 1.93098996 4 P 0 8 0;1=9
P 1.26066998 2.64043002 13 P 0 8 0;1=14
P 5.035 3.945 6 P 0 8 0;1=0
P 5.075 3.945 6 P 0 8 0;1=2
P 2.97771998 1.88693996 6 P 0 8 0;1=2
P 3.00995 1.87611004 6 P 0 8 0;1=2
P 2.86066998 2.64043002 13 P 0 8 0;1=14
P 2.105 0.305 5 P 0 8 0;1=8
P 2.235 0.5825 6 P 0 8 0;1=2
P 3.405 0.635 6 P 0 8 0;1=2
P 5.295 0.605 6 P 0 8 0;1=0
P 5.91 4.04 6 P 0 8 0;1=0
P 2.135 0.54 6 P 0 8 0;1=2
P 5.215 0.6 6 P 0 8 0;1=0
P 6.025 4.04 6 P 0 8 0;1=0
P 3.36 0.6106 6 P 0 8 0;1=2
P 0.96 2.41 6 P 0 8 0;1=2
P 0.68 2.355 6 P 0 8 0;1=2
P 2.38 3.45 6 P 0 8 0;1=2
P 1.41 3.795 6 P 0 8 0;1=2
P 3.645 4.135 6 P 0 8 0;1=2
P 4.29 2.74 4 P 0 8 0;1=3
P 4 2.655 6 P 0 8 0;1=2
P 3.51 2.37 6 P 0 8 0;1=2
P 0.29 2.915 6 P 0 8 0;1=0
P 0.28 2.965 6 P 0 8 0;1=0
P 0.285 3.02 6 P 0 8 0;1=0
P 2.977 3.351 3 P 0 8 0;1=4
P 3.36525 3.255 3 P 0 8 0;1=4
P 3.36525 3.205 3 P 0 8 0;1=4
P 1.8062 0.7789 5 P 0 8 0;1=7
P 3.073 0.613 5 P 0 8 0;1=7
P 2.54526998 0.339 5 P 0 8 0;1=8
P 2.527 0.44 3 P 0 8 0;1=4
P 5.73991004 4.27558002 6 P 0 8 0;1=0
P 5.38558002 4.27558002 6 P 0 8 0;1=0
P 5.50368996 4.27558002 6 P 0 8 0;1=0
P 5.6218 4.27558002 6 P 0 8 0;1=0
P 5.875 1.9 6 P 0 8 0;1=0
P 3.865 3.65 6 P 0 8 0;1=2
P 6.06901998 1.86 6 P 0 8 0;1=0
P 3.81 3.65 6 P 0 8 0;1=2
P 5.97 1.999 5 P 0 8 0;1=7
P 4.62 2.245 6 P 0 8 0;1=2
P 5.801 3.667 6 P 0 8 0;1=2
P 3.8 2.045 6 P 0 8 0;1=2
P 1.275 2.905 6 P 0 8 0;1=2
P 5.061 2.806 6 P 0 8 0;1=2
P 3.995 1.2 6 P 0 8 0;1=2
P 4.07 1.2 6 P 0 8 0;1=2
P 4.0805 1.16098996 5 P 0 8 0;1=8
P 4.092 1.005 5 P 0 8 0;1=8
P 4.135 0.885 6 P 0 8 0;1=2
P 4.13621998 0.75 5 P 0 8 0;1=8
P 4.13401998 0.54196998 5 P 0 8 0;1=8
P 4.09401998 0.54196998 5 P 0 8 0;1=8
P 4.05401998 0.54196998 5 P 0 8 0;1=8
P 4.01401998 0.54196998 5 P 0 8 0;1=8
P 2.985 1.845 6 P 0 8 0;1=2
P 2.845 1.907 5 P 0 8 0;1=8
P 2.845 1.811 5 P 0 8 0;1=8
P 2.822 1.79121004 6 P 0 8 0;1=2
P 2.71 1.845 6 P 0 8 0;1=2
P 2.2 0.69 6 P 0 8 0;1=2
P 2.15 0.69 6 P 0 8 0;1=2
P 1.9216 0.7784 6 P 0 8 0;1=2
P 2.0195 0.2905 5 P 0 8 0;1=8
P 1.91535 0.289 5 P 0 8 0;1=8
P 1.78196004 0.50601004 5 P 0 8 0;1=8
P 1.80341004 0.47225 5 P 0 8 0;1=8
P 1.63543002 0.52158996 5 P 0 8 0;1=8
P 3.65101004 1.85158996 5 P 0 8 0;1=8
P 3.45301004 1.86698996 5 P 0 8 0;1=8
P 3.473 1.79 6 P 0 8 0;1=2
P 3.1951 1.90298996 5 P 0 8 0;1=8
P 3.2911 1.90298996 5 P 0 8 0;1=8
P 2.958 0.289 5 P 0 8 0;1=8
P 2.88056998 0.289 5 P 0 8 0;1=8
P 2.95835 0.321 5 P 0 8 0;1=8
P 2.80051998 0.289 5 P 0 8 0;1=8
P 2.80086998 0.321 5 P 0 8 0;1=8
P 2.63506998 0.763 5 P 0 8 0;1=8
P 2.78655 0.763 5 P 0 8 0;1=8
P 2.73106998 0.763 5 P 0 8 0;1=8
P 2.7233 0.54871004 6 P 0 8 0;1=2
P 2.64338996 0.417 5 P 0 8 0;1=8
P 2.72308996 0.289 5 P 0 8 0;1=8
P 2.64303996 0.289 5 P 0 8 0;1=8
P 2.64338996 0.321 5 P 0 8 0;1=8
P 2.53421998 0.763 5 P 0 8 0;1=8
P 2.595 0.701 6 P 0 8 0;1=2
P 2.44618996 0.289 5 P 0 8 0;1=8
P 2.54526998 0.289 5 P 0 8 0;1=8
P 2.43821998 0.763 5 P 0 8 0;1=8
P 2.40508002 0.667 5 P 0 8 0;1=8
P 2.40508002 0.763 5 P 0 8 0;1=8
P 2.327 0.291 5 P 0 8 0;1=8
P 3.56 1.305 6 P 0 8 0;1=2
P 3.535 1.305 6 P 0 8 0;1=2
P 3.51 1.305 6 P 0 8 0;1=2
P 3.54 1.28 6 P 0 8 0;1=2
P 3.57863996 1.04706998 5 P 0 8 0;1=8
P 3.593 0.92 5 P 0 8 0;1=8
P 3.65401998 0.54196998 5 P 0 8 0;1=8
P 3.61401998 0.54196998 5 P 0 8 0;1=8
P 3.57401998 0.54196998 5 P 0 8 0;1=8
P 3.53401998 0.54196998 5 P 0 8 0;1=8
P 3.49401998 0.54196998 5 P 0 8 0;1=8
P 3.375 1.226 5 P 0 8 0;1=8
P 3.375 1.13 5 P 0 8 0;1=8
P 3.48263996 1.04706998 5 P 0 8 0;1=8
P 3.48198996 1.085 5 P 0 8 0;1=8
P 3.38598996 1.085 5 P 0 8 0;1=8
P 3.33401998 0.54196998 5 P 0 8 0;1=8
P 3.45401998 0.54196998 5 P 0 8 0;1=8
P 3.41401998 0.54196998 5 P 0 8 0;1=8
P 3.37401998 0.54196998 5 P 0 8 0;1=8
P 3.17025 0.82975 5 P 0 8 0;1=8
P 3.17401998 0.54196998 5 P 0 8 0;1=8
P 3.21401998 0.54196998 5 P 0 8 0;1=8
P 3.25401998 0.54196998 5 P 0 8 0;1=8
P 3.29401998 0.54196998 5 P 0 8 0;1=8
P 3.10236998 0.89763002 5 P 0 8 0;1=8
P 3.035 0.694 6 P 0 8 0;1=2
P 2.98726004 0.49471004 5 P 0 8 0;1=8
P 2.98726004 0.43528996 5 P 0 8 0;1=8
P 3.07708002 0.289 5 P 0 8 0;1=8
P 2.88255 0.763 5 P 0 8 0;1=8
P 2.95835 0.417 5 P 0 8 0;1=8
P 2.80086998 0.417 5 P 0 8 0;1=8
P 3.9845 1.16098996 5 P 0 8 0;1=8
P 3.9 1.005 5 P 0 8 0;1=8
P 3.964 1.005 5 P 0 8 0;1=7
P 3.97401998 0.54196998 5 P 0 8 0;1=8
P 3.93401998 0.54196998 5 P 0 8 0;1=8
P 3.89401998 0.54196998 5 P 0 8 0;1=8
P 3.85401998 0.54196998 5 P 0 8 0;1=8
P 3.798 1.771 6 P 0 8 0;1=2
P 3.647 1.694 6 P 0 8 0;1=2
P 3.676 1.693 6 P 0 8 0;1=2
P 3.718 1.32 6 P 0 8 0;1=2
P 3.743 1.32 6 P 0 8 0;1=2
P 3.718 1.29 6 P 0 8 0;1=2
P 3.743 1.29 6 P 0 8 0;1=2
P 3.67 1.26 6 P 0 8 0;1=2
P 3.84 1.095 6 P 0 8 0;1=2
P 3.84 1.0298 6 P 0 8 0;1=2
P 3.76838002 1.0023 6 P 0 8 0;1=2
P 3.735 0.94 5 P 0 8 0;1=8
P 3.689 0.92 5 P 0 8 0;1=8
P 3.805 0.774 5 P 0 8 0;1=8
P 3.735 0.78 5 P 0 8 0;1=8
P 3.795 0.725 5 P 0 8 0;1=7
P 3.81401998 0.54196998 5 P 0 8 0;1=8
P 3.77401998 0.54196998 5 P 0 8 0;1=8
P 3.73401998 0.54196998 5 P 0 8 0;1=8
P 3.69401998 0.54196998 5 P 0 8 0;1=8
P 3.551 1.694 6 P 0 8 0;1=2
P 3.576 1.694 6 P 0 8 0;1=2
P 3.526 1.694 6 P 0 8 0;1=2
P 3.501 1.694 6 P 0 8 0;1=2
P 3.636 1.766 6 P 0 8 0;1=2
P 2.86066998 1.04043002 13 P 0 8 0;1=14
P 4.6053 1.22166998 5 P 0 8 0;1=8
P 1.041 3.825 5 P 0 8 0;1=8
P 1.137 3.825 5 P 0 8 0;1=8
P 6.56038996 1.41205 5 P 0 8 0;1=8
P 6.56038996 1.37205 5 P 0 8 0;1=8
P 6.56038996 1.33205 5 P 0 8 0;1=8
P 6.56038996 1.29205 5 P 0 8 0;1=8
P 6.56038996 1.25205 5 P 0 8 0;1=8
P 6.56038996 1.21205 5 P 0 8 0;1=8
P 6.56038996 1.17205 5 P 0 8 0;1=8
P 6.56038996 1.13205 5 P 0 8 0;1=8
P 6.56038996 1.09205 5 P 0 8 0;1=8
P 5.9645 2.1035 6 P 0 8 0;1=15
P 6.0155 2.0845 6 P 0 8 0;1=15
P 0.22703996 0.43635 7 P 0 8 0;1=16
P 0.19878002 0.36811004 7 P 0 8 0;1=16
P 0.22703996 0.29986998 7 P 0 8 0;1=16
P 0.29528002 0.27161004 7 P 0 8 0;1=16
P 0.36351998 0.29986998 7 P 0 8 0;1=16
P 0.39178002 0.36811004 7 P 0 8 0;1=16
P 0.36351998 0.43635 7 P 0 8 0;1=16
P 0.29528002 0.46461004 7 P 0 8 0;1=16
P 6.33215 0.72178002 7 P 0 8 0;1=16
P 6.30388996 0.65353996 7 P 0 8 0;1=16
P 6.33215 0.5853 7 P 0 8 0;1=16
P 6.40038996 0.55703996 7 P 0 8 0;1=16
P 6.46863002 0.5853 7 P 0 8 0;1=16
P 6.49688996 0.65353996 7 P 0 8 0;1=16
P 6.46863002 0.72178002 7 P 0 8 0;1=16
P 6.40038996 0.75003996 7 P 0 8 0;1=16
P 6.33215 4.24658996 7 P 0 8 0;1=16
P 6.30388996 4.17835 7 P 0 8 0;1=16
P 6.33215 4.11011004 7 P 0 8 0;1=16
P 6.40038996 4.08185 7 P 0 8 0;1=16
P 6.46863002 4.11011004 7 P 0 8 0;1=16
P 6.49688996 4.17835 7 P 0 8 0;1=16
P 6.46863002 4.24658996 7 P 0 8 0;1=16
P 6.40038996 4.27485 7 P 0 8 0;1=16
P 5.92 1.36 6 P 0 8 0;1=0
P 6.22 1.36 6 P 0 8 0;1=2
P 5.99 0.925 6 P 0 8 0;1=2
P 5.803 3.857 6 P 0 8 0;1=2
P 1.355 3.905 6 P 0 8 0;1=2
P 1.21168996 3.96891998 6 P 0 8 0;1=2
P 0.42 2.368 6 P 0 8 0;1=2
P 5.325 2.725 6 P 0 8 0;1=2
P 1.6985 2.9895 6 P 0 8 0;1=15
P 1.6615 3.0405 6 P 0 8 0;1=15
P 5.6435 0.6535 6 P 0 8 0;1=15
P 5.1265 2.6815 6 P 0 8 0;1=15
P 5.0895 2.7325 6 P 0 8 0;1=15
P 4.1915 4.0395 6 P 0 8 0;1=15
P 4.0965 3.9445 6 P 0 8 0;1=15
P 4.1235 3.9715 6 P 0 8 0;1=15
P 4.1645 3.9715 6 P 0 8 0;1=15
P 4.1645 4.0125 6 P 0 8 0;1=15
P 4.1235 4.0125 6 P 0 8 0;1=15
P 4.0965 4.0395 6 P 0 8 0;1=15
P 4.1915 3.9445 6 P 0 8 0;1=15
P 4.5 4.07 6 P 0 8 0;1=2
P 4.31 4.16 6 P 0 8 0;1=2
P 1.41 2.985 6 P 0 8 0;1=2
P 1.45 2.965 6 P 0 8 0;1=2
P 1.51 3.242 6 P 0 8 0;1=2
P 1.89 3.26 6 P 0 8 0;1=2
P 1.895 3.19 6 P 0 8 0;1=2
P 1.9 3.055 6 P 0 8 0;1=2
P 1.9 3.015 6 P 0 8 0;1=2
P 1.65 2.94 6 P 0 8 0;1=2
P 1.685 2.94 6 P 0 8 0;1=2
P 5.17 2.125 6 P 0 8 0;1=2
P 4.96 1.79258002 6 P 0 8 0;1=2
P 4.59 3.26 6 P 0 8 0;1=2
P 2.866 1.987 5 P 0 8 0;1=8
P 2.77 1.987 5 P 0 8 0;1=8
P 4.5093 1.22166998 5 P 0 8 0;1=8
P 0.04 2.85618996 5 P 0 8 0;1=8
P 0.04 2.81618996 5 P 0 8 0;1=8
P 0.04 3.13618996 5 P 0 8 0;1=8
P 0.04 3.09618996 5 P 0 8 0;1=8
P 0.04 3.05618996 5 P 0 8 0;1=8
P 0.04 3.01618996 5 P 0 8 0;1=8
P 3.49 3.03 6 P 0 8 0;1=2
P 3.555 3.065 6 P 0 8 0;1=2
P 3.695 2.675 6 P 0 8 0;1=2
P 3.725 2.32 6 P 0 8 0;1=2
P 0.945 1.05 6 P 0 8 0;1=2
P 4.635 0.865 6 P 0 8 0;1=2
P 0.866 1.413 6 P 0 8 0;1=2
P 2.885 3.17 6 P 0 8 0;1=2
P 0.83 4.17 6 P 0 8 0;1=2
P 0.455 1.26 6 P 0 8 0;1=2
P 0.175 0.91 6 P 0 8 0;1=2
P 0.17 2.045 6 P 0 8 0;1=2
P 0.455 1.61 6 P 0 8 0;1=2
P 1.32 3.755 6 P 0 8 0;1=2
P 1.25095 3.06095 6 P 0 8 0;1=2
P 0.95593002 3.33346998 6 P 0 8 0;1=2
P 0.575 2.89 6 P 0 8 0;1=0
P 0.16 3.025 6 P 0 8 0;1=2
P 0.16 3.075 6 P 0 8 0;1=2
P 0.72 3.35 6 P 0 8 0;1=2
P 0.635 3.596 6 P 0 8 0;1=2
P 0.671 3.575 5 P 0 8 0;1=8
P 0.767 3.575 5 P 0 8 0;1=8
P 1.4213 3.2563 6 P 0 8 0;1=2
P 4.472 3.475 6 P 0 8 0;1=2
P 5.97703002 1.87 6 P 0 8 0;1=2
P 0.606 1.612 6 P 0 8 0;1=2
P 5.33 0.87 6 P 0 8 0;1=2
P 6.26988996 2.37988996 6 P 0 8 0;1=2
P 4.46 3.745 6 P 0 8 0;1=2
P 3.83 3.415 6 P 0 8 0;1=2
P 3.55 3.325 5 P 0 8 0;1=8
P 6.335 3.015 6 P 0 8 0;1=2
P 1.667 3.388 6 P 0 8 0;1=2
P 1.591 3.504 6 P 0 8 0;1=2
P 1.045 3.055 6 P 0 8 0;1=2
P 1.42 3.5 6 P 0 8 0;1=2
P 1.235 3.475 6 P 0 8 0;1=2
P 1.2 3.715 6 P 0 8 0;1=2
P 1.409 3.554 6 P 0 8 0;1=2
P 1.2 3.68 6 P 0 8 0;1=2
P 1.155 3.89 6 P 0 8 0;1=2
P 1.17 3.97 6 P 0 8 0;1=2
P 1.27 3.97061004 6 P 0 8 0;1=2
P 1.29 3.705 6 P 0 8 0;1=2
P 1.355 3.83 6 P 0 8 0;1=2
P 1.355 3.96 6 P 0 8 0;1=2
P 1.185 3.79 6 P 0 8 0;1=2
P 1.32 3.79 6 P 0 8 0;1=2
P 1.29 3.65 6 P 0 8 0;1=2
P 5.803 3.567 6 P 0 8 0;1=2
P 5.43 3.967 6 P 0 8 0;1=2
P 6.165 1.94873996 6 P 0 8 0;1=2
P 1.038 0.7624 6 P 0 8 0;1=2
P 4.037 2.593 6 P 0 8 0;1=2
P 3.978 2.593 6 P 0 8 0;1=2
P 4.81 0.707 6 P 0 8 0;1=2
P 6.47 1.135 6 P 0 8 0;1=2
P 4.595 3.22 6 P 0 8 0;1=2
P 4.175 3.52 6 P 0 8 0;1=2
P 3.98 3.52 6 P 0 8 0;1=2
P 3.973 3.207 6 P 0 8 0;1=2
P 4.075 3.05 6 P 0 8 0;1=2
P 3.839 3.726 6 P 0 8 0;1=2
P 4.1 3.58543002 6 P 0 8 0;1=2
P 5.637 3.524 6 P 0 8 0;1=0
P 5.276 3.189 6 P 0 8 0;1=2
P 5.329 3.189 6 P 0 8 0;1=2
P 5.386 3.189 6 P 0 8 0;1=2
P 5.271 3.456 6 P 0 8 0;1=2
P 5.271 3.406 6 P 0 8 0;1=2
P 5.324 3.456 6 P 0 8 0;1=2
P 5.381 3.456 6 P 0 8 0;1=2
P 5.324 3.406 6 P 0 8 0;1=2
P 5.381 3.406 6 P 0 8 0;1=2
P 5.802 3.617 6 P 0 8 0;1=2
P 5.763 3.712 6 P 0 8 0;1=2
P 5.803 3.757 6 P 0 8 0;1=2
P 5.803 3.807 6 P 0 8 0;1=2
P 5.602 3.865 6 P 0 8 0;1=2
P 5.645 3.79 6 P 0 8 0;1=2
P 5.48556998 3.877 6 P 0 8 0;1=0
P 5.237 3.777 6 P 0 8 0;1=2
P 5.282 3.777 6 P 0 8 0;1=2
P 5.237 3.841 6 P 0 8 0;1=2
P 5.322 3.777 6 P 0 8 0;1=2
P 5.385 4.07875 6 P 0 8 0;1=2
P 0.199 2.83 6 P 0 8 0;1=2
P 1.2 3.645 6 P 0 8 0;1=2
P 1.1 3.64 6 P 0 8 0;1=2
P 1.065 3.64 6 P 0 8 0;1=2
P 1.03 3.64 6 P 0 8 0;1=2
P 0.99 3.5 6 P 0 8 0;1=2
P 0.664 0.774 6 P 0 8 0;1=2
P 0.833 0.871 6 P 0 8 0;1=2
P 0.66 0.911 6 P 0 8 0;1=2
P 0.695 1 6 P 0 8 0;1=2
P 0.485 2.715 6 P 0 8 0;1=2
P 0.51771998 2.45073996 6 P 0 8 0;1=2
P 0.675 2.229 6 P 0 8 0;1=2
P 0.575 2.185 6 P 0 8 0;1=2
P 0.51771998 1.87986998 6 P 0 8 0;1=2
P 0.539 1.57 6 P 0 8 0;1=2
P 0.51771998 1.305 6 P 0 8 0;1=2
P 0.476 0.689 6 P 0 8 0;1=2
P 0.614 1.049 6 P 0 8 0;1=2
P 0.51771998 0.736 6 P 0 8 0;1=2
P 0.47 1 6 P 0 8 0;1=2
P 0.677 0.65 6 P 0 8 0;1=2
P 4.546 1.085 6 P 0 8 0;1=2
P 0.43705 3.51576004 19 P 0 8 0;1=17
P 0.43705 3.31655 19 P 0 8 0;1=17
P 0.24806998 3.47245 19 P 0 8 0;1=17
P 0.24806998 3.35985 19 P 0 8 0;1=17
P 0.24606004 3.4315 8 P 0 8 0;1=6
P 0.4587 3.4315 8 P 0 8 0;1=6
P 0.44098002 3.4008 8 P 0 8 0;1=6
P 0.22833996 3.4008 8 P 0 8 0;1=6
P 5.75071998 1.655 6 P 0 8 0;1=2
P 1.76 4.16 6 P 0 8 0;1=2
P 2.26 3.785 6 P 0 8 0;1=2
P 2.215 3.785 6 P 0 8 0;1=2
P 3.843 3.687 6 P 0 8 0;1=2
P 0.61488996 3.32328996 6 P 0 8 0;1=2
P 5.335 1.245 6 P 0 8 0;1=2
P 5.345 1.3 6 P 0 8 0;1=2
P 5.345 1.365 6 P 0 8 0;1=2
P 3.645 2.13 6 P 0 8 0;1=2
P 3.67 2.13 6 P 0 8 0;1=2
P 3.11 1.935 6 P 0 8 0;1=2
P 4.294 1.075 6 P 0 8 0;1=2
P 4.5 1.082 6 P 0 8 0;1=2
P 5.385 1.895 6 P 0 8 0;1=2
P 5.425 1.895 6 P 0 8 0;1=2
P 5.76458996 1.61971004 6 P 0 8 0;1=2
P 5.34 1.605 6 P 0 8 0;1=2
P 5.44 1.59 6 P 0 8 0;1=2
P 4.54123002 1.70563996 4 P 0 8 0;1=1
P 4.73806998 1.66626998 4 P 0 8 0;1=1
P 4.26563996 2.17806998 4 P 0 8 0;1=1
P 4.6987 1.3513 4 P 0 8 0;1=1
P 4.57843996 1.31408002 4 P 0 8 0;1=1
P 4.54121998 1.43005 4 P 0 8 0;1=1
P 4.42311004 1.54816004 4 P 0 8 0;1=1
P 4.42311004 1.39066998 4 P 0 8 0;1=1
P 4.38373996 1.58753002 4 P 0 8 0;1=1
P 4.38373996 1.50878996 4 P 0 8 0;1=1
P 4.38373996 1.6269 4 P 0 8 0;1=1
P 4.34436998 1.54816004 4 P 0 8 0;1=1
P 4.34436998 1.66626998 4 P 0 8 0;1=1
P 4.34436998 1.6269 4 P 0 8 0;1=1
P 4.26563996 1.58753002 4 P 0 8 0;1=1
P 4.26563996 1.3513 4 P 0 8 0;1=1
P 4.26563996 1.6269 4 P 0 8 0;1=1
P 4.26563996 1.66626998 4 P 0 8 0;1=1
P 4.22626998 1.54816004 4 P 0 8 0;1=1
P 4.22626998 1.46941998 4 P 0 8 0;1=1
P 4.22626998 1.6269 4 P 0 8 0;1=1
P 4.1869 1.58753002 4 P 0 8 0;1=1
P 4.14753002 1.54816004 4 P 0 8 0;1=1
P 4.14753002 1.31193002 4 P 0 8 0;1=1
P 4.10816004 1.54816004 4 P 0 8 0;1=1
P 4.10816004 1.50878996 4 P 0 8 0;1=1
P 4.10816004 1.46941998 4 P 0 8 0;1=1
P 4.06878996 1.46941998 4 P 0 8 0;1=1
P 4.02941998 1.46941998 4 P 0 8 0;1=1
P 4.02941998 1.43005 4 P 0 8 0;1=1
P 3.99005 1.43005 4 P 0 8 0;1=1
P 3.99005 1.39066998 4 P 0 8 0;1=1
P 3.95066998 1.39066998 4 P 0 8 0;1=1
P 3.87193002 2.17806998 4 P 0 8 0;1=1
P 3.9113 2.05996004 4 P 0 8 0;1=1
P 3.95066998 1.94185 4 P 0 8 0;1=1
P 4.10816004 1.86311004 4 P 0 8 0;1=1
P 3.99005 1.82373996 4 P 0 8 0;1=1
P 4.1869 1.78436998 4 P 0 8 0;1=1
P 4.10816004 1.78436998 4 P 0 8 0;1=1
P 3.99005 1.78436998 4 P 0 8 0;1=1
P 3.87193002 1.78436998 4 P 0 8 0;1=1
P 3.95066998 1.78436998 4 P 0 8 0;1=1
P 3.9113 1.78436998 4 P 0 8 0;1=1
P 4.22626998 1.70563996 4 P 0 8 0;1=1
P 4.14753002 1.70563996 4 P 0 8 0;1=1
P 4.06878996 1.70563996 4 P 0 8 0;1=1
P 4.02941998 1.70563996 4 P 0 8 0;1=1
P 3.87193002 1.70563996 4 P 0 8 0;1=1
P 4.1869 1.66626998 4 P 0 8 0;1=1
P 4.10816004 1.66626998 4 P 0 8 0;1=1
P 3.95066998 1.66626998 4 P 0 8 0;1=1
P 3.87193002 1.6269 4 P 0 8 0;1=1
P 4.14753002 1.6269 4 P 0 8 0;1=1
P 4.10816004 1.6269 4 P 0 8 0;1=1
P 4.02941998 1.6269 4 P 0 8 0;1=1
P 4.10816004 1.58753002 4 P 0 8 0;1=1
P 3.99005 1.58753002 4 P 0 8 0;1=1
P 3.87193002 1.54816004 4 P 0 8 0;1=1
P 4.02941998 1.54816004 4 P 0 8 0;1=1
P 3.95066998 1.50878996 4 P 0 8 0;1=1
P 3.87193002 1.46941998 4 P 0 8 0;1=1
P 3.87193002 1.39066998 4 P 0 8 0;1=1
P 3.9113 1.39066998 4 P 0 8 0;1=1
P 3.87193002 1.3513 4 P 0 8 0;1=1
P 4.6987 2.17806998 4 P 0 8 0;1=1
P 4.58058996 2.1387 4 P 0 8 0;1=1
P 4.50185 1.98121998 4 P 0 8 0;1=1
P 4.46248002 2.09933002 4 P 0 8 0;1=1
P 4.38373996 1.94185 4 P 0 8 0;1=1
P 4.34436998 2.05996004 4 P 0 8 0;1=1
P 4.22626998 1.90248002 4 P 0 8 0;1=1
P 4.1869 2.02058996 4 P 0 8 0;1=1
P 4.14753002 2.1387 4 P 0 8 0;1=1
P 4.06878996 1.98121998 4 P 0 8 0;1=1
P 4.02941998 2.09933002 4 P 0 8 0;1=1
P 4.73806998 2.05996004 4 P 0 8 0;1=1
P 4.61996004 2.02058996 4 P 0 8 0;1=1
P 4.65933002 1.90248002 4 P 0 8 0;1=1
P 4.54121998 1.86311004 4 P 0 8 0;1=1
P 4.42311004 1.82373996 4 P 0 8 0;1=1
P 4.6987 1.78436998 4 P 0 8 0;1=1
P 4.46248002 1.78436998 4 P 0 8 0;1=1
P 4.50185 1.70563996 4 P 0 8 0;1=1
P 4.42311004 1.70563996 4 P 0 8 0;1=1
P 4.34436998 1.70563996 4 P 0 8 0;1=1
P 4.46248002 1.66626998 4 P 0 8 0;1=1
P 4.58058996 1.66626998 4 P 0 8 0;1=1
P 4.38373996 1.66626998 4 P 0 8 0;1=1
P 4.50185 1.6269 4 P 0 8 0;1=1
P 4.42311004 1.6269 4 P 0 8 0;1=1
P 4.61996004 1.58753002 4 P 0 8 0;1=1
P 4.46248002 1.58753002 4 P 0 8 0;1=1
P 4.50185 1.54816004 4 P 0 8 0;1=1
P 4.65933002 1.46941998 4 P 0 8 0;1=1
P 0.12878002 0.21716998 5 P 0 8 0;1=8
P 0.16878002 0.21716998 5 P 0 8 0;1=8
P 0.20878002 0.21716998 5 P 0 8 0;1=8
P 0.24878002 0.21716998 5 P 0 8 0;1=8
P 0.08413002 4.33598002 5 P 0 8 0;1=8
P 0.04413002 4.33598002 5 P 0 8 0;1=8
P 0.04 4.29618996 5 P 0 8 0;1=8
P 0.04 4.25618996 5 P 0 8 0;1=8
P 0.04 4.21618996 5 P 0 8 0;1=8
P 0.04 4.17618996 5 P 0 8 0;1=8
P 0.04 4.13618996 5 P 0 8 0;1=8
P 0.04 4.09618996 5 P 0 8 0;1=8
P 0.04 4.05618996 5 P 0 8 0;1=8
P 0.04 4.01618996 5 P 0 8 0;1=8
P 0.04 3.97618996 5 P 0 8 0;1=8
P 0.04 3.93618996 5 P 0 8 0;1=8
P 0.04 3.89618996 5 P 0 8 0;1=8
P 0.04 3.85618996 5 P 0 8 0;1=8
P 0.04 3.81618996 5 P 0 8 0;1=8
P 0.04 3.77618996 5 P 0 8 0;1=8
P 0.04 3.73618996 5 P 0 8 0;1=8
P 0.04 3.69618996 5 P 0 8 0;1=8
P 0.04 3.65618996 5 P 0 8 0;1=8
P 0.04 3.61618996 5 P 0 8 0;1=8
P 0.04 3.57618996 5 P 0 8 0;1=8
P 0.04 3.53618996 5 P 0 8 0;1=8
P 0.04 3.49618996 5 P 0 8 0;1=8
P 0.04 3.45618996 5 P 0 8 0;1=8
P 0.04 3.41618996 5 P 0 8 0;1=8
P 0.04 3.37618996 5 P 0 8 0;1=8
P 0.04 2.97618996 5 P 0 8 0;1=8
P 0.04 2.93618996 5 P 0 8 0;1=8
P 0.04 2.89618996 5 P 0 8 0;1=8
P 0.04 0.49618996 5 P 0 8 0;1=8
P 0.04 0.45618996 5 P 0 8 0;1=8
P 0.04 0.41618996 5 P 0 8 0;1=8
P 0.04 0.37618996 5 P 0 8 0;1=8
P 0.04 0.33618996 5 P 0 8 0;1=8
P 0.04 0.29618996 5 P 0 8 0;1=8
P 0.04 0.25618996 5 P 0 8 0;1=8
P 0.04878002 0.21716998 5 P 0 8 0;1=8
P 0.08878002 0.21716998 5 P 0 8 0;1=8
P 2.76413002 4.33598002 5 P 0 8 0;1=8
P 2.72413002 4.33598002 5 P 0 8 0;1=8
P 2.68413002 4.33598002 5 P 0 8 0;1=8
P 2.64413002 4.33598002 5 P 0 8 0;1=8
P 2.60413002 4.33598002 5 P 0 8 0;1=8
P 0.55055 0.45073002 5 P 0 8 0;1=8
P 0.55558002 0.49041004 5 P 0 8 0;1=8
P 0.57858996 0.52313002 5 P 0 8 0;1=8
P 0.61463002 0.54048002 5 P 0 8 0;1=8
P 0.55055 0.29073002 5 P 0 8 0;1=8
P 0.55055 0.33073002 5 P 0 8 0;1=8
P 0.55055 0.37073002 5 P 0 8 0;1=8
P 0.55055 0.41073002 5 P 0 8 0;1=8
P 0.48878002 0.21716998 5 P 0 8 0;1=8
P 0.52878002 0.21716998 5 P 0 8 0;1=8
P 0.55055 0.25073002 5 P 0 8 0;1=8
P 0.44413002 4.33598002 5 P 0 8 0;1=8
P 0.40413002 4.33598002 5 P 0 8 0;1=8
P 0.36413002 4.33598002 5 P 0 8 0;1=8
P 0.32413002 4.33598002 5 P 0 8 0;1=8
P 0.28878002 0.21716998 5 P 0 8 0;1=8
P 0.32878002 0.21716998 5 P 0 8 0;1=8
P 0.36878002 0.21716998 5 P 0 8 0;1=8
P 0.40878002 0.21716998 5 P 0 8 0;1=8
P 0.44878002 0.21716998 5 P 0 8 0;1=8
P 0.28413002 4.33598002 5 P 0 8 0;1=8
P 0.24413002 4.33598002 5 P 0 8 0;1=8
P 0.20413002 4.33598002 5 P 0 8 0;1=8
P 0.16413002 4.33598002 5 P 0 8 0;1=8
P 0.12413002 4.33598002 5 P 0 8 0;1=8
P 0.889 0.67 6 P 0 8 0;1=2
P 0.6546 0.54196998 5 P 0 8 0;1=8
P 0.6946 0.54196998 5 P 0 8 0;1=8
P 0.7346 0.54196998 5 P 0 8 0;1=8
P 0.7746 0.54196998 5 P 0 8 0;1=8
P 0.8146 0.54196998 5 P 0 8 0;1=8
P 0.64413002 4.33598002 5 P 0 8 0;1=8
P 0.60413002 4.33598002 5 P 0 8 0;1=8
P 0.56413002 4.33598002 5 P 0 8 0;1=8
P 0.52413002 4.33598002 5 P 0 8 0;1=8
P 0.48413002 4.33598002 5 P 0 8 0;1=8
P 0.8575 2.0275 6 P 0 8 0;1=2
P 1.195 0.57693996 6 P 0 8 0;1=2
P 0.8546 0.54196998 5 P 0 8 0;1=8
P 0.8946 0.54196998 5 P 0 8 0;1=8
P 0.9346 0.54196998 5 P 0 8 0;1=8
P 0.9746 0.54196998 5 P 0 8 0;1=8
P 0.80413002 4.33598002 5 P 0 8 0;1=8
P 0.76413002 4.33598002 5 P 0 8 0;1=8
P 0.72413002 4.33598002 5 P 0 8 0;1=8
P 0.68413002 4.33598002 5 P 0 8 0;1=8
P 0.66 4.19 6 P 0 8 0;1=2
P 0.67 2.831 5 P 0 8 0;1=8
P 0.79248002 2.661 5 P 0 8 0;1=8
P 0.80148002 2.53648002 6 P 0 8 0;1=2
P 0.715 2.478 6 P 0 8 0;1=2
P 0.714 2.217 6 P 0 8 0;1=2
P 0.74593002 2.02206998 6 P 0 8 0;1=2
P 1.0146 0.54196998 5 P 0 8 0;1=8
P 1.0546 0.54196998 5 P 0 8 0;1=8
P 1.0946 0.54196998 5 P 0 8 0;1=8
P 1.1346 0.54196998 5 P 0 8 0;1=8
P 1.1746 0.54196998 5 P 0 8 0;1=8
P 1.00413002 4.33598002 5 P 0 8 0;1=8
P 0.96413002 4.33598002 5 P 0 8 0;1=8
P 0.92413002 4.33598002 5 P 0 8 0;1=8
P 0.88413002 4.33598002 5 P 0 8 0;1=8
P 0.84413002 4.33598002 5 P 0 8 0;1=8
P 1.025 4.2 6 P 0 8 0;1=2
P 0.94 4.2 6 P 0 8 0;1=2
P 0.858 2.87451998 3 P 0 8 0;1=4
P 0.988 2.724 6 P 0 8 0;1=2
P 0.987 2.683 6 P 0 8 0;1=0
P 0.856 2.637 5 P 0 8 0;1=8
P 0.93031998 2.46476998 6 P 0 8 0;1=2
P 0.872 2.583 6 P 0 8 0;1=2
P 0.868 2.3 5 P 0 8 0;1=8
P 1.401 3.956 6 P 0 8 0;1=2
P 1.40123002 3.91603996 6 P 0 8 0;1=2
P 1.48 3.7 6 P 0 8 0;1=2
P 1.38163002 0.21716998 5 P 0 8 0;1=8
P 1.42163002 0.21716998 5 P 0 8 0;1=8
P 1.46163002 0.21716998 5 P 0 8 0;1=8
P 1.50163002 0.21716998 5 P 0 8 0;1=8
P 1.54163002 0.21716998 5 P 0 8 0;1=8
P 1.36413002 4.33598002 5 P 0 8 0;1=8
P 1.32413002 4.33598002 5 P 0 8 0;1=8
P 1.28413002 4.33598002 5 P 0 8 0;1=8
P 1.24413002 4.33598002 5 P 0 8 0;1=8
P 1.20413002 4.33598002 5 P 0 8 0;1=8
P 1.515 3.7 6 P 0 8 0;1=2
P 1.385 0.75 5 P 0 8 0;1=8
P 1.44 0.625 5 P 0 8 0;1=8
P 1.5184 0.79935 5 P 0 8 0;1=8
P 1.2146 0.54196998 5 P 0 8 0;1=8
P 1.2546 0.54196998 5 P 0 8 0;1=8
P 1.2945 0.53916998 5 P 0 8 0;1=8
P 1.3292 0.51926004 5 P 0 8 0;1=8
P 1.34976998 0.48496004 5 P 0 8 0;1=8
P 1.35298996 0.44508996 5 P 0 8 0;1=8
P 1.35298996 0.40508996 5 P 0 8 0;1=8
P 1.35298996 0.36508996 5 P 0 8 0;1=8
P 1.35298996 0.32508996 5 P 0 8 0;1=8
P 1.35298996 0.28508996 5 P 0 8 0;1=8
P 1.35298996 0.24508996 5 P 0 8 0;1=8
P 1.16413002 4.33598002 5 P 0 8 0;1=8
P 1.12413002 4.33598002 5 P 0 8 0;1=8
P 1.08413002 4.33598002 5 P 0 8 0;1=8
P 1.04413002 4.33598002 5 P 0 8 0;1=8
P 1.96413002 4.33598002 5 P 0 8 0;1=8
P 1.92413002 4.33598002 5 P 0 8 0;1=8
P 1.915 4.13 6 P 0 8 0;1=2
P 1.88413002 4.33598002 5 P 0 8 0;1=8
P 1.84413002 4.33598002 5 P 0 8 0;1=8
P 1.80413002 4.33598002 5 P 0 8 0;1=8
P 1.76413002 4.33598002 5 P 0 8 0;1=8
P 1.746 4.061 6 P 0 8 0;1=2
P 1.746 4.106 6 P 0 8 0;1=0
P 1.751 3.871 6 P 0 8 0;1=2
P 1.746 4.016 6 P 0 8 0;1=2
P 1.751 3.826 6 P 0 8 0;1=0
P 1.786 3.746 6 P 0 8 0;1=2
P 1.786 3.786 6 P 0 8 0;1=2
P 2.0966 3.315 5 P 0 8 0;1=8
P 1.72413002 4.33598002 5 P 0 8 0;1=8
P 1.68413002 4.33598002 5 P 0 8 0;1=8
P 1.64413002 4.33598002 5 P 0 8 0;1=8
P 1.60413002 4.33598002 5 P 0 8 0;1=8
P 1.56413002 4.33598002 5 P 0 8 0;1=8
P 1.671 4.056 5 P 0 8 0;1=8
P 1.5086 0.674 6 P 0 8 0;1=0
P 1.59111998 0.45653996 5 P 0 8 0;1=8
P 1.60736004 0.49308996 5 P 0 8 0;1=8
P 1.58795 0.29666998 5 P 0 8 0;1=8
P 1.58795 0.33666998 5 P 0 8 0;1=8
P 1.58795 0.37666998 5 P 0 8 0;1=8
P 1.58795 0.41666998 5 P 0 8 0;1=8
P 1.58163002 0.21716998 5 P 0 8 0;1=8
P 1.58795 0.25666998 5 P 0 8 0;1=8
P 1.52413002 4.33598002 5 P 0 8 0;1=8
P 1.48413002 4.33598002 5 P 0 8 0;1=8
P 1.44413002 4.33598002 5 P 0 8 0;1=8
P 1.40413002 4.33598002 5 P 0 8 0;1=8
P 2.56413002 4.33598002 5 P 0 8 0;1=8
P 2.52413002 4.33598002 5 P 0 8 0;1=8
P 2.48413002 4.33598002 5 P 0 8 0;1=8
P 2.44413002 4.33598002 5 P 0 8 0;1=8
P 2.40413002 4.33598002 5 P 0 8 0;1=8
P 2.36413002 4.33598002 5 P 0 8 0;1=8
P 2.32413002 4.33598002 5 P 0 8 0;1=8
P 2.28413002 4.33598002 5 P 0 8 0;1=8
P 2.295 4.15 6 P 0 8 0;1=2
P 2.285 3.825 6 P 0 8 0;1=0
P 2.24413002 4.33598002 5 P 0 8 0;1=8
P 2.20413002 4.33598002 5 P 0 8 0;1=8
P 2.16413002 4.33598002 5 P 0 8 0;1=8
P 2.12413002 4.33598002 5 P 0 8 0;1=8
P 2.176 4.151 6 P 0 8 0;1=2
P 2.256 4.151 6 P 0 8 0;1=2
P 2.215 4.15 6 P 0 8 0;1=2
P 2.18 3.811 6 P 0 8 0;1=2
P 2.218 2.895 5 P 0 8 0;1=8
P 2.173 2.895 5 P 0 8 0;1=8
P 2.083 2.895 5 P 0 8 0;1=8
P 2.08413002 4.33598002 5 P 0 8 0;1=8
P 2.04413002 4.33598002 5 P 0 8 0;1=8
P 2.00413002 4.33598002 5 P 0 8 0;1=8
P 0.22703996 3.79855 7 P 0 8 0;1=16
P 0.19878002 3.73031004 7 P 0 8 0;1=16
P 0.22703996 3.66206998 7 P 0 8 0;1=16
P 0.29528002 3.63381004 7 P 0 8 0;1=16
P 0.36351998 3.66206998 7 P 0 8 0;1=16
P 0.39178002 3.73031004 7 P 0 8 0;1=16
P 0.36351998 3.79855 7 P 0 8 0;1=16
P 0.29528002 3.82681004 7 P 0 8 0;1=16
P 6.19961004 2.21273996 5 P 0 8 0;1=8
P 6.19961004 2.30873996 5 P 0 8 0;1=8
P 4.3445 1.16598996 5 P 0 8 0;1=8
P 4.4405 1.16598996 5 P 0 8 0;1=8
P 3.45301004 1.96298996 5 P 0 8 0;1=8
P 3.65101004 1.94758996 5 P 0 8 0;1=8
P 4.44 2.63 6 P 0 8 0;1=2
P 4.395 2.665 6 P 0 8 0;1=2
P 4.6 2.895 6 P 0 8 0;1=2
P 4.6 2.845 6 P 0 8 0;1=2
P 3.42 3.76 6 P 0 8 0;1=2
P 3.385 3.76 6 P 0 8 0;1=2
P 3.315 3.76 6 P 0 8 0;1=2
P 3.26 3.74 6 P 0 8 0;1=2
P 6.56038996 1.81205 5 P 0 8 0;1=8
P 6.56038996 1.77205 5 P 0 8 0;1=8
P 6.56038996 1.73205 5 P 0 8 0;1=8
P 6.56038996 1.69205 5 P 0 8 0;1=8
P 6.56038996 1.65205 5 P 0 8 0;1=8
P 6.56038996 1.61205 5 P 0 8 0;1=8
P 6.56038996 1.57205 5 P 0 8 0;1=8
P 6.56038996 1.53205 5 P 0 8 0;1=8
P 6.56038996 1.49205 5 P 0 8 0;1=8
P 6.56038996 1.45205 5 P 0 8 0;1=8
P 6.56038996 1.05205 5 P 0 8 0;1=8
P 6.56038996 1.01205 5 P 0 8 0;1=8
P 6.56038996 0.97205 5 P 0 8 0;1=8
P 6.56038996 0.93205 5 P 0 8 0;1=8
P 6.56038996 0.89205 5 P 0 8 0;1=8
P 6.56038996 0.85205 5 P 0 8 0;1=8
P 6.56038996 0.81205 5 P 0 8 0;1=8
P 6.56038996 0.77205 5 P 0 8 0;1=8
P 6.56038996 0.73205 5 P 0 8 0;1=8
P 6.56038996 0.69205 5 P 0 8 0;1=8
P 6.56038996 0.65205 5 P 0 8 0;1=8
P 6.56038996 0.61205 5 P 0 8 0;1=8
P 6.56038996 0.57205 5 P 0 8 0;1=8
P 6.53401998 0.54196998 5 P 0 8 0;1=8
P 6.49401998 0.54196998 5 P 0 8 0;1=8
P 6.29401998 0.54196998 5 P 0 8 0;1=8
P 6.25401998 0.54196998 5 P 0 8 0;1=8
P 6.21401998 0.54196998 5 P 0 8 0;1=8
P 6.17401998 0.54196998 5 P 0 8 0;1=8
P 6.13401998 0.54196998 5 P 0 8 0;1=8
P 6.09401998 0.54196998 5 P 0 8 0;1=8
P 6.05401998 0.54196998 5 P 0 8 0;1=8
P 6.01401998 0.54196998 5 P 0 8 0;1=8
P 5.97401998 0.54196998 5 P 0 8 0;1=8
P 5.93401998 0.54196998 5 P 0 8 0;1=8
P 5.89401998 0.54196998 5 P 0 8 0;1=8
P 5.85401998 0.54196998 5 P 0 8 0;1=8
P 5.81401998 0.54196998 5 P 0 8 0;1=8
P 5.77401998 0.54196998 5 P 0 8 0;1=8
P 5.73401998 0.54196998 5 P 0 8 0;1=8
P 5.69401998 0.54196998 5 P 0 8 0;1=8
P 5.65401998 0.54196998 5 P 0 8 0;1=8
P 5.61401998 0.54196998 5 P 0 8 0;1=8
P 5.57401998 0.54196998 5 P 0 8 0;1=8
P 5.53401998 0.54196998 5 P 0 8 0;1=8
P 5.49401998 0.54196998 5 P 0 8 0;1=8
P 5.45401998 0.54196998 5 P 0 8 0;1=8
P 5.41401998 0.54196998 5 P 0 8 0;1=8
P 5.37401998 0.54196998 5 P 0 8 0;1=8
P 5.33401998 0.54196998 5 P 0 8 0;1=8
P 5.29401998 0.54196998 5 P 0 8 0;1=8
P 5.25401998 0.54196998 5 P 0 8 0;1=8
P 5.21401998 0.54196998 5 P 0 8 0;1=8
P 5.17401998 0.54196998 5 P 0 8 0;1=8
P 5.13401998 0.54196998 5 P 0 8 0;1=8
P 5.09401998 0.54196998 5 P 0 8 0;1=8
P 5.05401998 0.54196998 5 P 0 8 0;1=8
P 5.01401998 0.54196998 5 P 0 8 0;1=8
P 4.97401998 0.54196998 5 P 0 8 0;1=8
P 4.93401998 0.54196998 5 P 0 8 0;1=8
P 4.89401998 0.54196998 5 P 0 8 0;1=8
P 4.85401998 0.54196998 5 P 0 8 0;1=8
P 4.81401998 0.54196998 5 P 0 8 0;1=8
P 4.77401998 0.54196998 5 P 0 8 0;1=8
P 4.73401998 0.54196998 5 P 0 8 0;1=8
P 4.69401998 0.54196998 5 P 0 8 0;1=8
P 4.65401998 0.54196998 5 P 0 8 0;1=8
P 4.61401998 0.54196998 5 P 0 8 0;1=8
P 4.57401998 0.54196998 5 P 0 8 0;1=8
P 4.53401998 0.54196998 5 P 0 8 0;1=8
P 4.49401998 0.54196998 5 P 0 8 0;1=8
P 4.45401998 0.54196998 5 P 0 8 0;1=8
P 4.41401998 0.54196998 5 P 0 8 0;1=8
P 4.37401998 0.54196998 5 P 0 8 0;1=8
P 4.33401998 0.54196998 5 P 0 8 0;1=8
P 4.29401998 0.54196998 5 P 0 8 0;1=8
P 4.25401998 0.54196998 5 P 0 8 0;1=8
P 4.21401998 0.54196998 5 P 0 8 0;1=8
P 4.17401998 0.54196998 5 P 0 8 0;1=8
P 2.80413002 4.33598002 5 P 0 8 0;1=8
P 2.84413002 4.33598002 5 P 0 8 0;1=8
P 2.88413002 4.33598002 5 P 0 8 0;1=8
P 2.92413002 4.33598002 5 P 0 8 0;1=8
P 2.96413002 4.33598002 5 P 0 8 0;1=8
P 3.00413002 4.33598002 5 P 0 8 0;1=8
P 3.04413002 4.33598002 5 P 0 8 0;1=8
P 3.08413002 4.33598002 5 P 0 8 0;1=8
P 3.12413002 4.33598002 5 P 0 8 0;1=8
P 3.16413002 4.33598002 5 P 0 8 0;1=8
P 3.20413002 4.33598002 5 P 0 8 0;1=8
P 3.24413002 4.33598002 5 P 0 8 0;1=8
P 3.28413002 4.33598002 5 P 0 8 0;1=8
P 3.32413002 4.33598002 5 P 0 8 0;1=8
P 3.36413002 4.33598002 5 P 0 8 0;1=8
P 3.40413002 4.33598002 5 P 0 8 0;1=8
P 3.44413002 4.33598002 5 P 0 8 0;1=8
P 3.48413002 4.33598002 5 P 0 8 0;1=8
P 3.52413002 4.33598002 5 P 0 8 0;1=8
P 3.56413002 4.33598002 5 P 0 8 0;1=8
P 3.60413002 4.33598002 5 P 0 8 0;1=8
P 3.64413002 4.33598002 5 P 0 8 0;1=8
P 3.68413002 4.33598002 5 P 0 8 0;1=8
P 3.72413002 4.33598002 5 P 0 8 0;1=8
P 3.76413002 4.33598002 5 P 0 8 0;1=8
P 3.80413002 4.33598002 5 P 0 8 0;1=8
P 3.84413002 4.33598002 5 P 0 8 0;1=8
P 3.88413002 4.33598002 5 P 0 8 0;1=8
P 3.92413002 4.33598002 5 P 0 8 0;1=8
P 3.96413002 4.33598002 5 P 0 8 0;1=8
P 4.00413002 4.33598002 5 P 0 8 0;1=8
P 4.04413002 4.33598002 5 P 0 8 0;1=8
P 4.08413002 4.33598002 5 P 0 8 0;1=8
P 4.12413002 4.33598002 5 P 0 8 0;1=8
P 4.16413002 4.33598002 5 P 0 8 0;1=8
P 4.20413002 4.33598002 5 P 0 8 0;1=8
P 4.24413002 4.33598002 5 P 0 8 0;1=8
P 4.28413002 4.33598002 5 P 0 8 0;1=8
P 4.32413002 4.33598002 5 P 0 8 0;1=8
P 4.36413002 4.33598002 5 P 0 8 0;1=8
P 4.40413002 4.33598002 5 P 0 8 0;1=8
P 4.44413002 4.33598002 5 P 0 8 0;1=8
P 4.48413002 4.33598002 5 P 0 8 0;1=8
P 4.52413002 4.33598002 5 P 0 8 0;1=8
P 4.56413002 4.33598002 5 P 0 8 0;1=8
P 4.60413002 4.33598002 5 P 0 8 0;1=8
P 4.64413002 4.33598002 5 P 0 8 0;1=8
P 4.68413002 4.33598002 5 P 0 8 0;1=8
P 4.72413002 4.33598002 5 P 0 8 0;1=8
P 4.76413002 4.33598002 5 P 0 8 0;1=8
P 4.80413002 4.33598002 5 P 0 8 0;1=8
P 4.84413002 4.33598002 5 P 0 8 0;1=8
P 4.88413002 4.33598002 5 P 0 8 0;1=8
P 4.92413002 4.33598002 5 P 0 8 0;1=8
P 4.96413002 4.33598002 5 P 0 8 0;1=8
P 5.00413002 4.33598002 5 P 0 8 0;1=8
P 5.04413002 4.33598002 5 P 0 8 0;1=8
P 5.08413002 4.33598002 5 P 0 8 0;1=8
P 5.12413002 4.33598002 5 P 0 8 0;1=8
P 5.16413002 4.33598002 5 P 0 8 0;1=8
P 5.20413002 4.33598002 5 P 0 8 0;1=8
P 5.24413002 4.33598002 5 P 0 8 0;1=8
P 5.28413002 4.33598002 5 P 0 8 0;1=8
P 5.32413002 4.33598002 5 P 0 8 0;1=8
P 5.36413002 4.33598002 5 P 0 8 0;1=8
P 5.40413002 4.33598002 5 P 0 8 0;1=8
P 5.44413002 4.33598002 5 P 0 8 0;1=8
P 5.48413002 4.33598002 5 P 0 8 0;1=8
P 5.52413002 4.33598002 5 P 0 8 0;1=8
P 5.56413002 4.33598002 5 P 0 8 0;1=8
P 5.60413002 4.33598002 5 P 0 8 0;1=8
P 5.64413002 4.33598002 5 P 0 8 0;1=8
P 5.68413002 4.33598002 5 P 0 8 0;1=8
P 5.72413002 4.33598002 5 P 0 8 0;1=8
P 5.76413002 4.33598002 5 P 0 8 0;1=8
P 5.80413002 4.33598002 5 P 0 8 0;1=8
P 5.84413002 4.33598002 5 P 0 8 0;1=8
P 5.88413002 4.33598002 5 P 0 8 0;1=8
P 5.92413002 4.33598002 5 P 0 8 0;1=8
P 5.96413002 4.33598002 5 P 0 8 0;1=8
P 6.00413002 4.33598002 5 P 0 8 0;1=8
P 6.04413002 4.33598002 5 P 0 8 0;1=8
P 6.08413002 4.33598002 5 P 0 8 0;1=8
P 6.12413002 4.33598002 5 P 0 8 0;1=8
P 6.16413002 4.33598002 5 P 0 8 0;1=8
P 6.20413002 4.33598002 5 P 0 8 0;1=8
P 6.24413002 4.33598002 5 P 0 8 0;1=8
P 6.28413002 4.33598002 5 P 0 8 0;1=8
P 6.32413002 4.33598002 5 P 0 8 0;1=8
P 6.36413002 4.33598002 5 P 0 8 0;1=8
P 6.40413002 4.33598002 5 P 0 8 0;1=8
P 6.44413002 4.33598002 5 P 0 8 0;1=8
P 6.48413002 4.33598002 5 P 0 8 0;1=8
P 6.52413002 4.33598002 5 P 0 8 0;1=8
P 6.56038996 4.31908996 5 P 0 8 0;1=8
P 6.56038996 4.27908996 5 P 0 8 0;1=8
P 6.56038996 4.23908996 5 P 0 8 0;1=8
P 6.56038996 4.19908996 5 P 0 8 0;1=8
P 6.56038996 4.15908996 5 P 0 8 0;1=8
P 6.56038996 4.11908996 5 P 0 8 0;1=8
P 6.56038996 4.07908996 5 P 0 8 0;1=8
P 6.56038996 4.03908996 5 P 0 8 0;1=8
P 6.56038996 3.99908996 5 P 0 8 0;1=8
P 6.56038996 3.95908996 5 P 0 8 0;1=8
P 6.56038996 3.91908996 5 P 0 8 0;1=8
P 6.56038996 3.87908996 5 P 0 8 0;1=8
P 6.56038996 3.83908996 5 P 0 8 0;1=8
P 6.56038996 3.79908996 5 P 0 8 0;1=8
P 6.56038996 3.75908996 5 P 0 8 0;1=8
P 6.56038996 3.71908996 5 P 0 8 0;1=8
P 6.56038996 3.67908996 5 P 0 8 0;1=8
P 6.56038996 3.63908996 5 P 0 8 0;1=8
P 6.56038996 3.59908996 5 P 0 8 0;1=8
P 6.56038996 3.55908996 5 P 0 8 0;1=8
P 6.56038996 3.51908996 5 P 0 8 0;1=8
P 6.56038996 3.47908996 5 P 0 8 0;1=8
P 6.56038996 3.43908996 5 P 0 8 0;1=8
P 6.56038996 3.39908996 5 P 0 8 0;1=8
P 6.56038996 3.35908996 5 P 0 8 0;1=8
P 6.56038996 3.31908996 5 P 0 8 0;1=8
P 6.56038996 3.27908996 5 P 0 8 0;1=8
P 6.56038996 3.23908996 5 P 0 8 0;1=8
P 6.56038996 3.19908996 5 P 0 8 0;1=8
P 6.56038996 3.15908996 5 P 0 8 0;1=8
P 6.56038996 3.11908996 5 P 0 8 0;1=8
P 6.56038996 2.35585 5 P 0 8 0;1=8
P 5.119 2.762 6 P 0 8 0;1=2
P 5.63341004 0.62101998 6 P 0 8 0;1=2
P 5.59941004 0.6212 6 P 0 8 0;1=2
P 2.419 2.388 6 P 0 8 0;1=2
P 2.805 2.243 6 P 0 8 0;1=2
P 2.7526 2.23 6 P 0 8 0;1=2
P 4.278 1.003 6 P 0 8 0;1=2
P 3.08966998 2.04 6 P 0 8 0;1=2
P 2.41441004 2.15 6 P 0 8 0;1=2
P 2.69 2.15 6 P 0 8 0;1=2
P 5.83 1.92 6 P 0 8 0;1=2
P 5.805 1.945 6 P 0 8 0;1=2
P 5.045 3.76 6 P 0 8 0;1=2
P 5.05 3.795 6 P 0 8 0;1=2
P 4.54 3.97 6 P 0 8 0;1=2
P 4.54 3.935 6 P 0 8 0;1=2
P 4.62 2.5 6 P 0 8 0;1=2
P 3.305 2.915 6 P 0 8 0;1=2
P 3.145 2.765 6 P 0 8 0;1=2
P 6.105 2.27 6 P 0 8 0;1=2
P 6.141 2.241 6 P 0 8 0;1=2
P 2.54 2.135 6 P 0 8 0;1=2
P 2.59 2.23 6 P 0 8 0;1=2
P 5.859 0.796 6 P 0 8 0;1=2
P 5.80643002 0.609 6 P 0 8 0;1=2
P 5.805 0.658 6 P 0 8 0;1=2
P 5.37 0.69 6 P 0 8 0;1=2
P 5.43956998 0.60543002 6 P 0 8 0;1=2
P 6.335 1.96873996 6 P 0 8 0;1=2
P 5.59 0.888 6 P 0 8 0;1=2
P 4.933 1.215 6 P 0 8 0;1=2
P 4.894 1.263 6 P 0 8 0;1=2
P 4.79866998 1.38866998 6 P 0 8 0;1=2
P 5.0395 1.43 6 P 0 8 0;1=2
P 4.44 2.5 6 P 0 8 0;1=2
P 4.965 1.925 6 P 0 8 0;1=2
P 4.96 2.055 6 P 0 8 0;1=2
P 5.346 1.52 6 P 0 8 0;1=2
P 5.346 1.483 6 P 0 8 0;1=2
P 4.96 1.675 6 P 0 8 0;1=2
P 3.99 2.25 6 P 0 8 0;1=2
P 3.99 2.21406998 6 P 0 8 0;1=2
P 3.7206 2.13 6 P 0 8 0;1=2
P 3.6956 2.13 6 P 0 8 0;1=2
P 4.78 1.98 6 P 0 8 0;1=2
P 5.6065 0.7045 6 P 0 8 0;1=15
P 5.602 0.815 6 P 0 8 0;1=2
P 5.59 0.85 6 P 0 8 0;1=2
P 5.625 0.746 6 P 0 8 0;1=2
P 4.22 0.775 6 P 0 8 0;1=2
P 4.345 0.77 6 P 0 8 0;1=2
P 4.4843 0.8954 6 P 0 8 0;1=2
P 4.442 1.005 6 P 0 8 0;1=2
P 4.31 1.165 6 P 0 8 0;1=2
P 4.414 0.781 6 P 0 8 0;1=0
P 4.335 1.005 6 P 0 8 0;1=2
P 4.23 1.005 6 P 0 8 0;1=2
P 3.12 2.955 6 P 0 8 0;1=2
P 2.995 2.955 6 P 0 8 0;1=2
P 2.92 2.9472 6 P 0 8 0;1=2
P 2.88 2.93 6 P 0 8 0;1=2
P 3.01 3.12 6 P 0 8 0;1=2
P 5.121 2.447 6 P 0 8 0;1=2
P 5.121 2.407 6 P 0 8 0;1=2
P 5.298 2.23 6 P 0 8 0;1=2
P 5.332 2.2 6 P 0 8 0;1=0
P 5.369 2.015 6 P 0 8 0;1=2
P 5.435 2.05 6 P 0 8 0;1=2
P 5.409 2.015 6 P 0 8 0;1=2
P 5.071 2.407 6 P 0 8 0;1=2
P 4.815 1.82016004 6 P 0 8 0;1=2
P 4.44 2.26 6 P 0 8 0;1=2
P 3.67 2.41243002 6 P 0 8 0;1=2
P 3.67 2.32 6 P 0 8 0;1=0
P 3.54975 2.479 6 P 0 8 0;1=2
P 3.605 2.43 6 P 0 8 0;1=2
P 3.55 2.425 6 P 0 8 0;1=2
P 3.415 2.335 6 P 0 8 0;1=2
P 3.505 2.295 6 P 0 8 0;1=2
P 3.40953002 2.37 6 P 0 8 0;1=2
P 3.116 2.524 6 P 0 8 0;1=2
P 3.12 2.344 6 P 0 8 0;1=2
P 3.12 2.17 6 P 0 8 0;1=0
P 3.512 1.966 6 P 0 8 0;1=2
P 4.395 3.37891998 5 P 0 8 0;1=8
P 4.44 4.165 5 P 0 8 0;1=8
P 2.86151004 3.295 5 P 0 8 0;1=8
P 3.21898996 3.43 6 P 0 8 0;1=2
P 3.548 2.898 5 P 0 8 0;1=8
P 3.621 2.91 6 P 0 8 0;1=2
P 3.658 2.861 6 P 0 8 0;1=2
P 3.658 2.911 6 P 0 8 0;1=2
P 3.623 2.861 6 P 0 8 0;1=2
P 3.615 2.961 6 P 0 8 0;1=2
P 3.253 3.917 6 P 0 8 0;1=2
P 3.253 3.962 6 P 0 8 0;1=2
P 3.248 4.107 6 P 0 8 0;1=2
P 3.213 4.167 6 P 0 8 0;1=2
P 3.248 4.152 6 P 0 8 0;1=2
P 3.213 4.236 6 P 0 8 0;1=0
P 3.253 3.872 6 P 0 8 0;1=2
P 4.465 2.895 5 P 0 8 0;1=8
P 4.093 2.863 6 P 0 8 0;1=2
P 4.091 2.813 6 P 0 8 0;1=2
P 4.092 2.917 6 P 0 8 0;1=2
P 3.78 2.735 6 P 0 8 0;1=2
P 3.435 2.589 6 P 0 8 0;1=2
P 3.5485 2.761 5 P 0 8 0;1=8
P 3.285 2.589 6 P 0 8 0;1=0
P 4.775 2.59 6 P 0 8 0;1=2
P 4.71 2.592 6 P 0 8 0;1=0
P 4.918 2.777 6 P 0 8 0;1=2
P 4.925 2.722 6 P 0 8 0;1=2
P 3.106 3.305 5 P 0 8 0;1=8
P 3.222 3.25 5 P 0 8 0;1=8
P 3.975 3.129 6 P 0 8 0;1=2
P 3.998 2.784 6 P 0 8 0;1=2
P 3.83 2.932 6 P 0 8 0;1=2
P 3.78 2.932 6 P 0 8 0;1=2
P 3.703 2.911 6 P 0 8 0;1=2
P 3.748 2.911 6 P 0 8 0;1=2
P 3.933 3.125 6 P 0 8 0;1=2
P 3.6 4.024 6 P 0 8 0;1=2
P 3.631 4.228 6 P 0 8 0;1=2
P 3.60311004 4.0988 6 P 0 8 0;1=2
P 3.631 4.183 6 P 0 8 0;1=2
P 3.38 3.15 6 P 0 8 0;1=2
P 4.43 3.965 5 P 0 8 0;1=8
P 4.43 4.015 5 P 0 8 0;1=8
P 4.714 3.633 6 P 0 8 0;1=2
P 4.71 3.47 6 P 0 8 0;1=2
P 4.94093996 4.12008002 17 P 0 8 0;1=18
P 4.94093996 3.09646004 17 P 0 8 0;1=18
P 3.8865 2.9265 6 P 0 8 0;1=15
P 2.55906004 4.12008002 17 P 0 8 0;1=18
P 2.55906004 3.09646004 17 P 0 8 0;1=18
P 5.815 2.67 6 P 0 8 0;1=2
P 5.517 2.563 6 P 0 8 0;1=2
P 5.49 2.675 6 P 0 8 0;1=2
P 5.3035 2.5748 6 P 0 8 0;1=2
P 5.122 2.587 6 P 0 8 0;1=2
P 5.123 2.544 6 P 0 8 0;1=2
P 5.121 2.495 6 P 0 8 0;1=2
P 5.121 2.625 6 P 0 8 0;1=2
P 5.41346004 3.03506998 6 P 0 8 0;1=2
P 5.814 2.9225 6 P 0 8 0;1=2
P 5.25176004 4.11925 6 P 0 8 0;1=2
P 5.88778996 3.34448996 12 P 0 8 0;1=13
P 5.88778996 3.50983996 12 P 0 8 0;1=13
P 5.88778996 3.67518996 12 P 0 8 0;1=13
P 5.538 2.402 6 P 0 8 0;1=2
P 5.666 2.129 5 P 0 8 0;1=8
P 5.647 2.044 6 P 0 8 0;1=2
P 5.687 2.043 6 P 0 8 0;1=2
P 5.732 2.043 6 P 0 8 0;1=2
P 5.865 2.3 6 P 0 8 0;1=2
P 6.36 2.16141998 6 P 0 8 0;1=2
P 6.51581998 2.24803996 18 P 0 8 0;1=19
P 6.51581998 1.97243996 18 P 0 8 0;1=20
P 6.40951998 2.20866998 9 P 0 8 0;1=21
P 6.40951998 2.01181004 9 P 0 8 0;1=21
P 0.06038996 1.38346004 11 P 0 8 0;1=22
P 0.26038996 1.38346004 11 P 0 8 0;1=22
P 0.06038996 1.18346004 11 P 0 8 0;1=22
P 0.26038996 1.18346004 11 P 0 8 0;1=22
P 0.06038996 0.8126 11 P 0 8 0;1=22
P 0.26038996 0.8126 11 P 0 8 0;1=22
P 0.06038996 0.6126 11 P 0 8 0;1=22
P 0.26038996 0.6126 11 P 0 8 0;1=22
P 0.06038996 2.5252 11 P 0 8 0;1=22
P 0.26038996 2.5252 11 P 0 8 0;1=22
P 0.06038996 2.3252 11 P 0 8 0;1=22
P 0.26038996 2.3252 11 P 0 8 0;1=22
P 0.06038996 1.95433002 11 P 0 8 0;1=22
P 0.26038996 1.95433002 11 P 0 8 0;1=22
P 0.06038996 1.75433002 11 P 0 8 0;1=22
P 0.26038996 1.75433002 11 P 0 8 0;1=22
P 1.26066998 1.84043002 13 P 0 8 0;1=14
P 5.91901998 2.003 5 P 0 8 0;1=7
P 6.06901998 2.004 5 P 0 8 0;1=7
P 3.49 0.825 5 P 0 8 0;1=7
P 2.65966998 0.93443002 13 P 0 8 0;1=14
P 6.095 2.545 6 P 0 8 0;1=0
P 5.07 1.885 6 P 0 8 0;1=2
P 5.33 0.995 5 P 0 8 0;1=8
P 3.54 0.825 6 P 0 8 0;1=2
P 6.04 2.545 6 P 0 8 0;1=0
P 5.07 1.925 6 P 0 8 0;1=2
P 5.33 0.95 5 P 0 8 0;1=8
P 2.53966998 0.93443002 13 P 0 8 0;1=14
P 2.802 1.987 5 P 0 8 0;1=8
P 2.834 1.987 5 P 0 8 0;1=8
P 2.845 1.875 5 P 0 8 0;1=8
P 2.845 1.843 5 P 0 8 0;1=8
P 2.77866998 0.93443002 13 P 0 8 0;1=14
P 4.97 1.54 4 P 0 8 0;1=3
P 4.9806 1.855 6 P 0 8 0;1=0
P 1.26066998 1.04043002 13 P 0 8 0;1=14
P 0.724 2.646 6 P 0 8 0;1=0
P 0.758 2.743 3 P 0 8 0;1=4
P 3.235 2.63 4 P 0 8 0;1=3
P 3.275 2.32 3 P 0 8 0;1=4
P 3.24 2.275 6 P 0 8 0;1=0
P 3.305 2.65 4 P 0 8 0;1=3
P 3.375 2.65 4 P 0 8 0;1=3
P 3.326 2.466 3 P 0 8 0;1=4
P 2.1481 0.7881 5 P 0 8 0;1=7
P 5.08 1.105 6 P 0 8 0;1=2
P 5.225 1.145 6 P 0 8 0;1=2
P 5.132 0.66 6 P 0 8 0;1=2
P 2.0816 0.7399 6 P 0 8 0;1=2
P 2.03 0.75 5 P 0 8 0;1=7
P 5.08 1.155 6 P 0 8 0;1=2
P 5.08 1.055 6 P 0 8 0;1=2
P 2.0788 0.7874 5 P 0 8 0;1=7
P 2.29581998 0.48918002 4 P 0 8 0;1=3
P 2.633 0.522 5 P 0 8 0;1=8
P 3.455 0.87 6 P 0 8 0;1=2
P 0.9225 0.9775 6 P 0 8 0;1=2
P 4.82 0.835 6 P 0 8 0;1=0
P 0.8825 1.7725 6 P 0 8 0;1=2
P 3.405 0.87 6 P 0 8 0;1=2
P 0.965 0.98 6 P 0 8 0;1=2
P 0.91 1.815 6 P 0 8 0;1=0
P 4.78 0.78 6 P 0 8 0;1=2
P 4.42311004 1.86311004 3 P 0 8 0;1=11
P 3.65101004 1.88358996 4 P 0 8 0;1=9
P 4.46248002 1.86311004 3 P 0 8 0;1=11
P 3.65101004 1.91558996 4 P 0 8 0;1=9
P 3.065 1.695 4 P 0 8 0;1=3
P 2.98283996 1.75183996 6 P 0 8 0;1=2
P 2.225 3.245 6 P 0 8 0;1=2
P 4.595 2.62 6 P 0 8 0;1=2
P 4.025 3.08 6 P 0 8 0;1=2
P 0.62 3.07 6 P 0 8 0;1=2
P 5.865 1.125 6 P 0 8 0;1=0
P 5.865 1.07 6 P 0 8 0;1=0
P 2.265 3.34 6 P 0 8 0;1=2
P 4.57 2.585 6 P 0 8 0;1=2
P 4.02 3.03 6 P 0 8 0;1=2
P 0.645 2.9675 6 P 0 8 0;1=2
P 5.48828996 4.16328996 6 P 0 8 0;1=0
P 3.99005 1.90248002 4 P 0 8 0;1=1
P 5.55315 4.175 6 P 0 8 0;1=0
P 3.99005 1.86311004 4 P 0 8 0;1=1
P 5.67126004 4.175 6 P 0 8 0;1=0
P 3.95066998 1.82373996 4 P 0 8 0;1=1
P 5.78936998 4.175 6 P 0 8 0;1=0
P 3.9113 1.82373996 4 P 0 8 0;1=1
P 4.205 2.295 4 P 0 8 0;1=3
P 4.65933002 1.6269 4 P 0 8 0;1=3
P 4.254 2.296 4 P 0 8 0;1=3
P 4.23 2.354 4 P 0 8 0;1=3
P 4.915 1.485 4 P 0 8 0;1=3
P 4.65933002 1.54816004 4 P 0 8 0;1=1
P 3.94 2.235 4 P 0 8 0;1=3
P 4.85 1.54 4 P 0 8 0;1=3
P 4.149 2.298 4 P 0 8 0;1=3
P 4.161 2.354 4 P 0 8 0;1=3
P 3.75 2.1 4 P 0 8 0;1=3
P 4.975 1.485 4 P 0 8 0;1=3
P 4.58058996 1.58753002 4 P 0 8 0;1=1
P 3.8 2.1 4 P 0 8 0;1=3
P 4.73806998 1.54816004 4 P 0 8 0;1=3
P 3.9 2.325 4 P 0 8 0;1=3
P 4.73806998 1.50878996 4 P 0 8 0;1=3
P 3.83 2.325 4 P 0 8 0;1=3
P 0.846 2.489 3 P 0 8 0;1=4
P 3.28 3.065 6 P 0 8 0;1=2
P 0.796 2.489 3 P 0 8 0;1=4
P 3.325 3.065 6 P 0 8 0;1=2
P 5.03 3.546 3 P 0 8 0;1=4
P 4.935 3.59 3 P 0 8 0;1=4
P 4.67 3.555 4 P 0 8 0;1=3
P 4.885 3.59 5 P 0 8 0;1=7
P 4.70461998 3.69461998 3 P 0 8 0;1=4
P 4.50185 1.82373996 4 P 0 8 0;1=1
P 5.395 2.92 6 P 0 8 0;1=0
P 5.015 1.925 6 P 0 8 0;1=2
P 5.39976998 2.75123996 5 P 0 8 0;1=7
P 4.46248002 1.82373996 4 P 0 8 0;1=1
P 5.375 2.96606998 5 P 0 8 0;1=7
P 4.58058996 1.78436998 4 P 0 8 0;1=1
P 5.4525 2.563 5 P 0 8 0;1=7
P 3.545 0.6092 6 P 0 8 0;1=2
P 1.395 0.625 5 P 0 8 0;1=7
P 5.085 0.645 6 P 0 8 0;1=2
P 3.495 0.61 6 P 0 8 0;1=2
P 5.04 0.645 6 P 0 8 0;1=2
P 1.485 0.625 5 P 0 8 0;1=7
P 3.99005 1.6269 3 P 0 8 0;1=11
P 2.95835 0.385 4 P 0 8 0;1=9
P 3.95066998 1.6269 3 P 0 8 0;1=11
P 2.95835 0.353 4 P 0 8 0;1=9
P 3.9113 1.66626998 3 P 0 8 0;1=11
P 2.80086998 0.385 4 P 0 8 0;1=9
P 3.87193002 1.66626998 3 P 0 8 0;1=11
P 2.80086998 0.353 4 P 0 8 0;1=9
P 3.99005 1.70563996 3 P 0 8 0;1=11
P 2.64338996 0.385 4 P 0 8 0;1=9
P 3.95066998 1.70563996 3 P 0 8 0;1=11
P 2.64338996 0.353 4 P 0 8 0;1=9
P 3.9113 1.58753002 3 P 0 8 0;1=11
P 2.95835 0.481 4 P 0 8 0;1=9
P 2.95835 0.449 4 P 0 8 0;1=9
P 3.87193002 1.58753002 3 P 0 8 0;1=11
P 3.125 0.875 4 P 0 8 0;1=9
P 3.99005 1.54816004 3 P 0 8 0;1=11
P 3.14763002 0.85236998 4 P 0 8 0;1=9
P 3.95066998 1.54816004 3 P 0 8 0;1=11
P 2.81855 0.763 4 P 0 8 0;1=9
P 3.9113 1.50878996 3 P 0 8 0;1=11
P 2.85055 0.763 4 P 0 8 0;1=9
P 3.87193002 1.50878996 3 P 0 8 0;1=11
P 2.66706998 0.763 4 P 0 8 0;1=9
P 3.99005 1.46941998 3 P 0 8 0;1=11
P 2.69906998 0.763 4 P 0 8 0;1=9
P 3.95066998 1.46941998 3 P 0 8 0;1=11
P 2.47021998 0.763 4 P 0 8 0;1=9
P 3.9113 1.43005 3 P 0 8 0;1=11
P 2.50221998 0.763 4 P 0 8 0;1=9
P 3.87193002 1.43005 3 P 0 8 0;1=11
P 1.889 0.5496 6 P 0 8 0;1=2
P 2.435 0.4865 3 P 0 8 0;1=4
P 3.56 3.023 6 P 0 8 0;1=0
P 3.57 2.955 6 P 0 8 0;1=0
P 4.975 2.14 6 P 0 8 0;1=2
P 5.03005 0.99493996 6 P 0 8 0;1=0
P 5.638 3.907 6 P 0 8 0;1=0
P 1.8317 0.5639 5 P 0 8 0;1=7
P 2.68566998 1.12143002 14 P 0 8 0;1=23
P 2.68566998 2.55943002 14 P 0 8 0;1=23
P 1.46066998 2.68043002 14 P 0 8 0;1=23
P 1.43566998 1.06043002 14 P 0 8 0;1=23
P 6.40038996 0.65353996 16 P 0 8 0;1=24
P 0.29528002 3.73031004 16 P 0 8 0;1=24
P 0.29528002 0.36811004 16 P 0 8 0;1=24
P 6.40038996 4.17835 16 P 0 8 0;1=24
P 6.34055 3.34448996 15 P 0 8 0;1=25
P 6.34055 3.67518996 15 P 0 8 0;1=25
L 3.80999961 -1.25 3.80999961 -1.33 1 N 0 ;0
L 3.80999961 -1.33 3.8500003 -1.33 1 N 0 ;0
L 3.90999902 -1.25 3.90199892 -1.25266614 1 N 0 ;0
L 3.90199892 -1.25266614 3.8960002 -1.25933386 1 N 0 ;0
L 3.8960002 -1.25933386 3.89199921 -1.26733209 1 N 0 ;0
L 3.89199921 -1.26733209 3.8889999 -1.27800138 1 N 0 ;0
L 3.8889999 -1.27800138 3.8880001 -1.29000128 1 N 0 ;0
L 3.8880001 -1.29000128 3.8889999 -1.30200118 1 N 0 ;0
L 3.8889999 -1.30200118 3.89199921 -1.31266801 1 N 0 ;0
L 3.89199921 -1.31266801 3.8960002 -1.3206687 1 N 0 ;0
L 3.8960002 -1.3206687 3.90199892 -1.32733396 1 N 0 ;0
L 3.90199892 -1.32733396 3.90999902 -1.33 1 N 0 ;0
L 3.90999902 -1.33 3.91799911 -1.32733396 1 N 0 ;0
L 3.91799911 -1.32733396 3.9239997 -1.3206687 1 N 0 ;0
L 3.9239997 -1.3206687 3.92800069 -1.31266801 1 N 0 ;0
L 3.92800069 -1.31266801 3.931 -1.30200118 1 N 0 ;0
L 3.931 -1.30200118 3.9319998 -1.29000128 1 N 0 ;0
L 3.9319998 -1.29000128 3.931 -1.27800138 1 N 0 ;0
L 3.931 -1.27800138 3.92800069 -1.26733209 1 N 0 ;0
L 3.92800069 -1.26733209 3.9239997 -1.25933386 1 N 0 ;0
L 3.9239997 -1.25933386 3.91799911 -1.25266614 1 N 0 ;0
L 3.91799911 -1.25266614 3.90999902 -1.25 1 N 0 ;0
L 3.9680001 -1.31800266 3.97399882 -1.32466782 1 N 0 ;0
L 3.97399882 -1.32466782 3.98099911 -1.32866703 1 N 0 ;0
L 3.98099911 -1.32866703 3.98999902 -1.33 1 N 0 ;0
L 3.98999902 -1.33 3.99900079 -1.32733396 1 N 0 ;0
L 3.99900079 -1.32733396 4.00599931 -1.32200177 1 N 0 ;0
L 4.00599931 -1.32200177 4.011 -1.31266801 1 N 0 ;0
L 4.011 -1.31266801 4.0119998 -1.30200118 1 N 0 ;0
L 4.0119998 -1.30200118 4.0100003 -1.29133435 1 N 0 ;0
L 4.0100003 -1.29133435 4.00499951 -1.28466663 1 N 0 ;0
L 4.00499951 -1.28466663 3.99799911 -1.27933445 1 N 0 ;0
L 3.99799911 -1.27933445 3.99100069 -1.27800138 1 N 0 ;0
L 3.99100069 -1.27800138 3.9840003 -1.27933445 1 N 0 ;0
L 3.9840003 -1.27933445 3.97500039 -1.28466663 1 N 0 ;0
L 3.97500039 -1.28466663 3.9779998 -1.25 1 N 0 ;0
L 3.9779998 -1.25 4.00499951 -1.25 1 N 0 ;0
L 4.04 -1.35666585 4.1 -1.35666585 1 N 0 ;0
L 4.12499892 -1.25 4.14999902 -1.33 1 N 0 ;0
L 4.14999902 -1.33 4.17500098 -1.25 1 N 0 ;0
L 4.2519998 -1.25666772 4.24599931 -1.25266614 1 N 0 ;0
L 4.24599931 -1.25266614 4.23900079 -1.25 1 N 0 ;0
L 4.23900079 -1.25 4.23100069 -1.25 1 N 0 ;0
L 4.23100069 -1.25 4.22199892 -1.25400167 1 N 0 ;0
L 4.22199892 -1.25400167 4.21500039 -1.26066683 1 N 0 ;0
L 4.21500039 -1.26066683 4.20999961 -1.26866762 1 N 0 ;0
L 4.20999961 -1.26866762 4.20599862 -1.28200049 1 N 0 ;0
L 4.20599862 -1.28200049 4.20499892 -1.29400039 1 N 0 ;0
L 4.20499892 -1.29400039 4.2070003 -1.3060003 1 N 0 ;0
L 4.2070003 -1.3060003 4.20999961 -1.31400098 1 N 0 ;0
L 4.20999961 -1.31400098 4.2160002 -1.32200177 1 N 0 ;0
L 4.2160002 -1.32200177 4.22300049 -1.32733396 1 N 0 ;0
L 4.22300049 -1.32733396 4.22999902 -1.33 1 N 0 ;0
L 4.22999902 -1.33 4.23699941 -1.33 1 N 0 ;0
L 4.23699941 -1.33 4.2439997 -1.32733396 1 N 0 ;0
L 4.2439997 -1.32733396 4.2500003 -1.32333484 1 N 0 ;0
L 4.2500003 -1.32333484 4.25500098 -1.31800266 1 N 0 ;0
L 4.3319998 -1.25666772 4.32599931 -1.25266614 1 N 0 ;0
L 4.32599931 -1.25266614 4.31900079 -1.25 1 N 0 ;0
L 4.31900079 -1.25 4.31100069 -1.25 1 N 0 ;0
L 4.31100069 -1.25 4.30199892 -1.25400167 1 N 0 ;0
L 4.30199892 -1.25400167 4.29500039 -1.26066683 1 N 0 ;0
L 4.29500039 -1.26066683 4.28999961 -1.26866762 1 N 0 ;0
L 4.28999961 -1.26866762 4.28599862 -1.28200049 1 N 0 ;0
L 4.28599862 -1.28200049 4.28499892 -1.29400039 1 N 0 ;0
L 4.28499892 -1.29400039 4.2870003 -1.3060003 1 N 0 ;0
L 4.2870003 -1.3060003 4.28999961 -1.31400098 1 N 0 ;0
L 4.28999961 -1.31400098 4.2960002 -1.32200177 1 N 0 ;0
L 4.2960002 -1.32200177 4.30300049 -1.32733396 1 N 0 ;0
L 4.30300049 -1.32733396 4.30999902 -1.33 1 N 0 ;0
L 4.30999902 -1.33 4.31699941 -1.33 1 N 0 ;0
L 4.31699941 -1.33 4.3239997 -1.32733396 1 N 0 ;0
L 4.3239997 -1.32733396 4.3300003 -1.32333484 1 N 0 ;0
L 4.3300003 -1.32333484 4.33500098 -1.31800266 1 N 0 ;0
L 4.38999902 -1.33 4.38999902 -1.25 1 N 0 ;0
L 4.38999902 -1.25 4.3779998 -1.26599911 1 N 0 ;0
L 4.3779998 -1.33 4.40199833 -1.33 1 N 0 ;0
L 3.16 -0.655 3.16 -1.58 2 N 0 ;0
L 1.36 -0.655 1.36 -1.58 2 N 0 ;0
L 1.36 -1.58 5.06 -1.58 2 N 0 ;0
L 5.06 -1.58 5.06 -0.655 2 N 0 ;0
L 5.06 -0.655 1.36 -0.655 2 N 0 ;0
A 1.559 -1.33655 1.559 -1.33655 1.55268002 -1.33655 1 N 0 N;0
A 1.54775 -1.205 1.54775 -1.205 1.53883002 -1.205 1 N 0 N;0
A 1.54763996 -0.99775 1.54763996 -0.99775 1.53871998 -0.99775 1 N 0 N;0
A 1.54063996 -1.10118002 1.54063996 -1.10118002 1.52603996 -1.10118002 1 N 0 N;0
A 1.49695 -1.10118002 1.49695 -1.10118002 1.48656998 -1.10118002 1 N 0 N;0
A 1.45963996 -1.10118002 1.45963996 -1.10118002 1.4533 -1.10118002 1 N 0 N;0
A 1.52135 -0.98681004 1.52135 -0.98681004 1.51503002 -0.98681004 1 N 0 N;0
A 1.79433002 -1.43586998 1.79433002 -1.43586998 1.78798996 -1.43586998 1 N 0 N;0
A 1.79841004 -1.40261004 1.79841004 -1.40261004 1.78798996 -1.40261004 1 N 0 N;0
A 1.80255 -1.36311004 1.80255 -1.36311004 1.78798996 -1.36311004 1 N 0 N;0
A 1.80668996 -1.31528002 1.80668996 -1.31528002 1.78798996 -1.31528002 1 N 0 N;0
A 1.68013002 -1.37456004 1.68013002 -1.37456004 1.67378996 -1.37456004 1 N 0 N;0
A 1.69321998 -1.35033002 1.69321998 -1.35033002 1.6843 -1.35033002 1 N 0 N;0
A 1.7108 -1.31738996 1.7108 -1.31738996 1.69798002 -1.31738996 1 N 0 N;0
A 1.89666998 -1.31511004 1.89666998 -1.31511004 1.88383996 -1.31511004 1 N 0 N;0
A 1.88198996 -1.16876004 1.88198996 -1.16876004 1.85558996 -1.16876004 1 N 0 N;0
A 1.87928002 -1.27801998 1.87928002 -1.27801998 1.86343996 -1.27801998 1 N 0 N;0
A 1.86176998 -1.23075 1.86176998 -1.23075 1.84206004 -1.23075 1 N 0 N;0
A 1.80978996 -1.25916998 1.80978996 -1.25916998 1.78798996 -1.25916998 1 N 0 N;0
A 1.74681004 -1.16876004 1.74681004 -1.16876004 1.72041004 -1.16876004 1 N 0 N;0
A 1.67813002 -1.15513002 1.67813002 -1.15513002 1.65841998 -1.15513002 1 N 0 N;0
A 1.73018002 -1.27816004 1.73018002 -1.27816004 1.71433996 -1.27816004 1 N 0 N;0
A 1.75373002 -1.23081004 1.75373002 -1.23081004 1.73405 -1.23081004 1 N 0 N;0
A 1.65531004 -1.25255 1.65531004 -1.25255 1.63661998 -1.25255 1 N 0 N;0
A 1.69808996 -1.21291998 1.69808996 -1.21291998 1.67628996 -1.21291998 1 N 0 N;0
A 1.81438996 -1.1968 1.81438996 -1.1968 1.78798996 -1.1968 1 N 0 N;0
A 1.6269 -1.1749 1.6269 -1.1749 1.61106004 -1.1749 1 N 0 N;0
A 1.58461004 -1.19126004 1.58461004 -1.19126004 1.57178002 -1.19126004 1 N 0 N;0
A 1.5853 -1.31428002 1.5853 -1.31428002 1.57488996 -1.31428002 1 N 0 N;0
A 1.61735 -1.28638996 1.61735 -1.28638996 1.60276998 -1.28638996 1 N 0 N;0
A 1.88198996 -1.03361004 1.88198996 -1.03361004 1.85558996 -1.03361004 1 N 0 N;0
A 1.71881004 -1.10118002 1.71881004 -1.10118002 1.69238996 -1.10118002 1 N 0 N;0
A 1.65183002 -1.10118002 1.65183002 -1.10118002 1.63003002 -1.10118002 1 N 0 N;0
A 1.67801998 -1.04738996 1.67801998 -1.04738996 1.65831004 -1.04738996 1 N 0 N;0
A 1.74681004 -1.03361004 1.74681004 -1.03361004 1.72041004 -1.03361004 1 N 0 N;0
A 1.69811998 -0.98951004 1.69811998 -0.98951004 1.67631998 -0.98951004 1 N 0 N;0
A 1.81438996 -1.00556004 1.81438996 -1.00556004 1.78798996 -1.00556004 1 N 0 N;0
A 1.59258002 -1.10118002 1.59258002 -1.10118002 1.5739 -1.10118002 1 N 0 N;0
A 1.58451004 -1.01148996 1.58451004 -1.01148996 1.57168002 -1.01148996 1 N 0 N;0
A 1.62681004 -1.02773996 1.62681004 -1.02773996 1.61096998 -1.02773996 1 N 0 N;0
A 1.92148002 -1.21285 1.92148002 -1.21285 1.89968002 -1.21285 1 N 0 N;0
A 1.92148002 -0.98951004 1.92148002 -0.98951004 1.89968002 -0.98951004 1 N 0 N;0
A 1.80978996 -0.9432 1.80978996 -0.9432 1.78798996 -0.9432 1 N 0 N;0
A 1.80668996 -0.88708002 1.80668996 -0.88708002 1.78798996 -0.88708002 1 N 0 N;0
A 1.80255 -0.83923996 1.80255 -0.83923996 1.78798996 -0.83923996 1 N 0 N;0
A 1.8919 -0.88538002 1.8919 -0.88538002 1.87906998 -0.88538002 1 N 0 N;0
A 1.87838996 -0.92456998 1.87838996 -0.92456998 1.86255 -0.92456998 1 N 0 N;0
A 1.65531004 -0.94981004 1.65531004 -0.94981004 1.63661998 -0.94981004 1 N 0 N;0
A 1.73123002 -0.92378002 1.73123002 -0.92378002 1.71538996 -0.92378002 1 N 0 N;0
A 1.71216998 -0.88443996 1.71216998 -0.88443996 1.69935 -0.88443996 1 N 0 N;0
A 1.86225 -0.97178002 1.86225 -0.97178002 1.84253996 -0.97178002 1 N 0 N;0
A 1.75451998 -0.97123996 1.75451998 -0.97123996 1.73483996 -0.97123996 1 N 0 N;0
A 1.61741998 -0.91601004 1.61741998 -0.91601004 1.60283996 -0.91601004 1 N 0 N;0
A 1.5853 -0.88808996 1.5853 -0.88808996 1.57488996 -0.88808996 1 N 0 N;0
A 1.79841004 -0.79975 1.79841004 -0.79975 1.78798996 -0.79975 1 N 0 N;0
A 1.79433002 -0.76648002 1.79433002 -0.76648002 1.78798996 -0.76648002 1 N 0 N;0
A 1.92135 -1.36781004 1.92135 -1.36781004 1.91503996 -1.36781004 1 N 0 N;0
A 1.91096004 -1.34658002 1.91096004 -1.34658002 1.90203996 -1.34658002 1 N 0 N;0
A 2.19078996 -1.1806 2.26591004 -1.16473002 2.21741014 -1.12088169 1 N 0 N;0
A 2.15903002 -1.1402 2.19078996 -1.18061004 2.22093406 -1.12423278 1 N 0 N;0
A 2.05721004 -1.16178996 2.08853002 -1.16658996 2.08281614 -1.09929134 1 N 0 N;0
A 2.00546998 -1.13951998 2.03345 -1.17196004 2.07793927 -1.10530069 1 N 0 N;0
A 2.03346004 -1.17195 2.0847 -1.18461004 2.07891181 -1.09801299 1 N 0 N;0
A 2.0847 -1.18461998 2.14261004 -1.15663002 2.07348435 -1.08751378 1 N 0 N;0
A 2.08853996 -1.16658002 2.13313002 -1.14451998 2.06368967 -1.06025512 1 N 0 N;0
A 1.95808002 -1.25255 1.95808002 -1.25255 1.93938996 -1.25255 1 N 0 N;0
A 1.98775 -1.28635 1.98775 -1.28635 1.97316998 -1.28635 1 N 0 N;0
A 2.27411998 -1.11835 2.15906004 -1.11835 2.21658996 -1.11611998 1 N 0 N;0
L 2.25188002 -1.11418002 2.1807 -1.11418002 1 N 0 ;0
L 2.1807 -1.11418002 2.1807 -1.11398996 1 N 8191 ;0
A 2.25188996 -1.11398996 2.18071004 -1.11398996 2.2163 -1.1124 1 N 0 N;0
A 2.08028996 -1.03428996 2.02048996 -1.08258996 2.0798126 -1.09486801 1 N 0 N;0
A 2.13151998 -1.05146004 2.0803 -1.0343 2.0802999 -1.11932195 1 N 0 N;0
A 2.1315 -1.05146998 2.14175 -1.03951004 2.1356003 -1.04461171 1 N 0 N;0
A 2.14175 -1.03951004 2.08283002 -1.01613002 2.07772461 -1.11492805 1 N 0 N;0
A 2.08283996 -1.01611998 2.00698002 -1.05835 2.08064724 -1.10143169 1 N 0 N;0
L 2.27413002 -1.12868996 2.18073996 -1.12868996 1 N 0 ;0
A 2.18075 -1.12868996 2.19083002 -1.15751998 2.22417795 -1.12968307 1 N 0 N;0
A 2.19083002 -1.15753002 2.25311004 -1.15211004 2.21927195 -1.12381791 1 N 0 N;0
L 2.15903996 -1.1402 2.15903996 -1.11835 1 N 8191 ;0
A 2.02048996 -1.0826 2.05721998 -1.16181004 2.09087933 -1.0980811 1 N 0 N;0
A 2.00698996 -1.05836004 2.00546998 -1.13953002 2.09672953 -1.10063967 1 N 0 N;0
A 2.14258996 -1.15661004 2.13313996 -1.14453002 2.13544892 -1.15246004 1 N 0 N;0
A 1.95808002 -0.94981004 1.95808002 -0.94981004 1.93938996 -0.94981004 1 N 0 N;0
A 1.90183996 -0.8525 1.90183996 -0.8525 1.89291004 -0.8525 1 N 0 N;0
A 1.91108002 -0.82726998 1.91108002 -0.82726998 1.90473996 -0.82726998 1 N 0 N;0
L 2.32081004 -1.02041004 2.32081004 -1.17625 1 N 0 ;0
A 2.49568002 -1.15528996 2.47898002 -1.16443002 2.4882003 -1.1614502 1 N 0 N;0
A 2.47896998 -1.16443996 2.50283002 -1.18086004 2.51649242 -1.13546152 1 N 0 N;0
A 2.50281998 -1.18086998 2.54318002 -1.1834 2.52887392 -1.08843022 1 N 0 N;0
A 2.52306998 -1.16761004 2.52848996 -1.16771998 2.52673258 -1.12070098 1 N 0 N;0
A 2.49566004 -1.15528996 2.52306998 -1.1676 2.5255122 -1.12549094 1 N 0 N;0
A 2.37851998 -1.15753002 2.4408 -1.15211004 2.40696191 -1.12381791 1 N 0 N;0
A 2.45358002 -1.16471998 2.44078996 -1.1521 2.44541191 -1.16020689 1 N 0 N;0
A 2.37848002 -1.1806 2.4536 -1.16473002 2.4051001 -1.12088169 1 N 0 N;0
A 2.34673002 -1.1402 2.37848996 -1.18061004 2.40863406 -1.12423278 1 N 0 N;0
A 2.2659 -1.16471998 2.25311004 -1.1521 2.25773199 -1.16020689 1 N 0 N;0
A 2.3006 -1.17626004 2.3208 -1.17626004 2.3107 -1.17386841 1 N 0 N;0
L 2.30058996 -1.17625 2.30058996 -1.02033996 1 N 0 ;0
A 2.50836998 -1.10106004 2.54306004 -1.11513002 2.56106673 -1.02093386 1 N 0 N;0
A 2.51081004 -1.07948002 2.50836998 -1.10103996 2.51886093 -1.09130915 1 N 0 N;0
A 2.53611004 -1.07688996 2.5108 -1.07948996 2.52742205 -1.11680827 1 N 0 N;0
A 2.56883996 -1.07368002 2.50178002 -1.06358996 2.5273123 -1.12178858 1 N 0 N;0
A 2.50178996 -1.06358996 2.48536998 -1.08248996 2.52926211 -1.10403986 1 N 0 N;0
L 2.48536998 -1.0825 2.48536998 -1.09748002 1 N 8191 ;0
A 2.48536998 -1.09748002 2.49956004 -1.12031004 2.51189104 -1.09682067 1 N 0 N;0
A 2.46181004 -1.11835 2.34675 -1.11835 2.40428002 -1.11611998 1 N 0 N;0
L 2.43956998 -1.11418002 2.36841004 -1.11418002 1 N 0 ;0
L 2.36841004 -1.11418002 2.36841004 -1.11398996 1 N 8191 ;0
A 2.43958002 -1.11398996 2.3684 -1.11398996 2.40398996 -1.1124 1 N 0 N;0
L 2.43956998 -1.11398996 2.43956998 -1.11418002 1 N 8191 ;0
A 2.49955 -1.1203 2.52723002 -1.12985 2.58163209 -0.92727982 1 N 0 N;0
A 2.55001998 -1.14328002 2.52723002 -1.12986004 2.51462185 -1.17733228 1 N 0 N;0
L 2.46181004 -1.12868996 2.36843996 -1.12868996 1 N 0 ;0
A 2.36843996 -1.12868996 2.37851998 -1.15751998 2.41186801 -1.12968307 1 N 0 N;0
L 2.34675 -1.1402 2.34675 -1.11835 1 N 8191 ;0
L 2.46181004 -1.11835 2.46181004 -1.12868996 1 N 8191 ;0
L 2.25188002 -1.11398996 2.25188002 -1.11418002 1 N 8191 ;0
A 2.3208 -1.02041004 2.3006 -1.02033996 2.31069163 -1.02276978 1 N 0 N;0
L 2.27413002 -1.11835 2.27413002 -1.12868996 1 N 8191 ;0
A 2.52848996 -1.16771004 2.54891998 -1.15895 2.52774557 -1.13777087 1 N 0 N;0
A 2.55608002 -1.08618002 2.53611998 -1.07688996 2.5249185 -1.12704419 1 N 0 N;0
L 2.71926004 -1.06796998 2.71926004 -1.17483996 1 N 0 ;0
A 2.78888996 -1.16296998 2.81508002 -1.16676998 2.8083499 -1.12100167 1 N 0 N;0
A 2.8151 -1.16675 2.83966004 -1.15211998 2.80521398 -1.12222392 1 N 0 N;0
A 2.85201004 -1.16508002 2.83966004 -1.15211004 2.84505768 -1.15933514 1 N 0 N;0
L 2.85201004 -1.16508002 2.84523996 -1.17161004 1 N 8191 ;0
A 2.81425 -1.1835 2.84525 -1.17161004 2.81425 -1.13714291 1 N 0 N;0
L 2.81425 -1.1835 2.79571004 -1.1835 1 N 8191 ;0
A 2.75886998 -1.16443002 2.79571998 -1.18351998 2.80278976 -1.12476142 1 N 0 N;0
A 2.74528996 -1.13568002 2.75888002 -1.16443002 2.80246565 -1.12624016 1 N 0 N;0
A 2.54316998 -1.1834 2.56906004 -1.1647 2.5305814 -1.13869892 1 N 0 N;0
A 2.56906004 -1.1647 2.57053996 -1.13728002 2.53763041 -1.14925374 1 N 0 N;0
A 2.65463996 -1.18351998 2.66863996 -1.17373996 2.65440246 -1.16826969 1 N 0 N;0
L 2.65463002 -1.1835 2.64165 -1.1835 1 N 8191 ;0
A 2.60955 -1.16043002 2.64163996 -1.18351004 2.63911063 -1.15317815 1 N 0 N;0
A 2.62978002 -1.15461998 2.66001998 -1.16328996 2.6502374 -1.14033868 1 N 0 N;0
A 2.66863996 -1.17375 2.66001998 -1.16328996 2.66100344 -1.17126132 1 N 0 N;0
A 2.6962 -1.17483996 2.71926004 -1.17483996 2.70773002 -1.17286427 1 N 0 N;0
L 2.69618996 -1.17483996 2.69618996 -1.06796998 1 N 0 ;0
A 2.83833002 -1.09275 2.82661998 -1.08201998 2.74555758 -1.18224094 1 N 0 N;0
A 2.82661998 -1.08198996 2.80036998 -1.07538996 2.80348839 -1.11848878 1 N 0 N;0
A 2.80036004 -1.07541998 2.76848996 -1.09933002 2.80700217 -1.1174685 1 N 0 N;0
A 2.76848996 -1.09931998 2.76446004 -1.12066004 2.82315728 -1.120694 1 N 0 N;0
A 2.74998002 -1.09273996 2.74528996 -1.11838996 2.8498563 -1.12425591 1 N 0 N;0
A 2.7954 -1.05776998 2.74998996 -1.09273996 2.80799961 -1.12109961 1 N 0 N;0
L 2.79541004 -1.05776998 2.80918996 -1.05776998 1 N 8191 ;0
A 2.85401998 -1.08106004 2.80918996 -1.05776998 2.80626024 -1.1181998 1 N 0 N;0
A 2.83833002 -1.09273996 2.85403002 -1.08106004 2.84418386 -1.08421683 1 N 0 N;0
L 2.76445 -1.12066004 2.76445 -1.12943002 1 N 8191 ;0
A 2.76446004 -1.12943002 2.76836998 -1.14305 2.80607844 -1.12485364 1 N 0 N;0
A 2.76836998 -1.14305 2.78891004 -1.16296998 2.80906152 -1.12164144 1 N 0 N;0
L 2.74528996 -1.13566004 2.74528996 -1.11838996 1 N 8191 ;0
A 2.55606004 -1.0862 2.56885 -1.07366998 2.56205354 -1.0795252 1 N 0 N;0
L 2.60953996 -1.07953996 2.59981998 -1.07953996 1 N 8191 ;0
A 2.5993 -1.05931998 2.59981004 -1.07955 2.6022813 -1.06936624 1 N 0 N;0
L 2.5993 -1.05931998 2.60953996 -1.05931998 1 N 8191 ;0
L 2.60953996 -1.05931998 2.60953996 -1.03491998 1 N 8191 ;0
A 2.62971998 -1.03418002 2.60953996 -1.03491004 2.61966791 -1.03559478 1 N 0 N;0
L 2.62971004 -1.03418996 2.62978002 -1.05931998 1 N 8191 ;0
L 2.62978002 -1.05931998 2.66008002 -1.05931998 1 N 8191 ;0
A 2.66003996 -1.07955 2.66008002 -1.05931998 2.65827421 -1.0694314 1 N 0 N;0
L 2.66003002 -1.07953996 2.62978002 -1.07953996 1 N 8191 ;0
A 2.71926004 -1.06796998 2.6962 -1.06796998 2.70773002 -1.0720561 1 N 0 N;0
A 2.71968996 -1.02341998 2.71968996 -1.02341998 2.70775 -1.02341998 1 N 0 N;0
A 2.57053996 -1.13728996 2.54306998 -1.11513002 2.53584449 -1.15219301 1 N 0 N;0
A 2.54891998 -1.15895 2.55001004 -1.14328002 2.54127923 -1.15054557 1 N 0 N;0
L 2.60953996 -1.16041004 2.60953996 -1.07953996 1 N 0 ;0
L 2.62978002 -1.07953996 2.62978002 -1.15463002 1 N 0 ;0
L 2.98495 -1.09393996 2.98495 -1.17625 1 N 0 ;0
A 2.96473996 -1.17626998 2.98493996 -1.17626998 2.97483996 -1.17442303 1 N 0 N;0
L 2.96473002 -1.17625 2.96473002 -1.17226004 1 N 8191 ;0
A 2.94165 -1.1835 2.96471004 -1.17226004 2.93076516 -1.1318935 1 N 0 N;0
L 2.94165 -1.1835 2.90701004 -1.1835 1 N 8191 ;0
A 2.90671004 -1.10841998 2.90703002 -1.18351004 2.9153065 -1.14592904 1 N 0 N;0
A 2.91853002 -1.12288996 2.91853002 -1.16618996 2.92048209 -1.14453996 1 N 0 N;0
L 2.91853002 -1.1662 2.94456004 -1.1662 1 N 8191 ;0
A 2.94456998 -1.16618996 2.94456998 -1.12288996 2.94406004 -1.14453996 1 N 0 N;0
A 2.96473002 -1.09686004 2.94741998 -1.07955 2.94874833 -1.09553169 1 N 0 N;0
L 2.9474 -1.07953996 2.90986998 -1.07953996 1 N 8191 ;0
A 2.90986998 -1.07953996 2.89821004 -1.0852 2.92433445 -1.12417766 1 N 0 N;0
A 2.89111998 -1.07086004 2.8982 -1.0852 2.8969689 -1.07688996 1 N 0 N;0
A 2.91561998 -1.05931998 2.89111998 -1.07085 2.92146033 -1.103525 1 N 0 N;0
L 2.91563002 -1.05931998 2.95031004 -1.05931998 1 N 8191 ;0
A 2.98496004 -1.09393996 2.95031004 -1.05933002 2.9453438 -1.09895197 1 N 0 N;0
A 2.92878996 -1.10535 2.9067 -1.10841998 2.93158484 -1.20646998 1 N 0 N;0
A 2.96471998 -1.10841004 2.92878002 -1.10536004 2.93215738 -1.27883829 1 N 0 N;0
L 2.96473002 -1.10841004 2.96473002 -1.09686004 1 N 8191 ;0
L 2.94456004 -1.12288002 2.91853002 -1.12288002 1 N 8191 ;0
L 3.04731004 -1.06001004 3.04191998 -1.07631998 1 N 8191 ;0
L 3.04191998 -1.07631998 3.03648002 -1.06001004 1 N 8191 ;0
L 3.03648002 -1.06001004 3.03243002 -1.06001004 1 N 8191 ;0
L 3.03243002 -1.06001004 3.02698002 -1.08543996 1 N 8191 ;0
L 3.02698002 -1.08543996 3.03226004 -1.08543996 1 N 8191 ;0
L 3.03226004 -1.08543996 3.03501004 -1.06886998 1 N 8191 ;0
L 3.03501004 -1.06886998 3.04086004 -1.08543996 1 N 8191 ;0
L 3.04086004 -1.08543996 3.04308996 -1.08543996 1 N 8191 ;0
L 3.04308996 -1.08543996 3.04888996 -1.06871004 1 N 8191 ;0
L 3.04888996 -1.06871004 3.05171004 -1.08543996 1 N 8191 ;0
L 3.05171004 -1.08543996 3.05713002 -1.08543996 1 N 8191 ;0
L 3.05713002 -1.08543996 3.05163996 -1.06001004 1 N 8191 ;0
L 3.05163996 -1.06001004 3.04731004 -1.06001004 1 N 8191 ;0
L 3.01066998 -1.06508002 3.00223002 -1.06508002 1 N 8191 ;0
L 3.00223002 -1.06508002 3.00223002 -1.06001004 1 N 8191 ;0
L 3.00223002 -1.06001004 3.02461004 -1.06001004 1 N 8191 ;0
L 3.02461004 -1.06001004 3.02461004 -1.06508002 1 N 8191 ;0
L 3.02461004 -1.06508002 3.01615 -1.06508002 1 N 8191 ;0
L 3.01615 -1.06508002 3.01615 -1.08533996 1 N 8191 ;0
L 3.01615 -1.08533996 3.01066998 -1.08533996 1 N 8191 ;0
L 3.01066998 -1.08533996 3.01066998 -1.06508002 1 N 8191 ;0
L 3.36933297 -0.955 3.36933297 -0.88 0 N 0 ;0
L 3.36933297 -0.88 3.39173337 -0.88 0 N 0 ;0
L 3.39173337 -0.88 3.3992001 -0.88375157 0 N 0 ;0
L 3.3992001 -0.88375157 3.40480059 -0.8924997 0 N 0 ;0
L 3.40480059 -0.8924997 3.40666693 -0.9024998 0 N 0 ;0
L 3.40666693 -0.9024998 3.40480059 -0.9125 0 N 0 ;0
L 3.40480059 -0.9125 3.40013327 -0.92000069 0 N 0 ;0
L 3.40013327 -0.92000069 3.39173337 -0.92375217 0 N 0 ;0
L 3.39173337 -0.92375217 3.36933297 -0.92375217 0 N 0 ;0
L 3.44619931 -0.95749941 3.47980059 -0.88 0 N 0 ;0
L 3.51653356 -0.955 3.51653356 -0.88 0 N 0 ;0
L 3.51653356 -0.88 3.55946634 -0.955 0 N 0 ;0
L 3.55946634 -0.955 3.55946634 -0.88 0 N 0 ;0
L 3.68799911 -0.95749941 3.68613287 -0.9562497 0 N 0 ;0
L 3.68613287 -0.9562497 3.68613287 -0.9537503 0 N 0 ;0
L 3.68613287 -0.9537503 3.68799911 -0.95250059 0 N 0 ;0
L 3.68799911 -0.95250059 3.68986703 -0.9537503 0 N 0 ;0
L 3.68986703 -0.9537503 3.68986703 -0.9562497 0 N 0 ;0
L 3.68986703 -0.9562497 3.68799911 -0.95749941 0 N 0 ;0
L 3.68799911 -0.92375217 3.68613287 -0.9225001 0 N 0 ;0
L 3.68613287 -0.9225001 3.68613287 -0.92000069 0 N 0 ;0
L 3.68613287 -0.92000069 3.68799911 -0.91875089 0 N 0 ;0
L 3.68799911 -0.91875089 3.68986703 -0.92000069 0 N 0 ;0
L 3.68986703 -0.92000069 3.68986703 -0.9225001 0 N 0 ;0
L 3.68986703 -0.9225001 3.68799911 -0.92375217 0 N 0 ;0
L 3.81933297 -0.955 3.81933297 -0.88 0 N 0 ;0
L 3.81933297 -0.88 3.84266644 -0.88 0 N 0 ;0
L 3.84266644 -0.88 3.85013327 -0.88375157 0 N 0 ;0
L 3.85013327 -0.88375157 3.85480059 -0.88875049 0 N 0 ;0
L 3.85480059 -0.88875049 3.85666693 -0.89875059 0 N 0 ;0
L 3.85666693 -0.89875059 3.85480059 -0.90875079 0 N 0 ;0
L 3.85480059 -0.90875079 3.8492001 -0.91499941 0 N 0 ;0
L 3.8492001 -0.91499941 3.84266644 -0.91875089 0 N 0 ;0
L 3.84266644 -0.91875089 3.81933297 -0.91875089 0 N 0 ;0
L 3.84266644 -0.91875089 3.85666693 -0.955 0 N 0 ;0
L 3.9242001 -0.955 3.9242001 -0.88 0 N 0 ;0
L 3.9242001 -0.88 3.88966565 -0.93375 0 N 0 ;0
L 3.88966565 -0.93375 3.93633425 -0.93375 0 N 0 ;0
L 3.98799911 -0.88 3.98053228 -0.88249951 0 N 0 ;0
L 3.98053228 -0.88249951 3.97493346 -0.88875049 0 N 0 ;0
L 3.97493346 -0.88875049 3.97119931 -0.89624882 0 N 0 ;0
L 3.97119931 -0.89624882 3.9683999 -0.90625128 0 N 0 ;0
L 3.9683999 -0.90625128 3.96746673 -0.91750118 0 N 0 ;0
L 3.96746673 -0.91750118 3.9683999 -0.92875108 0 N 0 ;0
L 3.9683999 -0.92875108 3.97119931 -0.93875128 0 N 0 ;0
L 3.97119931 -0.93875128 3.97493346 -0.94625187 0 N 0 ;0
L 3.97493346 -0.94625187 3.98053228 -0.95250059 0 N 0 ;0
L 3.98053228 -0.95250059 3.98799911 -0.955 0 N 0 ;0
L 3.98799911 -0.955 3.99546585 -0.95250059 0 N 0 ;0
L 3.99546585 -0.95250059 4.00106644 -0.94625187 0 N 0 ;0
L 4.00106644 -0.94625187 4.00480059 -0.93875128 0 N 0 ;0
L 4.00480059 -0.93875128 4.0076 -0.92875108 0 N 0 ;0
L 4.0076 -0.92875108 4.00853317 -0.91750118 0 N 0 ;0
L 4.00853317 -0.91750118 4.0076 -0.90625128 0 N 0 ;0
L 4.0076 -0.90625128 4.00480059 -0.89624882 0 N 0 ;0
L 4.00480059 -0.89624882 4.00106644 -0.88875049 0 N 0 ;0
L 4.00106644 -0.88875049 3.99546585 -0.88249951 0 N 0 ;0
L 3.99546585 -0.88249951 3.98799911 -0.88 0 N 0 ;0
L 4.06299911 -0.88 4.05553228 -0.88249951 0 N 0 ;0
L 4.05553228 -0.88249951 4.04993346 -0.88875049 0 N 0 ;0
L 4.04993346 -0.88875049 4.04619931 -0.89624882 0 N 0 ;0
L 4.04619931 -0.89624882 4.0433999 -0.90625128 0 N 0 ;0
L 4.0433999 -0.90625128 4.04246673 -0.91750118 0 N 0 ;0
L 4.04246673 -0.91750118 4.0433999 -0.92875108 0 N 0 ;0
L 4.0433999 -0.92875108 4.04619931 -0.93875128 0 N 0 ;0
L 4.04619931 -0.93875128 4.04993346 -0.94625187 0 N 0 ;0
L 4.04993346 -0.94625187 4.05553228 -0.95250059 0 N 0 ;0
L 4.05553228 -0.95250059 4.06299911 -0.955 0 N 0 ;0
L 4.06299911 -0.955 4.07046585 -0.95250059 0 N 0 ;0
L 4.07046585 -0.95250059 4.07606644 -0.94625187 0 N 0 ;0
L 4.07606644 -0.94625187 4.07980059 -0.93875128 0 N 0 ;0
L 4.07980059 -0.93875128 4.0826 -0.92875108 0 N 0 ;0
L 4.0826 -0.92875108 4.08353317 -0.91750118 0 N 0 ;0
L 4.08353317 -0.91750118 4.0826 -0.90625128 0 N 0 ;0
L 4.0826 -0.90625128 4.07980059 -0.89624882 0 N 0 ;0
L 4.07980059 -0.89624882 4.07606644 -0.88875049 0 N 0 ;0
L 4.07606644 -0.88875049 4.07046585 -0.88249951 0 N 0 ;0
L 4.07046585 -0.88249951 4.06299911 -0.88 0 N 0 ;0
L 4.12026614 -0.92375217 4.1267998 -0.91499941 0 N 0 ;0
L 4.1267998 -0.91499941 4.1324003 -0.91000049 0 N 0 ;0
L 4.1324003 -0.91000049 4.13986703 -0.90750108 0 N 0 ;0
L 4.13986703 -0.90750108 4.14640069 -0.91000049 0 N 0 ;0
L 4.14640069 -0.91000049 4.15106644 -0.91499941 0 N 0 ;0
L 4.15106644 -0.91499941 4.15480059 -0.9225001 0 N 0 ;0
L 4.15480059 -0.9225001 4.15573376 -0.93125059 0 N 0 ;0
L 4.15573376 -0.93125059 4.15480059 -0.93875128 0 N 0 ;0
L 4.15480059 -0.93875128 4.15106644 -0.94625187 0 N 0 ;0
L 4.15106644 -0.94625187 4.14546585 -0.95250059 0 N 0 ;0
L 4.14546585 -0.95250059 4.13893396 -0.955 0 N 0 ;0
L 4.13893396 -0.955 4.13146713 -0.95250059 0 N 0 ;0
L 4.13146713 -0.95250059 4.12493346 -0.94500217 0 N 0 ;0
L 4.12493346 -0.94500217 4.12119931 -0.93375 0 N 0 ;0
L 4.12119931 -0.93375 4.12026614 -0.92125039 0 N 0 ;0
L 4.12026614 -0.92125039 4.12213238 -0.90500157 0 N 0 ;0
L 4.12213238 -0.90500157 4.12493346 -0.89624882 0 N 0 ;0
L 4.12493346 -0.89624882 4.12959921 -0.88750069 0 N 0 ;0
L 4.12959921 -0.88750069 4.13613287 -0.8812498 0 N 0 ;0
L 4.13613287 -0.8812498 4.14266644 -0.88 0 N 0 ;0
L 4.14266644 -0.88 4.1492001 -0.88249951 0 N 0 ;0
L 4.1492001 -0.88249951 4.15386752 -0.88875049 0 N 0 ;0
L 4.20086663 -0.93000079 4.22513327 -0.93000079 0 N 0 ;0
L 4.29546585 -0.91499941 4.2992001 -0.9112502 0 N 0 ;0
L 4.2992001 -0.9112502 4.30199951 -0.90500157 0 N 0 ;0
L 4.30199951 -0.90500157 4.30386752 -0.89624882 0 N 0 ;0
L 4.30386752 -0.89624882 4.30199951 -0.88875049 0 N 0 ;0
L 4.30199951 -0.88875049 4.29826703 -0.88375157 0 N 0 ;0
L 4.29826703 -0.88375157 4.29173337 -0.88 0 N 0 ;0
L 4.29173337 -0.88 4.26653356 -0.88 0 N 0 ;0
L 4.26653356 -0.88 4.26653356 -0.955 0 N 0 ;0
L 4.26653356 -0.955 4.29733386 -0.955 0 N 0 ;0
L 4.29733386 -0.955 4.30386752 -0.95000108 0 N 0 ;0
L 4.30386752 -0.95000108 4.3076 -0.94250039 0 N 0 ;0
L 4.3076 -0.94250039 4.30946634 -0.93375 0 N 0 ;0
L 4.30946634 -0.93375 4.3076 -0.92500187 0 N 0 ;0
L 4.3076 -0.92500187 4.30199951 -0.91750118 0 N 0 ;0
L 4.30199951 -0.91750118 4.29546585 -0.91499941 0 N 0 ;0
L 4.29546585 -0.91499941 4.26653356 -0.91499941 0 N 0 ;0
L 4.36299911 -0.88 4.35553228 -0.88249951 0 N 0 ;0
L 4.35553228 -0.88249951 4.34993346 -0.88875049 0 N 0 ;0
L 4.34993346 -0.88875049 4.34619931 -0.89624882 0 N 0 ;0
L 4.34619931 -0.89624882 4.3433999 -0.90625128 0 N 0 ;0
L 4.3433999 -0.90625128 4.34246673 -0.91750118 0 N 0 ;0
L 4.34246673 -0.91750118 4.3433999 -0.92875108 0 N 0 ;0
L 4.3433999 -0.92875108 4.34619931 -0.93875128 0 N 0 ;0
L 4.34619931 -0.93875128 4.34993346 -0.94625187 0 N 0 ;0
L 4.34993346 -0.94625187 4.35553228 -0.95250059 0 N 0 ;0
L 4.35553228 -0.95250059 4.36299911 -0.955 0 N 0 ;0
L 4.36299911 -0.955 4.37046585 -0.95250059 0 N 0 ;0
L 4.37046585 -0.95250059 4.37606644 -0.94625187 0 N 0 ;0
L 4.37606644 -0.94625187 4.37980059 -0.93875128 0 N 0 ;0
L 4.37980059 -0.93875128 4.3826 -0.92875108 0 N 0 ;0
L 4.3826 -0.92875108 4.38353317 -0.91750118 0 N 0 ;0
L 4.38353317 -0.91750118 4.3826 -0.90625128 0 N 0 ;0
L 4.3826 -0.90625128 4.37980059 -0.89624882 0 N 0 ;0
L 4.37980059 -0.89624882 4.37606644 -0.88875049 0 N 0 ;0
L 4.37606644 -0.88875049 4.37046585 -0.88249951 0 N 0 ;0
L 4.37046585 -0.88249951 4.36299911 -0.88 0 N 0 ;0
L 4.43799911 -0.88 4.43053228 -0.88249951 0 N 0 ;0
L 4.43053228 -0.88249951 4.42493346 -0.88875049 0 N 0 ;0
L 4.42493346 -0.88875049 4.42119931 -0.89624882 0 N 0 ;0
L 4.42119931 -0.89624882 4.4183999 -0.90625128 0 N 0 ;0
L 4.4183999 -0.90625128 4.41746673 -0.91750118 0 N 0 ;0
L 4.41746673 -0.91750118 4.4183999 -0.92875108 0 N 0 ;0
L 4.4183999 -0.92875108 4.42119931 -0.93875128 0 N 0 ;0
L 4.42119931 -0.93875128 4.42493346 -0.94625187 0 N 0 ;0
L 4.42493346 -0.94625187 4.43053228 -0.95250059 0 N 0 ;0
L 4.43053228 -0.95250059 4.43799911 -0.955 0 N 0 ;0
L 4.43799911 -0.955 4.44546585 -0.95250059 0 N 0 ;0
L 4.44546585 -0.95250059 4.45106644 -0.94625187 0 N 0 ;0
L 4.45106644 -0.94625187 4.45480059 -0.93875128 0 N 0 ;0
L 4.45480059 -0.93875128 4.4576 -0.92875108 0 N 0 ;0
L 4.4576 -0.92875108 4.45853317 -0.91750118 0 N 0 ;0
L 4.45853317 -0.91750118 4.4576 -0.90625128 0 N 0 ;0
L 4.4576 -0.90625128 4.45480059 -0.89624882 0 N 0 ;0
L 4.45480059 -0.89624882 4.45106644 -0.88875049 0 N 0 ;0
L 4.45106644 -0.88875049 4.44546585 -0.88249951 0 N 0 ;0
L 4.44546585 -0.88249951 4.43799911 -0.88 0 N 0 ;0
L 4.51299911 -0.88 4.50553228 -0.88249951 0 N 0 ;0
L 4.50553228 -0.88249951 4.49993346 -0.88875049 0 N 0 ;0
L 4.49993346 -0.88875049 4.49619931 -0.89624882 0 N 0 ;0
L 4.49619931 -0.89624882 4.4933999 -0.90625128 0 N 0 ;0
L 4.4933999 -0.90625128 4.49246673 -0.91750118 0 N 0 ;0
L 4.49246673 -0.91750118 4.4933999 -0.92875108 0 N 0 ;0
L 4.4933999 -0.92875108 4.49619931 -0.93875128 0 N 0 ;0
L 4.49619931 -0.93875128 4.49993346 -0.94625187 0 N 0 ;0
L 4.49993346 -0.94625187 4.50553228 -0.95250059 0 N 0 ;0
L 4.50553228 -0.95250059 4.51299911 -0.955 0 N 0 ;0
L 4.51299911 -0.955 4.52046585 -0.95250059 0 N 0 ;0
L 4.52046585 -0.95250059 4.52606644 -0.94625187 0 N 0 ;0
L 4.52606644 -0.94625187 4.52980059 -0.93875128 0 N 0 ;0
L 4.52980059 -0.93875128 4.5326 -0.92875108 0 N 0 ;0
L 4.5326 -0.92875108 4.53353317 -0.91750118 0 N 0 ;0
L 4.53353317 -0.91750118 4.5326 -0.90625128 0 N 0 ;0
L 4.5326 -0.90625128 4.52980059 -0.89624882 0 N 0 ;0
L 4.52980059 -0.89624882 4.52606644 -0.88875049 0 N 0 ;0
L 4.52606644 -0.88875049 4.52046585 -0.88249951 0 N 0 ;0
L 4.52046585 -0.88249951 4.51299911 -0.88 0 N 0 ;0
L 4.58799911 -0.955 4.58799911 -0.88 0 N 0 ;0
L 4.58799911 -0.88 4.5767998 -0.89499911 0 N 0 ;0
L 4.5767998 -0.955 4.59919843 -0.955 0 N 0 ;0
L 4.65086663 -0.93000079 4.67513327 -0.93000079 0 N 0 ;0
L 4.73799911 -0.88 4.73053228 -0.88249951 0 N 0 ;0
L 4.73053228 -0.88249951 4.72493346 -0.88875049 0 N 0 ;0
L 4.72493346 -0.88875049 4.72119931 -0.89624882 0 N 0 ;0
L 4.72119931 -0.89624882 4.7183999 -0.90625128 0 N 0 ;0
L 4.7183999 -0.90625128 4.71746673 -0.91750118 0 N 0 ;0
L 4.71746673 -0.91750118 4.7183999 -0.92875108 0 N 0 ;0
L 4.7183999 -0.92875108 4.72119931 -0.93875128 0 N 0 ;0
L 4.72119931 -0.93875128 4.72493346 -0.94625187 0 N 0 ;0
L 4.72493346 -0.94625187 4.73053228 -0.95250059 0 N 0 ;0
L 4.73053228 -0.95250059 4.73799911 -0.955 0 N 0 ;0
L 4.73799911 -0.955 4.74546585 -0.95250059 0 N 0 ;0
L 4.74546585 -0.95250059 4.75106644 -0.94625187 0 N 0 ;0
L 4.75106644 -0.94625187 4.75480059 -0.93875128 0 N 0 ;0
L 4.75480059 -0.93875128 4.7576 -0.92875108 0 N 0 ;0
L 4.7576 -0.92875108 4.75853317 -0.91750118 0 N 0 ;0
L 4.75853317 -0.91750118 4.7576 -0.90625128 0 N 0 ;0
L 4.7576 -0.90625128 4.75480059 -0.89624882 0 N 0 ;0
L 4.75480059 -0.89624882 4.75106644 -0.88875049 0 N 0 ;0
L 4.75106644 -0.88875049 4.74546585 -0.88249951 0 N 0 ;0
L 4.74546585 -0.88249951 4.73799911 -0.88 0 N 0 ;0
L 4.79526614 -0.8924997 4.80086663 -0.88500128 0 N 0 ;0
L 4.80086663 -0.88500128 4.8074003 -0.8812498 0 N 0 ;0
L 4.8074003 -0.8812498 4.81486703 -0.88 0 N 0 ;0
L 4.81486703 -0.88 4.8242001 -0.88249951 0 N 0 ;0
L 4.8242001 -0.88249951 4.83073376 -0.88875049 0 N 0 ;0
L 4.83073376 -0.88875049 4.8326 -0.89624882 0 N 0 ;0
L 4.8326 -0.89624882 4.83166693 -0.90375187 0 N 0 ;0
L 4.83166693 -0.90375187 4.82793268 -0.91000049 0 N 0 ;0
L 4.82793268 -0.91000049 4.80926654 -0.9225001 0 N 0 ;0
L 4.80926654 -0.9225001 4.80086663 -0.93125059 0 N 0 ;0
L 4.80086663 -0.93125059 4.79526614 -0.94375246 0 N 0 ;0
L 4.79526614 -0.94375246 4.7933999 -0.955 0 N 0 ;0
L 4.7933999 -0.955 4.8326 -0.955 0 N 0 ;0
L 3.36746673 -1.205 3.36746673 -1.13 0 N 0 ;0
L 3.36746673 -1.13 3.38613287 -1.13 0 N 0 ;0
L 3.38613287 -1.13 3.39359961 -1.13375157 0 N 0 ;0
L 3.39359961 -1.13375157 3.3992001 -1.13875049 0 N 0 ;0
L 3.3992001 -1.13875049 3.40386752 -1.14624882 0 N 0 ;0
L 3.40386752 -1.14624882 3.4076 -1.15500157 0 N 0 ;0
L 3.4076 -1.15500157 3.40853317 -1.16750118 0 N 0 ;0
L 3.40853317 -1.16750118 3.4076 -1.18000079 0 N 0 ;0
L 3.4076 -1.18000079 3.40386752 -1.18875128 0 N 0 ;0
L 3.40386752 -1.18875128 3.3992001 -1.19625187 0 N 0 ;0
L 3.3992001 -1.19625187 3.39359961 -1.20125089 0 N 0 ;0
L 3.39359961 -1.20125089 3.38613287 -1.205 0 N 0 ;0
L 3.38613287 -1.205 3.36746673 -1.205 0 N 0 ;0
L 3.47980059 -1.205 3.47980059 -1.15500157 0 N 0 ;0
L 3.47980059 -1.1637497 3.47606644 -1.15875079 0 N 0 ;0
L 3.47606644 -1.15875079 3.47046585 -1.15625128 0 N 0 ;0
L 3.47046585 -1.15625128 3.46393396 -1.15500157 0 N 0 ;0
L 3.46393396 -1.15500157 3.4574003 -1.15750108 0 N 0 ;0
L 3.4574003 -1.15750108 3.4517998 -1.1625 0 N 0 ;0
L 3.4517998 -1.1625 3.44806555 -1.17000069 0 N 0 ;0
L 3.44806555 -1.17000069 3.44619931 -1.18000079 0 N 0 ;0
L 3.44619931 -1.18000079 3.44806555 -1.19000098 0 N 0 ;0
L 3.44806555 -1.19000098 3.4517998 -1.19750167 0 N 0 ;0
L 3.4517998 -1.19750167 3.4574003 -1.20250059 0 N 0 ;0
L 3.4574003 -1.20250059 3.46393396 -1.205 0 N 0 ;0
L 3.46393396 -1.205 3.47046585 -1.2037503 0 N 0 ;0
L 3.47046585 -1.2037503 3.47606644 -1.20000108 0 N 0 ;0
L 3.47606644 -1.20000108 3.47980059 -1.19500217 0 N 0 ;0
L 3.53799911 -1.13 3.53799911 -1.205 0 N 0 ;0
L 3.52493346 -1.15500157 3.55106644 -1.15500157 0 N 0 ;0
L 3.59900039 -1.17125039 3.62886752 -1.17125039 0 N 0 ;0
L 3.62886752 -1.17125039 3.62606644 -1.1625 0 N 0 ;0
L 3.62606644 -1.1625 3.62140069 -1.15750108 0 N 0 ;0
L 3.62140069 -1.15750108 3.61486703 -1.15500157 0 N 0 ;0
L 3.61486703 -1.15500157 3.60833346 -1.15625128 0 N 0 ;0
L 3.60833346 -1.15625128 3.60273287 -1.16000049 0 N 0 ;0
L 3.60273287 -1.16000049 3.59900039 -1.16875089 0 N 0 ;0
L 3.59900039 -1.16875089 3.59713238 -1.17625157 0 N 0 ;0
L 3.59713238 -1.17625157 3.59713238 -1.18375 0 N 0 ;0
L 3.59713238 -1.18375 3.59900039 -1.19125069 0 N 0 ;0
L 3.59900039 -1.19125069 3.60366604 -1.19875138 0 N 0 ;0
L 3.60366604 -1.19875138 3.60926654 -1.2037503 0 N 0 ;0
L 3.60926654 -1.2037503 3.6158002 -1.205 0 N 0 ;0
L 3.6158002 -1.205 3.62233386 -1.20250059 0 N 0 ;0
L 3.62233386 -1.20250059 3.62886752 -1.19500217 0 N 0 ;0
L 3.68799911 -1.20749941 3.68613287 -1.2062497 0 N 0 ;0
L 3.68613287 -1.2062497 3.68613287 -1.2037503 0 N 0 ;0
L 3.68613287 -1.2037503 3.68799911 -1.20250059 0 N 0 ;0
L 3.68799911 -1.20250059 3.68986703 -1.2037503 0 N 0 ;0
L 3.68986703 -1.2037503 3.68986703 -1.2062497 0 N 0 ;0
L 3.68986703 -1.2062497 3.68799911 -1.20749941 0 N 0 ;0
L 3.68799911 -1.17375217 3.68613287 -1.1725001 0 N 0 ;0
L 3.68613287 -1.1725001 3.68613287 -1.17000069 0 N 0 ;0
L 3.68613287 -1.17000069 3.68799911 -1.16875089 0 N 0 ;0
L 3.68799911 -1.16875089 3.68986703 -1.17000069 0 N 0 ;0
L 3.68986703 -1.17000069 3.68986703 -1.1725001 0 N 0 ;0
L 3.68986703 -1.1725001 3.68799911 -1.17375217 0 N 0 ;0
L 3.82026614 -1.1424997 3.82586663 -1.13500128 0 N 0 ;0
L 3.82586663 -1.13500128 3.8324003 -1.1312498 0 N 0 ;0
L 3.8324003 -1.1312498 3.83986703 -1.13 0 N 0 ;0
L 3.83986703 -1.13 3.8492001 -1.13249951 0 N 0 ;0
L 3.8492001 -1.13249951 3.85573376 -1.13875049 0 N 0 ;0
L 3.85573376 -1.13875049 3.8576 -1.14624882 0 N 0 ;0
L 3.8576 -1.14624882 3.85666693 -1.15375187 0 N 0 ;0
L 3.85666693 -1.15375187 3.85293268 -1.16000049 0 N 0 ;0
L 3.85293268 -1.16000049 3.83426654 -1.1725001 0 N 0 ;0
L 3.83426654 -1.1725001 3.82586663 -1.18125059 0 N 0 ;0
L 3.82586663 -1.18125059 3.82026614 -1.19375246 0 N 0 ;0
L 3.82026614 -1.19375246 3.8183999 -1.205 0 N 0 ;0
L 3.8183999 -1.205 3.8576 -1.205 0 N 0 ;0
L 3.91299911 -1.13 3.90553228 -1.13249951 0 N 0 ;0
L 3.90553228 -1.13249951 3.89993346 -1.13875049 0 N 0 ;0
L 3.89993346 -1.13875049 3.89619931 -1.14624882 0 N 0 ;0
L 3.89619931 -1.14624882 3.8933999 -1.15625128 0 N 0 ;0
L 3.8933999 -1.15625128 3.89246673 -1.16750118 0 N 0 ;0
L 3.89246673 -1.16750118 3.8933999 -1.17875108 0 N 0 ;0
L 3.8933999 -1.17875108 3.89619931 -1.18875128 0 N 0 ;0
L 3.89619931 -1.18875128 3.89993346 -1.19625187 0 N 0 ;0
L 3.89993346 -1.19625187 3.90553228 -1.20250059 0 N 0 ;0
L 3.90553228 -1.20250059 3.91299911 -1.205 0 N 0 ;0
L 3.91299911 -1.205 3.92046585 -1.20250059 0 N 0 ;0
L 3.92046585 -1.20250059 3.92606644 -1.19625187 0 N 0 ;0
L 3.92606644 -1.19625187 3.92980059 -1.18875128 0 N 0 ;0
L 3.92980059 -1.18875128 3.9326 -1.17875108 0 N 0 ;0
L 3.9326 -1.17875108 3.93353317 -1.16750118 0 N 0 ;0
L 3.93353317 -1.16750118 3.9326 -1.15625128 0 N 0 ;0
L 3.9326 -1.15625128 3.92980059 -1.14624882 0 N 0 ;0
L 3.92980059 -1.14624882 3.92606644 -1.13875049 0 N 0 ;0
L 3.92606644 -1.13875049 3.92046585 -1.13249951 0 N 0 ;0
L 3.92046585 -1.13249951 3.91299911 -1.13 0 N 0 ;0
L 3.97026614 -1.1424997 3.97586663 -1.13500128 0 N 0 ;0
L 3.97586663 -1.13500128 3.9824003 -1.1312498 0 N 0 ;0
L 3.9824003 -1.1312498 3.98986703 -1.13 0 N 0 ;0
L 3.98986703 -1.13 3.9992001 -1.13249951 0 N 0 ;0
L 3.9992001 -1.13249951 4.00573376 -1.13875049 0 N 0 ;0
L 4.00573376 -1.13875049 4.0076 -1.14624882 0 N 0 ;0
L 4.0076 -1.14624882 4.00666693 -1.15375187 0 N 0 ;0
L 4.00666693 -1.15375187 4.00293268 -1.16000049 0 N 0 ;0
L 4.00293268 -1.16000049 3.98426654 -1.1725001 0 N 0 ;0
L 3.98426654 -1.1725001 3.97586663 -1.18125059 0 N 0 ;0
L 3.97586663 -1.18125059 3.97026614 -1.19375246 0 N 0 ;0
L 3.97026614 -1.19375246 3.9683999 -1.205 0 N 0 ;0
L 3.9683999 -1.205 4.0076 -1.205 0 N 0 ;0
L 4.04526614 -1.1424997 4.05086663 -1.13500128 0 N 0 ;0
L 4.05086663 -1.13500128 4.0574003 -1.1312498 0 N 0 ;0
L 4.0574003 -1.1312498 4.06486703 -1.13 0 N 0 ;0
L 4.06486703 -1.13 4.0742001 -1.13249951 0 N 0 ;0
L 4.0742001 -1.13249951 4.08073376 -1.13875049 0 N 0 ;0
L 4.08073376 -1.13875049 4.0826 -1.14624882 0 N 0 ;0
L 4.0826 -1.14624882 4.08166693 -1.15375187 0 N 0 ;0
L 4.08166693 -1.15375187 4.07793268 -1.16000049 0 N 0 ;0
L 4.07793268 -1.16000049 4.05926654 -1.1725001 0 N 0 ;0
L 4.05926654 -1.1725001 4.05086663 -1.18125059 0 N 0 ;0
L 4.05086663 -1.18125059 4.04526614 -1.19375246 0 N 0 ;0
L 4.04526614 -1.19375246 4.0433999 -1.205 0 N 0 ;0
L 4.0433999 -1.205 4.0826 -1.205 0 N 0 ;0
L 4.12586663 -1.18000079 4.15013327 -1.18000079 0 N 0 ;0
L 4.21299911 -1.13 4.20553228 -1.13249951 0 N 0 ;0
L 4.20553228 -1.13249951 4.19993346 -1.13875049 0 N 0 ;0
L 4.19993346 -1.13875049 4.19619931 -1.14624882 0 N 0 ;0
L 4.19619931 -1.14624882 4.1933999 -1.15625128 0 N 0 ;0
L 4.1933999 -1.15625128 4.19246673 -1.16750118 0 N 0 ;0
L 4.19246673 -1.16750118 4.1933999 -1.17875108 0 N 0 ;0
L 4.1933999 -1.17875108 4.19619931 -1.18875128 0 N 0 ;0
L 4.19619931 -1.18875128 4.19993346 -1.19625187 0 N 0 ;0
L 4.19993346 -1.19625187 4.20553228 -1.20250059 0 N 0 ;0
L 4.20553228 -1.20250059 4.21299911 -1.205 0 N 0 ;0
L 4.21299911 -1.205 4.22046585 -1.20250059 0 N 0 ;0
L 4.22046585 -1.20250059 4.22606644 -1.19625187 0 N 0 ;0
L 4.22606644 -1.19625187 4.22980059 -1.18875128 0 N 0 ;0
L 4.22980059 -1.18875128 4.2326 -1.17875108 0 N 0 ;0
L 4.2326 -1.17875108 4.23353317 -1.16750118 0 N 0 ;0
L 4.23353317 -1.16750118 4.2326 -1.15625128 0 N 0 ;0
L 4.2326 -1.15625128 4.22980059 -1.14624882 0 N 0 ;0
L 4.22980059 -1.14624882 4.22606644 -1.13875049 0 N 0 ;0
L 4.22606644 -1.13875049 4.22046585 -1.13249951 0 N 0 ;0
L 4.22046585 -1.13249951 4.21299911 -1.13 0 N 0 ;0
L 4.27026614 -1.1424997 4.27586663 -1.13500128 0 N 0 ;0
L 4.27586663 -1.13500128 4.2824003 -1.1312498 0 N 0 ;0
L 4.2824003 -1.1312498 4.28986703 -1.13 0 N 0 ;0
L 4.28986703 -1.13 4.2992001 -1.13249951 0 N 0 ;0
L 4.2992001 -1.13249951 4.30573376 -1.13875049 0 N 0 ;0
L 4.30573376 -1.13875049 4.3076 -1.14624882 0 N 0 ;0
L 4.3076 -1.14624882 4.30666693 -1.15375187 0 N 0 ;0
L 4.30666693 -1.15375187 4.30293268 -1.16000049 0 N 0 ;0
L 4.30293268 -1.16000049 4.28426654 -1.1725001 0 N 0 ;0
L 4.28426654 -1.1725001 4.27586663 -1.18125059 0 N 0 ;0
L 4.27586663 -1.18125059 4.27026614 -1.19375246 0 N 0 ;0
L 4.27026614 -1.19375246 4.2683999 -1.205 0 N 0 ;0
L 4.2683999 -1.205 4.3076 -1.205 0 N 0 ;0
L 4.35086663 -1.18000079 4.37513327 -1.18000079 0 N 0 ;0
L 4.42026614 -1.1424997 4.42586663 -1.13500128 0 N 0 ;0
L 4.42586663 -1.13500128 4.4324003 -1.1312498 0 N 0 ;0
L 4.4324003 -1.1312498 4.43986703 -1.13 0 N 0 ;0
L 4.43986703 -1.13 4.4492001 -1.13249951 0 N 0 ;0
L 4.4492001 -1.13249951 4.45573376 -1.13875049 0 N 0 ;0
L 4.45573376 -1.13875049 4.4576 -1.14624882 0 N 0 ;0
L 4.4576 -1.14624882 4.45666693 -1.15375187 0 N 0 ;0
L 4.45666693 -1.15375187 4.45293268 -1.16000049 0 N 0 ;0
L 4.45293268 -1.16000049 4.43426654 -1.1725001 0 N 0 ;0
L 4.43426654 -1.1725001 4.42586663 -1.18125059 0 N 0 ;0
L 4.42586663 -1.18125059 4.42026614 -1.19375246 0 N 0 ;0
L 4.42026614 -1.19375246 4.4183999 -1.205 0 N 0 ;0
L 4.4183999 -1.205 4.4576 -1.205 0 N 0 ;0
L 4.49246673 -1.19375246 4.49806555 -1.20000108 0 N 0 ;0
L 4.49806555 -1.20000108 4.50459921 -1.2037503 0 N 0 ;0
L 4.50459921 -1.2037503 4.51299911 -1.205 0 N 0 ;0
L 4.51299911 -1.205 4.52140069 -1.20250059 0 N 0 ;0
L 4.52140069 -1.20250059 4.52793268 -1.19750167 0 N 0 ;0
L 4.52793268 -1.19750167 4.5326 -1.18875128 0 N 0 ;0
L 4.5326 -1.18875128 4.53353317 -1.17875108 0 N 0 ;0
L 4.53353317 -1.17875108 4.53166693 -1.16875089 0 N 0 ;0
L 4.53166693 -1.16875089 4.52699951 -1.1625 0 N 0 ;0
L 4.52699951 -1.1625 4.52046585 -1.15750108 0 N 0 ;0
L 4.52046585 -1.15750108 4.51393396 -1.15625128 0 N 0 ;0
L 4.51393396 -1.15625128 4.5074003 -1.15750108 0 N 0 ;0
L 4.5074003 -1.15750108 4.49900039 -1.1625 0 N 0 ;0
L 4.49900039 -1.1625 4.5017998 -1.13 0 N 0 ;0
L 4.5017998 -1.13 4.52699951 -1.13 0 N 0 ;0
L 3.29433297 -1.255 3.29433297 -1.33 0 N 0 ;0
L 3.29433297 -1.33 3.33166693 -1.33 0 N 0 ;0
L 3.40480059 -1.33 3.40480059 -1.28000157 0 N 0 ;0
L 3.40480059 -1.2887497 3.40106644 -1.28375079 0 N 0 ;0
L 3.40106644 -1.28375079 3.39546585 -1.28125128 0 N 0 ;0
L 3.39546585 -1.28125128 3.38893396 -1.28000157 0 N 0 ;0
L 3.38893396 -1.28000157 3.3824003 -1.28250108 0 N 0 ;0
L 3.3824003 -1.28250108 3.3767998 -1.2875 0 N 0 ;0
L 3.3767998 -1.2875 3.37306555 -1.29500069 0 N 0 ;0
L 3.37306555 -1.29500069 3.37119931 -1.30500079 0 N 0 ;0
L 3.37119931 -1.30500079 3.37306555 -1.31500098 0 N 0 ;0
L 3.37306555 -1.31500098 3.3767998 -1.32250167 0 N 0 ;0
L 3.3767998 -1.32250167 3.3824003 -1.32750059 0 N 0 ;0
L 3.3824003 -1.32750059 3.38893396 -1.33 0 N 0 ;0
L 3.38893396 -1.33 3.39546585 -1.3287503 0 N 0 ;0
L 3.39546585 -1.3287503 3.40106644 -1.32500108 0 N 0 ;0
L 3.40106644 -1.32500108 3.40480059 -1.32000217 0 N 0 ;0
L 3.4433999 -1.3524997 3.44900039 -1.35499921 0 N 0 ;0
L 3.44900039 -1.35499921 3.45646713 -1.3524997 0 N 0 ;0
L 3.45646713 -1.3524997 3.46113287 -1.34750079 0 N 0 ;0
L 3.46113287 -1.34750079 3.46486703 -1.3412498 0 N 0 ;0
L 3.46486703 -1.3412498 3.47046585 -1.32125187 0 N 0 ;0
L 3.47046585 -1.32125187 3.4826 -1.28000157 0 N 0 ;0
L 3.45273287 -1.28000157 3.47046585 -1.32125187 0 N 0 ;0
L 3.52400039 -1.29625039 3.55386752 -1.29625039 0 N 0 ;0
L 3.55386752 -1.29625039 3.55106644 -1.2875 0 N 0 ;0
L 3.55106644 -1.2875 3.54640069 -1.28250108 0 N 0 ;0
L 3.54640069 -1.28250108 3.53986703 -1.28000157 0 N 0 ;0
L 3.53986703 -1.28000157 3.53333346 -1.28125128 0 N 0 ;0
L 3.53333346 -1.28125128 3.52773287 -1.28500049 0 N 0 ;0
L 3.52773287 -1.28500049 3.52400039 -1.29375089 0 N 0 ;0
L 3.52400039 -1.29375089 3.52213238 -1.30125157 0 N 0 ;0
L 3.52213238 -1.30125157 3.52213238 -1.30875 0 N 0 ;0
L 3.52213238 -1.30875 3.52400039 -1.31625069 0 N 0 ;0
L 3.52400039 -1.31625069 3.52866604 -1.32375138 0 N 0 ;0
L 3.52866604 -1.32375138 3.53426654 -1.3287503 0 N 0 ;0
L 3.53426654 -1.3287503 3.5408002 -1.33 0 N 0 ;0
L 3.5408002 -1.33 3.54733386 -1.32750059 0 N 0 ;0
L 3.54733386 -1.32750059 3.55386752 -1.32000217 0 N 0 ;0
L 3.59993346 -1.33 3.59993346 -1.28000157 0 N 0 ;0
L 3.59993346 -1.28999941 3.60459921 -1.28500049 0 N 0 ;0
L 3.60459921 -1.28500049 3.60926654 -1.28125128 0 N 0 ;0
L 3.60926654 -1.28125128 3.6158002 -1.28000157 0 N 0 ;0
L 3.6158002 -1.28000157 3.62046585 -1.28125128 0 N 0 ;0
L 3.62046585 -1.28125128 3.62606644 -1.28500049 0 N 0 ;0
L 3.68799911 -1.33249941 3.68613287 -1.3312497 0 N 0 ;0
L 3.68613287 -1.3312497 3.68613287 -1.3287503 0 N 0 ;0
L 3.68613287 -1.3287503 3.68799911 -1.32750059 0 N 0 ;0
L 3.68799911 -1.32750059 3.68986703 -1.3287503 0 N 0 ;0
L 3.68986703 -1.3287503 3.68986703 -1.3312497 0 N 0 ;0
L 3.68986703 -1.3312497 3.68799911 -1.33249941 0 N 0 ;0
L 3.68799911 -1.29875217 3.68613287 -1.2975001 0 N 0 ;0
L 3.68613287 -1.2975001 3.68613287 -1.29500069 0 N 0 ;0
L 3.68613287 -1.29500069 3.68799911 -1.29375089 0 N 0 ;0
L 3.68799911 -1.29375089 3.68986703 -1.29500069 0 N 0 ;0
L 3.68986703 -1.29500069 3.68986703 -1.2975001 0 N 0 ;0
L 3.68986703 -1.2975001 3.68799911 -1.29875217 0 N 0 ;0
L 3.36933297 -1.08 3.36933297 -1.005 0 N 0 ;0
L 3.36933297 -1.005 3.39266644 -1.005 0 N 0 ;0
L 3.39266644 -1.005 3.40013327 -1.00875157 0 N 0 ;0
L 3.40013327 -1.00875157 3.40480059 -1.01375049 0 N 0 ;0
L 3.40480059 -1.01375049 3.40666693 -1.02375059 0 N 0 ;0
L 3.40666693 -1.02375059 3.40480059 -1.03375079 0 N 0 ;0
L 3.40480059 -1.03375079 3.3992001 -1.03999941 0 N 0 ;0
L 3.3992001 -1.03999941 3.39266644 -1.04375089 0 N 0 ;0
L 3.39266644 -1.04375089 3.36933297 -1.04375089 0 N 0 ;0
L 3.39266644 -1.04375089 3.40666693 -1.08 0 N 0 ;0
L 3.44900039 -1.04625039 3.47886752 -1.04625039 0 N 0 ;0
L 3.47886752 -1.04625039 3.47606644 -1.0375 0 N 0 ;0
L 3.47606644 -1.0375 3.47140069 -1.03250108 0 N 0 ;0
L 3.47140069 -1.03250108 3.46486703 -1.03000157 0 N 0 ;0
L 3.46486703 -1.03000157 3.45833346 -1.03125128 0 N 0 ;0
L 3.45833346 -1.03125128 3.45273287 -1.03500049 0 N 0 ;0
L 3.45273287 -1.03500049 3.44900039 -1.04375089 0 N 0 ;0
L 3.44900039 -1.04375089 3.44713238 -1.05125157 0 N 0 ;0
L 3.44713238 -1.05125157 3.44713238 -1.05875 0 N 0 ;0
L 3.44713238 -1.05875 3.44900039 -1.06625069 0 N 0 ;0
L 3.44900039 -1.06625069 3.45366604 -1.07375138 0 N 0 ;0
L 3.45366604 -1.07375138 3.45926654 -1.0787503 0 N 0 ;0
L 3.45926654 -1.0787503 3.4658002 -1.08 0 N 0 ;0
L 3.4658002 -1.08 3.47233386 -1.07750059 0 N 0 ;0
L 3.47233386 -1.07750059 3.47886752 -1.07000217 0 N 0 ;0
L 3.52119931 -1.03000157 3.53799911 -1.08 0 N 0 ;0
L 3.53799911 -1.08 3.55480059 -1.03000157 0 N 0 ;0
L 3.68799911 -1.08249941 3.68613287 -1.0812497 0 N 0 ;0
L 3.68613287 -1.0812497 3.68613287 -1.0787503 0 N 0 ;0
L 3.68613287 -1.0787503 3.68799911 -1.07750059 0 N 0 ;0
L 3.68799911 -1.07750059 3.68986703 -1.0787503 0 N 0 ;0
L 3.68986703 -1.0787503 3.68986703 -1.0812497 0 N 0 ;0
L 3.68986703 -1.0812497 3.68799911 -1.08249941 0 N 0 ;0
L 3.68799911 -1.04875217 3.68613287 -1.0475001 0 N 0 ;0
L 3.68613287 -1.0475001 3.68613287 -1.04500069 0 N 0 ;0
L 3.68613287 -1.04500069 3.68799911 -1.04375089 0 N 0 ;0
L 3.68799911 -1.04375089 3.68986703 -1.04500069 0 N 0 ;0
L 3.68986703 -1.04500069 3.68986703 -1.0475001 0 N 0 ;0
L 3.68986703 -1.0475001 3.68799911 -1.04875217 0 N 0 ;0
L 3.83799911 -1.005 3.83053228 -1.00749951 0 N 0 ;0
L 3.83053228 -1.00749951 3.82493346 -1.01375049 0 N 0 ;0
L 3.82493346 -1.01375049 3.82119931 -1.02124882 0 N 0 ;0
L 3.82119931 -1.02124882 3.8183999 -1.03125128 0 N 0 ;0
L 3.8183999 -1.03125128 3.81746673 -1.04250118 0 N 0 ;0
L 3.81746673 -1.04250118 3.8183999 -1.05375108 0 N 0 ;0
L 3.8183999 -1.05375108 3.82119931 -1.06375128 0 N 0 ;0
L 3.82119931 -1.06375128 3.82493346 -1.07125187 0 N 0 ;0
L 3.82493346 -1.07125187 3.83053228 -1.07750059 0 N 0 ;0
L 3.83053228 -1.07750059 3.83799911 -1.08 0 N 0 ;0
L 3.83799911 -1.08 3.84546585 -1.07750059 0 N 0 ;0
L 3.84546585 -1.07750059 3.85106644 -1.07125187 0 N 0 ;0
L 3.85106644 -1.07125187 3.85480059 -1.06375128 0 N 0 ;0
L 3.85480059 -1.06375128 3.8576 -1.05375108 0 N 0 ;0
L 3.8576 -1.05375108 3.85853317 -1.04250118 0 N 0 ;0
L 3.85853317 -1.04250118 3.8576 -1.03125128 0 N 0 ;0
L 3.8576 -1.03125128 3.85480059 -1.02124882 0 N 0 ;0
L 3.85480059 -1.02124882 3.85106644 -1.01375049 0 N 0 ;0
L 3.85106644 -1.01375049 3.84546585 -1.00749951 0 N 0 ;0
L 3.84546585 -1.00749951 3.83799911 -1.005 0 N 0 ;0
L 3.91299911 -1.08 3.91299911 -1.005 0 N 0 ;0
L 3.91299911 -1.005 3.9017998 -1.01999911 0 N 0 ;0
L 3.9017998 -1.08 3.92419843 -1.08 0 N 0 ;0

### steps/pcb/layers/l06_vcc2/features
#
#Num Features
#
F 3181

#
#Units
#
U INCH

#
#Feature symbol names
#
$0 r5
$1 r6
$2 r10
$3 r26
$4 r28
$5 r30
$6 r32
$7 r33
$8 r39
$9 r56
$10 r82
$11 r86
$12 r99
$13 r102
$14 r125
$15 r143
$16 r150
$17 r189
$18 oval74x47 I
$19 oval86x47 I
$20 ths102x92.01x45x4x14 I

#
#Feature attribute names
#
@0 .nomenclature
@1 .geometry
@2 .sip

#
#Feature attribute text strings
#
&0 V010C020P_TP030B
&1 V008C018P-ANTI28-NSM
&2 V010C020P
&3 TPV010CT020B030
&4 V008C018P_ANTI026_TP030B
&5 V008C018P_NATI28_TP030B_NSMT
&6 016C024P
&7 V008C018P_TP030B
&8 V008C018P_ANTI28
&9 V008C018P
&10 059C086P
&11 V008C018P_ANTI026_NSM
&12 076S104P
&13 076C104P
&14 079C100P
&15 V010C020P_SM014-NTH
&16 V012C024-NTH
&17 024X063OB035X075P
&18 166CT244CB198P
&19 024X051OB071X075P_R
&20 024X051OB071X075P_L
&21 033C057P
&22 063C090P
&23 MTH100C090N
&24 MTH125C115N
&25 MTH118C108N

#
#Layer features
#
S P 0;0,2=1
OB -24.76435 -17.98935 I
OS -24.76435 16.38535
OS 21.05735 16.38535
OS 21.05735 -17.98935
OS -24.76435 -17.98935
OE
OB -0.00110019685 0.21653976378 H
OC 0.039369783465 0.176069783465 0.039369783465 0.21653976378 N
OS 0.551194094488 0.176069980315
OC 0.59165 0.216525885827 0.551180019685 0.21653996063 N
OS 0.59165019685 0.46260019685
OC 0.629906200787 0.500870177165 0.629920177165 0.46260019685 Y
OS 1.273619980315 0.500869980315
OC 1.31188996063 0.462613779528 1.273619980315 0.4626 Y
OS 1.31188976378 0.21653976378
OC 1.35235984252 0.176069783465 1.352359744094 0.21653976378 N
OS 1.588594094488 0.176069980315
OC 1.62905 0.216525885827 1.588580019685 0.21653996063 N
OS 1.62905019685 0.430120177165
OC 1.77055019685 0.430134055118 1.69980019685 0.430120177165 Y
OS 1.770550098425 0.019702952756
OC 1.770872244094 0.018912204724 1.77165 0.019690059055 N
OS 1.790547933071 -0.000763484252
OC 1.791339862205 -0.001100098425 1.79133996063 -0.000000098425 N
OS 2.192896850394 -0.001100098425
OC 2.193511712598 -0.000920767717 2.192909645669 -0.00000019685 N
OC 2.193677066929 -0.000788484252 2.192910728346 -0.000000098425 N
OS 2.213388188976 0.018922637795
OC 2.213699901575 0.019689862205 2.212599901575 0.019689862205 N
OS 2.2137 0.29331003937
OC 2.2863 0.29331003937 2.25 0.29331003937 Y
OS 2.286300098425 0.019690059055
OC 2.286636712598 0.018898129921 2.287400098425 0.01969015748 N
OS 2.306298129921 -0.000763287402
OC 2.307090059055 -0.001099901575 2.30709015748 0.000000098425 N
OS 3.102347047244 -0.001099901575
OC 3.102961909449 -0.000920570866 3.10235984252 0 N
OC 3.10312726378 -0.000788287402 3.102360925197 0.000000098425 N
OS 3.122837893701 0.01892234252
OC 3.122970570866 0.019087992126 3.122049901575 0.019689468504 N
OC 3.123149901575 0.019702952756 3.12205 0.019690059055 N
OS 3.12314980315 0.462613779528
OC 3.161419783465 0.500869783465 3.161419783465 0.46259980315 Y
OS 6.561034055118 0.500869980315
OC 6.60148996063 0.541325885827 6.561019980315 0.54133996063 N
OS 6.60149015748 2.374999901575
OC 6.580710531496 2.39579015748 6.580705216535 2.375005216535 N
OS 6.572096555118 2.39578996063
OC 6.553530019685 2.414369980315 6.57211003937 2.414369980315 Y
OS 6.553529822835 2.826783759843
OC 6.572110137795 2.84535984252 6.57211476378 2.826774901575 Y
OS 6.572111122047 2.84535984252
OS 6.580724409449 2.84536003937
OC 6.60148996063 2.866125590551 6.58071003937 2.86613996063 N
OS 6.60149015748 4.33661023622
OC 6.561020177165 4.377080216535 6.561020177165 4.33661023622 N
OS 0.039355905512 4.377080019685
OC -0.0011 4.336624114173 0.039369980315 4.33661003937 N
OS -0.00110019685 0.21653976378
OE
SE
S P 0
OB -0.00110019685 0.21653976378 I
OS -0.0011 4.336624114173
OC 0.039355905512 4.377080019685 0.039369980315 4.33661003937 Y
OS 6.561020177165 4.377080216535
OC 6.60149015748 4.33661023622 6.561020177165 4.33661023622 Y
OS 6.60148996063 2.866125590551
OC 6.580724409449 2.84536003937 6.58071003937 2.86613996063 Y
OS 6.580725 2.84536003937
OS 6.580710629921 2.845359940945
OS 6.572123917323 2.845359940945
OS 6.572111122047 2.84535984252
OS 6.572110137795 2.84535984252
OC 6.553529822835 2.826783759843 6.57211476378 2.826774901575 N
OS 6.553530019685 2.414369980315
OC 6.572096555118 2.39578996063 6.57211003937 2.414369980315 N
OS 6.580710531496 2.39579015748
OC 6.60149015748 2.374999901575 6.580705216535 2.375005216535 Y
OS 6.60148996063 0.541325885827
OC 6.561034055118 0.500869980315 6.561019980315 0.54133996063 Y
OS 6.561034744094 0.500869980315
OS 6.561020570866 0.50086988189
OS 3.161433858268 0.50086988189
OS 3.161419783465 0.500869783465
OC 3.12314980315 0.462613779528 3.161419783465 0.46259980315 N
OS 3.123149901575 0.019702952756
OC 3.122970570866 0.019087992126 3.12205 0.019690059055 Y
OC 3.122837893701 0.01892234252 3.122049901575 0.019689468504 Y
OS 3.10312726378 -0.000788287402
OC 3.102961909449 -0.000920570866 3.102360925197 0.000000098425 Y
OC 3.102347047244 -0.001099901575 3.10235984252 0 Y
OS 2.307090059055 -0.001099901575
OC 2.306298129921 -0.000763287402 2.30709015748 0.000000098425 Y
OS 2.286636712598 0.018898129921
OC 2.286300098425 0.019690059055 2.287400098425 0.01969015748 Y
OS 2.2863 0.29331003937
OC 2.2137 0.29331003937 2.25 0.29331003937 N
OS 2.213699901575 0.019689862205
OC 2.213388188976 0.018922637795 2.212599901575 0.019689862205 Y
OS 2.193677066929 -0.000788484252
OC 2.193511712598 -0.000920767717 2.192910728346 -0.000000098425 Y
OC 2.192896850394 -0.001100098425 2.192909645669 -0.00000019685 Y
OS 1.791339862205 -0.001100098425
OC 1.790547933071 -0.000763484252 1.79133996063 -0.000000098425 Y
OS 1.770872244094 0.018912204724
OC 1.770550098425 0.019702952756 1.77165 0.019690059055 Y
OS 1.77055019685 0.430134055118
OC 1.62905019685 0.430120177165 1.69980019685 0.430120177165 N
OS 1.62905 0.216525885827
OC 1.588594094488 0.176069980315 1.588580019685 0.21653996063 Y
OS 1.588594783465 0.176069980315
OS 1.588580610236 0.17606988189
OS 1.352373917323 0.17606988189
OS 1.35235984252 0.176069783465
OC 1.31188976378 0.21653976378 1.352359744094 0.21653976378 Y
OS 1.31188996063 0.462613779528
OC 1.273619980315 0.500869980315 1.273619980315 0.4626 N
OS 0.629906200787 0.500870177165
OC 0.59165019685 0.46260019685 0.629920177165 0.46260019685 N
OS 0.59165 0.216525885827
OC 0.551194094488 0.176069980315 0.551180019685 0.21653996063 Y
OS 0.551194783465 0.176069980315
OS 0.551180610236 0.17606988189
OS 0.039383858268 0.17606988189
OS 0.039369783465 0.176069783465
OC -0.00110019685 0.21653976378 0.039369783465 0.21653976378 Y
OE
OB 3.725 1.775 H
OS 3.7845 1.775
OS 3.785 1.77625
OC 3.811 1.77625 3.798 1.770999901575 Y
OS 3.8115 1.775
OS 3.955 1.775
OC 3.962069980315 1.772069980315 3.954999901575 1.76500511811 Y
OS 3.982069980315 1.752069980315
OC 3.985 1.745 3.97500511811 1.744999901575 Y
OS 3.985 1.71866003937
OS 3.99003996063 1.71866003937
OC 3.99003996063 1.692619980315 3.99003996063 1.705640059055 Y
OS 3.985 1.692619980315
OS 3.985 1.655
OS 4.014030019685 1.655
OC 4.01763996063 1.66071003937 4.014025098425 1.658999212598 N
OC 4.0164 1.666269980315 4.029423129921 1.666256102362 Y
OC 4.029419980315 1.6793 4.029419980315 1.666280019685 Y
OS 4.06878996063 1.6793
OC 4.081819980315 1.666269980315 4.06878996063 1.666269980315 Y
OC 4.080569980315 1.66071003937 4.068791929134 1.666278543307 Y
OC 4.084180019685 1.655 4.084184940945 1.658999311024 N
OS 4.485 1.655
OS 4.485 1.71586003937
OS 4.462930019685 1.737930019685
OC 4.46 1.745 4.46999488189 1.745000098425 Y
OS 4.46 1.7715
OS 4.4586 1.77193996063
OC 4.4586 1.7968 4.462482086614 1.784369980315 Y
OS 4.46 1.79723996063
OS 4.46 1.810869980315
OS 4.4586 1.81131003937
OC 4.44946003937 1.82373996063 4.462482086614 1.82373996063 Y
OC 4.4531 1.83276003937 4.462476574803 1.823731791339 Y
OS 4.435780019685 1.850080019685
OS 4.42311003937 1.850080019685
OC 4.41008996063 1.86301003937 4.423109940945 1.863100295276 Y
OS 4.410069980315 1.865
OS 4.19 1.865
OC 4.182930019685 1.867930019685 4.190000098425 1.87499488189 Y
OS 3.932930019685 2.117930019685
OC 3.93 2.125 3.93999488189 2.125000098425 Y
OS 3.93 2.20668996063
OC 3.909980019685 2.235 3.940006397638 2.234999901575 Y
OC 3.92376003937 2.26025 3.940003641732 2.235 Y
OC 3.924419980315 2.26643996063 3.921593110236 2.263611220472 N
OS 3.89586003937 2.295
OS 3.83106003937 2.295
OC 3.83 2.294980019685 3.829964370079 2.324999311024 Y
OC 3.82893996063 2.295 3.830035629921 2.324999311024 Y
OS 3.741619980315 2.295
OC 3.730069980315 2.29041003937 3.724998326772 2.319999015748 Y
OS 3.72943996063 2.2903
OS 3.725 2.28586003937
OS 3.725 2.15973996063
OS 3.7266 2.15941003937
OC 3.7266 2.10058996063 3.720605216535 2.13 Y
OS 3.725 2.10026003937
OS 3.725 1.775
OE
OB 3.66 0.78413996063 H
OS 3.71913996063 0.725
OS 4.785980019685 0.725
OC 4.834019980315 0.725 4.81 0.707009940945 Y
OS 5.50586003937 0.725
OS 5.545 0.76413996063
OS 5.545 1.00586003937
OS 5.335880019685 1.214980019685
OS 5.33505 1.214980019685
OC 5.304980019685 1.24505 5.335 1.245 Y
OS 5.304980019685 1.245880019685
OS 5.14056003937 1.4103
OS 5.139930019685 1.41041003937
OC 5.11541003937 1.434930019685 5.145 1.44 Y
OS 5.1153 1.43556003937
OS 5.030880019685 1.519980019685
OS 5.03005 1.519980019685
OC 4.999980019685 1.55005 5.03 1.55 Y
OS 4.999980019685 1.550880019685
OS 4.94866003937 1.6022
OS 4.9483 1.60235
OC 4.93221003937 1.61865 4.960004429134 1.62999488189 Y
OS 4.91586003937 1.635
OS 4.856619980315 1.635
OC 4.823380019685 1.635 4.84 1.660002362205 Y
OS 4.00656003937 1.635
OC 4.002680019685 1.63003996063 4.006563090551 1.631 N
OC 4.00306003937 1.6269 3.990037893701 1.626916929134 Y
OC 3.99003996063 1.613880019685 3.990040059055 1.6269 Y
OS 3.985 1.613880019685
OS 3.985 1.561180019685
OS 3.99003996063 1.561180019685
OC 3.99003996063 1.53513996063 3.99003996063 1.54816003937 Y
OS 3.985 1.53513996063
OS 3.985 1.48243996063
OS 3.99003996063 1.48243996063
OC 3.99003996063 1.4564 3.99003996063 1.469419980315 Y
OS 3.985 1.4564
OS 3.985 1.42
OC 3.982069980315 1.412930019685 3.97500511811 1.420000098425 Y
OS 3.963269980315 1.394130019685
OS 3.96346003937 1.39308996063
OC 3.96368996063 1.390669980315 3.950671555118 1.390654035433 Y
OC 3.950669980315 1.37765 3.950669980315 1.390669980315 Y
OC 3.94825 1.377880019685 3.950686417323 1.390668405512 Y
OS 3.94721003937 1.378069980315
OS 3.937069980315 1.367930019685
OC 3.93 1.365 3.929999901575 1.37499488189 Y
OS 3.66 1.365
OS 3.66 0.934019980315
OS 3.671019980315 0.934019980315
OS 3.671019980315 0.905980019685
OS 3.66 0.905980019685
OS 3.66 0.78413996063
OE
OB 3.63 1.40913996063 H
OS 3.65413996063 1.385
OS 3.92586003937 1.385
OS 3.965 1.42413996063
OS 3.965 1.4564
OS 3.950669980315 1.4564
OC 3.950669980315 1.48243996063 3.950669980315 1.469419980315 Y
OS 3.965 1.48243996063
OS 3.965 1.53513996063
OS 3.950669980315 1.53513996063
OC 3.950669980315 1.561180019685 3.950669980315 1.54816003937 Y
OS 3.965 1.561180019685
OS 3.965 1.613880019685
OS 3.950669980315 1.613880019685
OC 3.950669980315 1.639919980315 3.950669980315 1.6269 Y
OS 3.965 1.639919980315
OS 3.965 1.692619980315
OS 3.950669980315 1.692619980315
OC 3.950669980315 1.71866003937 3.950669980315 1.705640059055 Y
OS 3.965 1.71866003937
OS 3.965 1.74086003937
OS 3.95086003937 1.755
OS 3.759119980315 1.755
OC 3.732880019685 1.755 3.746 1.781989074803 Y
OS 3.663930019685 1.755
OC 3.63595 1.735980019685 3.635998425197 1.765999311024 Y
OS 3.635119980315 1.735980019685
OS 3.63 1.73086003937
OS 3.63 1.561619980315
OC 3.63 1.528380019685 3.604997637795 1.545 Y
OS 3.63 1.40913996063
OE
OB 1.12 2.323280019685 H
OS 2.26413996063 1.17913996063
OC 2.27 1.165 2.250010334646 1.164999901575 Y
OS 2.27 0.40898996063
OC 2.3674 0.29331003937 2.250004625984 0.293309940945 Y
OS 2.3674 0.262
OS 3.04205 0.262
OS 3.04205 0.4626
OC 3.161419980315 0.581969980315 3.161419980315 0.4626 Y
OS 6.275469980315 0.581969980315
OC 6.27898996063 0.587869980315 6.275469783465 0.58597007874 N
OC 6.26236003937 0.65353996063 6.400386811024 0.65355246063 Y
OC 6.40038996063 0.79156003937 6.400390059055 0.653530019685 Y
OC 6.513119980315 0.733180019685 6.40038996063 0.653530905512 Y
OC 6.52038996063 0.735480019685 6.516389862205 0.735483956693 N
OS 6.52038996063 2.32916003937
OC 6.472430019685 2.414369980315 6.572105807087 2.414369980315 Y
OS 6.472430019685 2.82678996063
OC 6.52038996063 2.91198996063 6.57211496063 2.826774901575 Y
OS 6.52038996063 4.09641003937
OC 6.513119980315 4.09871003937 6.516389862205 4.096406102362 N
OC 6.40038996063 4.040319980315 6.400383956693 4.178346948819 Y
OC 6.26236003937 4.17835 6.40038996063 4.178349901575 Y
OC 6.31758996063 4.288780019685 6.400387007874 4.178344094488 Y
OC 6.31518996063 4.295980019685 6.31518996063 4.291980019685 N
OS 6.10486003937 4.295980019685
OS 6.08 4.271119980315
OS 6.08 3.918280019685
OS 6.14913996063 3.84913996063
OC 6.155 3.835 6.135010334646 3.834999901575 Y
OS 6.155 3.275
OC 6.14913996063 3.26086003937 6.135010334646 3.275000098425 Y
OS 6.06413996063 3.17586003937
OC 6.05 3.17 6.049999901575 3.189989665354 Y
OS 5.903280019685 3.17
OS 5.81 3.076719980315
OS 5.81 2.38745
OC 5.819019980315 2.366 5.789005413386 2.366 Y
OC 5.8027 2.33928996063 5.78900265748 2.365999901575 Y
OS 5.802419980315 2.33913996063
OS 5.72413996063 2.26086003937
OC 5.71 2.255 5.709999901575 2.274989665354 Y
OS 5.688030019685 2.255
OC 5.645969980315 2.255 5.667 2.275005610236 Y
OS 5.60973996063 2.255
OC 5.58026003937 2.255 5.595 2.280013287402 Y
OS 5.54631003937 2.255
OC 5.516130019685 2.255 5.53122007874 2.279800885827 Y
OS 5.49573996063 2.255
OC 5.467419980315 2.255 5.481580019685 2.280323818898 Y
OS 5.335 2.255
OC 5.32086003937 2.26086003937 5.335000098425 2.274989665354 Y
OS 5.28086003937 2.30086003937
OC 5.275 2.315 5.294989665354 2.315000098425 Y
OS 5.275 2.424980019685
OS 5.14141003937 2.424980019685
OC 5.12101003937 2.416980019685 5.121005314961 2.447002066929 Y
OS 5.12098996063 2.416980019685
OC 5.10058996063 2.424980019685 5.120994685039 2.447002066929 Y
OS 4.99141003937 2.424980019685
OC 4.97101003937 2.416980019685 4.971005314961 2.447002066929 Y
OS 4.97098996063 2.416980019685
OC 4.95058996063 2.424980019685 4.970994685039 2.447002066929 Y
OS 4.88085 2.424980019685
OS 4.844980019685 2.46085
OS 4.844980019685 2.80585
OS 4.61085 3.039980019685
OS 4.591 3.039980019685
OC 4.539 3.039980019685 4.565 3.055013287402 Y
OS 4.52661003937 3.039980019685
OS 4.526119980315 3.039669980315
OC 4.51001003937 3.034980019685 4.51000757874 3.065002165354 Y
OS 4.50998996063 3.034980019685
OC 4.4934 3.039980019685 4.509990059055 3.065002952756 Y
OS 4.36563996063 3.039980019685
OC 4.35143996063 3.03641003937 4.351440846457 3.066432677165 Y
OS 4.351419980315 3.03641003937
OC 4.337219980315 3.039980019685 4.351419094488 3.066432677165 Y
OS 4.16915 3.039980019685
OS 4.15321003937 3.02403996063
OC 4.160019980315 3.005 4.129998129921 3.005 Y
OC 4.13 2.974980019685 4.13 3.005 Y
OC 4.11096003937 2.98178996063 4.13 3.005001870079 Y
OS 4.085019980315 2.95585
OS 4.085019980315 2.47585
OS 4.063969980315 2.45481003937
OS 4.063830019685 2.454519980315
OC 4.05018996063 2.441030019685 4.037004527559 2.468003051181 Y
OS 3.92968996063 2.320530019685
OS 3.929580019685 2.3199
OC 3.92115 2.30368996063 3.899994389764 2.324988976378 Y
OC 3.92113996063 2.298030019685 3.923968011811 2.300855019685 N
OS 3.950019980315 2.26915
OS 3.950019980315 2.2633
OC 3.950019980315 2.2067 3.93999773622 2.235 Y
OS 3.950019980315 2.12915
OS 4.19415 1.885019980315
OS 4.42915 1.885019980315
OS 4.438030019685 1.87613996063
OS 4.462480019685 1.87613996063
OC 4.4755 1.86311003937 4.462469980315 1.863109940945 Y
OS 4.4755 1.86308996063
OC 4.469219980315 1.85196003937 4.462475590551 1.86310226378 Y
OC 4.46846003937 1.84571003937 4.471285433071 1.84853769685 N
OS 4.480019980315 1.83415
OS 4.480019980315 1.74915
OS 4.505019980315 1.72415
OS 4.505019980315 1.71835
OS 4.506330019685 1.717869980315
OC 4.506330019685 1.69341003937 4.501842814961 1.705640059055 Y
OS 4.505019980315 1.692930019685
OS 4.505019980315 1.678980019685
OS 4.506330019685 1.6785
OC 4.514869980315 1.666269980315 4.501842814961 1.66627007874 Y
OS 4.514869980315 1.66626003937
OC 4.513630019685 1.660719980315 4.501849015748 1.666265551181 Y
OC 4.51723996063 1.655019980315 4.517246653543 1.659017322835 N
OS 4.92415 1.655019980315
OS 5.565019980315 1.01415
OS 5.565019980315 0.75585
OS 5.51415 0.704980019685
OS 4.84 0.704980019685
OS 4.839780019685 0.703230019685
OC 4.780219980315 0.703230019685 4.81 0.706995964567 Y
OS 4.78 0.704980019685
OS 4.247330019685 0.704980019685
OC 4.23001003937 0.699480019685 4.230009448819 0.729502952756 Y
OS 4.22998996063 0.699480019685
OC 4.212669980315 0.704980019685 4.229990551181 0.729502952756 Y
OS 3.81601003937 0.704980019685
OC 3.77398996063 0.704980019685 3.795 0.725003346457 Y
OS 3.71085 0.704980019685
OS 3.639980019685 0.77585
OS 3.639980019685 0.905980019685
OS 3.610980019685 0.905980019685
OS 3.610980019685 0.934019980315
OS 3.639980019685 0.934019980315
OS 3.639980019685 1.37085
OS 3.609980019685 1.40085
OS 3.609980019685 1.73915
OS 3.64585 1.775019980315
OS 3.704980019685 1.775019980315
OS 3.704980019685 2.09638996063
OC 3.70035 2.10033996063 3.700979330709 2.096389074803 N
OC 3.69561003937 2.09996003937 3.6955875 2.129999409449 Y
OS 3.6956 2.09996003937
OC 3.68278996063 2.102830019685 3.695603543307 2.129999212598 Y
OC 3.67 2.099969980315 3.669999901575 2.129998622047 Y
OC 3.65753996063 2.102680019685 3.670006496063 2.129998622047 Y
OC 3.645 2.09993996063 3.64499980315 2.130005511811 Y
OC 3.61493996063 2.13 3.645 2.13 Y
OC 3.61541003937 2.135280019685 3.644997637795 2.129984940945 Y
OC 3.611469980315 2.139980019685 3.611472047244 2.135980216535 N
OS 3.54085 2.139980019685
OS 3.504980019685 2.17585
OS 3.504980019685 2.26496003937
OC 3.47496003937 2.295 3.505 2.295 Y
OC 3.48436003937 2.316830019685 3.505008366142 2.295 Y
OC 3.479980019685 2.332430019685 3.509997047244 2.332443011811 Y
OS 3.479980019685 2.33245
OC 3.486580019685 2.351219980315 3.510002952756 2.332438484252 Y
OC 3.479980019685 2.37 3.509998818898 2.37 Y
OC 3.503419980315 2.39928996063 3.51 2.37 Y
OS 3.504980019685 2.39963996063
OS 3.504980019685 2.52415
OS 3.589980019685 2.60915
OS 3.589980019685 2.88085
OS 3.230680019685 3.24016003937
OS 3.229319980315 3.239230019685
OC 3.222 3.236980019685 3.222 3.250012204724 Y
OC 3.208980019685 3.25 3.222 3.25 Y
OC 3.211230019685 3.257319980315 3.222012204724 3.25 Y
OS 3.21216003937 3.258680019685
OS 3.11085 3.359980019685
OS 2.20278996063 3.359980019685
OC 2.192019980315 3.357980019685 2.192015354331 3.388002854331 Y
OS 2.191980019685 3.357980019685
OC 2.18121003937 3.359980019685 2.191984645669 3.388002854331 Y
OS 1.75915 3.359980019685
OS 1.58321003937 3.18403996063
OC 1.590019980315 3.165 1.559998129921 3.165 Y
OC 1.56 3.134980019685 1.56 3.165 Y
OC 1.54231003937 3.14075 1.56000511811 3.164998326772 Y
OS 1.540919980315 3.14176003937
OS 1.522230019685 3.123069980315
OS 1.52273996063 3.121830019685
OC 1.525019980315 3.110369980315 1.494997244094 3.110353641732 Y
OS 1.525019980315 3.11033996063
OC 1.495 3.080319980315 1.495 3.11033996063 Y
OS 1.494969980315 3.080319980315
OC 1.483519980315 3.0826 1.494996062992 3.110341437008 Y
OS 1.482269980315 3.08311003937
OS 1.48165 3.082480019685
OS 1.39045 3.082480019685
OS 1.381619980315 3.07365
OS 1.381619980315 2.98245
OS 1.305019980315 2.90585
OS 1.305019980315 2.905
OC 1.275 2.874980019685 1.275 2.905 Y
OS 1.27415 2.874980019685
OS 1.120019980315 2.72085
OS 1.120019980315 2.37085
OS 1.12 2.370830019685
OS 1.12 2.323280019685
OE
OB 0.925 2.518280019685 H
OS 1.073280019685 2.37
OS 1.09086003937 2.37
OS 1.097930019685 2.377069980315
OC 1.1 2.37866003937 1.105004429134 2.370002755906 Y
OS 1.1 2.725
OC 1.102930019685 2.732069980315 1.10999488189 2.724999901575 Y
OS 1.28925 2.91838996063
OS 1.28938996063 2.91866003937
OC 1.3016 2.93073996063 1.314991732283 2.904993208661 Y
OS 1.3616 2.99073996063
OS 1.3616 3.0778
OC 1.364530019685 3.084869980315 1.37159488189 3.077799901575 Y
OS 1.379230019685 3.099569980315
OC 1.3863 3.1025 1.386300098425 3.09250511811 Y
OS 1.4612 3.1025
OC 1.465169980315 3.10695 1.461196456693 3.106499015748 N
OC 1.464980019685 3.1103 1.495000984252 3.110321948819 Y
OS 1.464980019685 3.11033996063
OC 1.495 3.14036003937 1.495 3.110340059055 Y
OC 1.50695 3.137880019685 1.494999901575 3.110329133858 Y
OS 1.5082 3.13733996063
OS 1.53045 3.15958996063
OS 1.53031003937 3.16058996063
OC 1.529980019685 3.165 1.559997834646 3.165028937008 Y
OC 1.56 3.195019980315 1.56 3.165 Y
OC 1.56441003937 3.19468996063 1.559971062992 3.165002165354 Y
OS 1.56541003937 3.19455
OS 1.747930019685 3.377069980315
OC 1.755 3.38 1.755000098425 3.37000511811 Y
OS 2.97596003937 3.38
OC 2.977 3.380019980315 2.977037401575 3.351000688976 Y
OC 2.97803996063 3.38 2.976962598425 3.351000688976 Y
OS 3.115 3.38
OC 3.122069980315 3.377069980315 3.114999901575 3.37000511811 Y
OS 3.607069980315 2.892069980315
OC 3.61 2.885 3.60000511811 2.884999901575 Y
OS 3.61 2.61606003937
OC 3.610019980315 2.615 3.580000688976 2.614964370079 Y
OC 3.61 2.61393996063 3.580000688976 2.615035629921 Y
OS 3.61 2.605
OC 3.607069980315 2.597930019685 3.60000511811 2.605000098425 Y
OS 3.525 2.51586003937
OS 3.525 2.396
OC 3.540019980315 2.37 3.510006692913 2.37 Y
OC 3.533419980315 2.351219980315 3.510001181102 2.37 Y
OC 3.540019980315 2.33245 3.509997047244 2.332438484252 Y
OS 3.540019980315 2.332430019685
OC 3.530630019685 2.310619980315 3.509996161417 2.33242992126 Y
OC 3.535019980315 2.295 3.50500265748 2.294990551181 Y
OC 3.525 2.27261003937 3.504994389764 2.295 Y
OS 3.525 2.18413996063
OS 3.54913996063 2.16
OS 3.64393996063 2.16
OC 3.645 2.160019980315 3.645035629921 2.130000688976 Y
OC 3.64606003937 2.16 3.644964370079 2.130000688976 Y
OS 3.66893996063 2.16
OC 3.67 2.160019980315 3.670035629921 2.130000688976 Y
OC 3.67106003937 2.16 3.669964370079 2.130000688976 Y
OS 3.69453996063 2.16
OC 3.6956 2.160019980315 3.695635629921 2.130000688976 Y
OC 3.69666003937 2.16 3.695564370079 2.130000688976 Y
OS 3.704980019685 2.16
OS 3.704980019685 2.29415
OS 3.72585 2.315019980315
OS 3.895880019685 2.315019980315
OS 4.065 2.48413996063
OS 4.065 2.79798996063
OC 4.065 2.82801003937 4.091012401575 2.813 Y
OS 4.065 2.852169980315
OC 4.062980019685 2.863 4.093000688976 2.862995964567 Y
OC 4.065 2.873830019685 4.093000688976 2.863004035433 Y
OS 4.065 2.903880019685
OC 4.065 2.930119980315 4.091989074803 2.917 Y
OS 4.065 2.96
OC 4.067930019685 2.967069980315 4.07499488189 2.959999901575 Y
OS 4.10045 2.99958996063
OS 4.10031003937 3.00058996063
OC 4.099980019685 3.005 4.129997834646 3.005028937008 Y
OC 4.13 3.035019980315 4.13 3.005 Y
OC 4.13441003937 3.03468996063 4.129971062992 3.005002165354 Y
OS 4.13541003937 3.03455
OS 4.157930019685 3.057069980315
OC 4.165 3.06 4.165000098425 3.05000511811 Y
OS 4.53536003937 3.06
OS 4.53571003937 3.06156003937
OC 4.59428996063 3.06156003937 4.565 3.055005610236 Y
OS 4.59463996063 3.06
OS 4.615 3.06
OC 4.622069980315 3.057069980315 4.614999901575 3.05000511811 Y
OS 4.862069980315 2.817069980315
OC 4.865 2.81 4.85500511811 2.809999901575 Y
OS 4.865 2.46913996063
OS 4.88913996063 2.445
OS 5.275 2.445
OS 5.275 2.56536003937
OS 5.27491003937 2.56566003937
OC 5.273480019685 2.5748 5.30349773622 2.574814665354 Y
OC 5.27491003937 2.58393996063 5.30349773622 2.574785334646 Y
OS 5.275 2.58423996063
OS 5.275 2.96276003937
OC 5.275 3.01723996063 5.284996259843 2.99 Y
OS 5.275 3.159
OC 5.275 3.219 5.275996555118 3.189 Y
OS 5.275 3.671719980315
OS 5.191719980315 3.755
OS 5.07463996063 3.755
OS 5.07428996063 3.75343996063
OC 5.01571003937 3.75343996063 5.045 3.759994389764 Y
OS 5.01536003937 3.755
OS 3.824919980315 3.755
OS 3.82465 3.75331003937
OC 3.76535 3.75331003937 3.795 3.757998425197 Y
OS 3.765080019685 3.755
OS 3.44963996063 3.755
OS 3.44928996063 3.75343996063
OC 3.42 3.729980019685 3.42 3.759994389764 Y
OC 3.4025 3.73561003937 3.42 3.759993011811 Y
OC 3.385 3.729980019685 3.385 3.759993011811 Y
OC 3.35571003937 3.75343996063 3.385 3.759994389764 Y
OS 3.35536003937 3.755
OS 3.34463996063 3.755
OS 3.34428996063 3.75343996063
OC 3.28571003937 3.75343996063 3.315 3.759994389764 Y
OS 3.28536003937 3.755
OS 2.26106003937 3.755
OC 2.26 3.754980019685 2.259964370079 3.784999311024 Y
OC 2.25893996063 3.755 2.260035629921 3.784999311024 Y
OS 2.21606003937 3.755
OC 2.215 3.754980019685 2.214964370079 3.784999311024 Y
OC 2.21393996063 3.755 2.215035629921 3.784999311024 Y
OS 1.918280019685 3.755
OS 1.80913996063 3.64586003937
OC 1.795 3.64 1.794999901575 3.659989665354 Y
OS 1.353280019685 3.64
OS 1.26413996063 3.55086003937
OC 1.25 3.545 1.249999901575 3.564989665354 Y
OS 0.973280019685 3.545
OS 0.925 3.496719980315
OS 0.925 2.518280019685
OE
OB 0.796130019685 3.841819980315 H
OC 0.8 3.83 0.780014271654 3.83 Y
OS 0.8 3.638280019685
OS 0.81543996063 3.62283996063
OS 0.816830019685 3.6239
OC 0.835 3.630019980315 0.835 3.599987007874 Y
OC 0.865019980315 3.6 0.835 3.6 Y
OC 0.8589 3.581830019685 0.834987007874 3.6 Y
OS 0.85783996063 3.58043996063
OS 0.905 3.533280019685
OS 0.95086003937 3.57913996063
OC 0.965 3.585 0.965000098425 3.565010334646 Y
OS 1.241719980315 3.585
OS 1.33086003937 3.67413996063
OC 1.345 3.68 1.345000098425 3.660010334646 Y
OS 1.786719980315 3.68
OS 1.89586003937 3.78913996063
OC 1.91 3.795 1.910000098425 3.775010334646 Y
OS 2.18668996063 3.795
OC 2.215 3.815019980315 2.214999901575 3.784993602362 Y
OC 2.23608996063 3.80636003937 2.215 3.785009350394 Y
OC 2.23891003937 3.80636003937 2.2375 3.807781988189 N
OC 2.26 3.815019980315 2.26 3.785009350394 Y
OC 2.28831003937 3.795 2.260000098425 3.784993602362 Y
OS 5.2 3.795
OC 5.21413996063 3.78913996063 5.199999901575 3.775010334646 Y
OS 5.30913996063 3.69413996063
OC 5.315 3.68 5.295010334646 3.679999901575 Y
OS 5.315 2.88463996063
OS 5.31656003937 2.88428996063
OC 5.31656003937 2.82571003937 5.310005610236 2.855 Y
OS 5.315 2.82536003937
OS 5.315 2.602530019685
OC 5.315 2.547069980315 5.303499901575 2.5748 Y
OS 5.315 2.323280019685
OS 5.343280019685 2.295
OS 5.45653996063 2.295
OC 5.481580019685 2.30935 5.48157992126 2.280328248031 Y
OC 5.5036 2.299230019685 5.481580019685 2.280333464567 Y
OC 5.50961003937 2.29916003937 5.506635728346 2.301834547244 N
OC 5.531219980315 2.30881003937 5.53122007874 2.279788484252 Y
OC 5.555930019685 2.295 5.531219980315 2.279798425197 Y
OS 5.57016003937 2.295
OC 5.61983996063 2.295 5.595 2.280004822835 Y
OS 5.645969980315 2.295
OC 5.688030019685 2.295 5.667 2.274994389764 Y
OS 5.701719980315 2.295
OS 5.761230019685 2.35451003937
OS 5.7608 2.35571003937
OC 5.758980019685 2.366 5.788999409449 2.366003543307 Y
OC 5.77 2.38923996063 5.788995374016 2.366 Y
OS 5.77 3.085
OC 5.77586003937 3.09913996063 5.789989665354 3.084999901575 Y
OS 5.88086003937 3.20413996063
OC 5.895 3.21 5.895000098425 3.190010334646 Y
OS 6.041719980315 3.21
OS 6.115 3.283280019685
OS 6.115 3.826719980315
OS 6.051719980315 3.89
OS 5.978280019685 3.89
OS 5.84443996063 3.75616003937
OC 5.84911003937 3.749780019685 5.847269389764 3.753331889764 N
OC 5.97175 3.67843996063 5.887789370079 3.675188681102 Y
OS 5.971819980315 3.676819980315
OS 5.971819980315 3.34448996063
OC 5.88778996063 3.26046003937 5.887790059055 3.34448996063 Y
OC 5.80413996063 3.33658996063 5.887789862205 3.344481397638 Y
OC 5.797330019685 3.33905 5.800156594488 3.336218897638 N
OS 5.7 3.241719980315
OS 5.7 3.2
OC 5.69413996063 3.18586003937 5.680010334646 3.200000098425 Y
OS 5.65413996063 3.14586003937
OC 5.64 3.14 5.639999901575 3.159989665354 Y
OS 5.52 3.14
OC 5.50586003937 3.14586003937 5.520000098425 3.159989665354 Y
OS 5.46086003937 3.19086003937
OC 5.455 3.205 5.474989665354 3.205000098425 Y
OS 5.455 3.696719980315
OS 5.291719980315 3.86
OS 4.665 3.86
OC 4.65086003937 3.86586003937 4.665000098425 3.879989665354 Y
OS 4.601819980315 3.9149
OS 4.5623 3.9149
OC 4.5177 3.9149 4.54 3.935005019685 Y
OS 4.347180019685 3.9149
OS 4.34673996063 3.91348996063
OC 4.29126003937 3.91348996063 4.319 3.921994291339 Y
OS 4.290819980315 3.9149
OS 4.19651003937 3.9149
OS 4.19635 3.914869980315
OC 4.1915 3.914480019685 4.191526771654 3.944502165354 Y
OC 4.18665 3.914869980315 4.191473228346 3.944502165354 Y
OS 4.18648996063 3.9149
OS 4.10151003937 3.9149
OS 4.10135 3.914869980315
OC 4.0965 3.914480019685 4.096526771654 3.944502165354 Y
OC 4.09165 3.914869980315 4.096473228346 3.944502165354 Y
OS 4.09148996063 3.9149
OS 3.43505 3.9149
OS 3.434880019685 3.91308996063
OC 3.375119980315 3.91308996063 3.405 3.916001476378 Y
OS 3.37495 3.9149
OS 3.283 3.9149
OS 3.282769980315 3.91316003937
OC 3.253 3.886980019685 3.253 3.916996161417 Y
OC 3.22631003937 3.90325 3.253 3.917006692913 Y
OC 3.219930019685 3.90425 3.222754822835 3.90142007874 N
OS 3.19633996063 3.88066003937
OC 3.1822 3.8748 3.182199901575 3.894789665354 Y
OS 1.714780019685 3.8748
OS 1.69083996063 3.85086003937
OC 1.6767 3.845 1.676699901575 3.864989665354 Y
OS 1.58676003937 3.845
OS 1.586519980315 3.84493996063
OC 1.579 3.843980019685 1.578989370079 3.873998622047 Y
OC 1.571480019685 3.84493996063 1.579010629921 3.873998622047 Y
OS 1.57123996063 3.845
OS 1.53376003937 3.845
OC 1.48823996063 3.845 1.511 3.862993503937 Y
OS 1.134019980315 3.845
OS 1.134019980315 3.795980019685
OS 1.043980019685 3.795980019685
OS 1.043980019685 3.845
OS 0.85306003937 3.845
OS 0.852869980315 3.843219980315
OC 0.803130019685 3.843219980315 0.828 3.846005511811 Y
OS 0.80293996063 3.845
OS 0.79775 3.845
OC 0.796130019685 3.841819980315 0.797744980315 3.842999901575 N
OE
OB 0.6 2.238280019685 H
OS 1.69413996063 1.14413996063
OC 1.7 1.13 1.680010334646 1.129999901575 Y
OS 1.7 0.581969980315
OC 1.85165 0.430119980315 1.699799901575 0.430119980315 Y
OS 1.85165 0.262
OS 2.1326 0.262
OS 2.1326 0.29331003937
OC 2.23 0.40898996063 2.249995374016 0.293309940945 Y
OS 2.23 0.55286003937
OS 2.22843996063 0.55321003937
OC 2.22843996063 0.61178996063 2.234994389764 0.5825 Y
OS 2.23 0.61213996063
OS 2.23 1.156719980315
OS 0.94695 2.439769980315
OC 0.93033996063 2.43475 0.930329822835 2.464772933071 Y
OS 0.930319980315 2.43475
OC 0.9003 2.464769980315 0.930319980315 2.464769980315 Y
OS 0.9003 2.464780019685
OC 0.9045 2.48008996063 0.930321456693 2.464775295276 Y
OS 0.90528996063 2.481430019685
OS 0.89086003937 2.49586003937
OC 0.885 2.51 0.904989665354 2.510000098425 Y
OS 0.885 3.496719980315
OS 0.76586003937 3.61586003937
OC 0.76 3.63 0.779989665354 3.630000098425 Y
OS 0.76 3.821719980315
OS 0.736719980315 3.845
OS 0.613280019685 3.845
OS 0.6 3.831719980315
OS 0.6 2.906619980315
OC 0.6 2.873380019685 0.574997637795 2.89 Y
OS 0.6 2.281619980315
OC 0.605019980315 2.265 0.574997637795 2.265 Y
OC 0.60031003937 2.248869980315 0.575013779528 2.265009153543 Y
OS 0.6 2.248380019685
OS 0.6 2.238280019685
OE
OB 0.565 3.883280019685 H
OS 0.58 3.868280019685
OS 0.59086003937 3.87913996063
OC 0.605 3.885 0.605000098425 3.865010334646 Y
OS 1.35776003937 3.885
OC 1.41223996063 3.885 1.385 3.875003740157 Y
OS 1.492069980315 3.885
OC 1.529930019685 3.885 1.511 3.862986811024 Y
OS 1.551069980315 3.885
OC 1.606930019685 3.885 1.579 3.874003051181 Y
OS 1.668419980315 3.885
OS 1.69236003937 3.90893996063
OC 1.7065 3.9148 1.706500098425 3.894810334646 Y
OS 3.173919980315 3.9148
OS 3.20816003937 3.94903996063
OC 3.2223 3.9549 3.222300098425 3.934910334646 Y
OS 4.06833996063 3.9549
OC 4.12466003937 3.9549 4.0965 3.944501377953 Y
OS 4.16333996063 3.9549
OC 4.21966003937 3.9549 4.1915 3.944501377953 Y
OS 4.517519980315 3.9549
OC 4.562480019685 3.9549 4.54 3.934992125984 Y
OS 4.6101 3.9549
OC 4.62423996063 3.94903996063 4.610099901575 3.934910334646 Y
OS 4.673280019685 3.9
OS 5.25165 3.9
OC 5.275 3.916019980315 5.274999901575 3.890993110236 Y
OC 5.29785 3.90118996063 5.275 3.891001377953 Y
OS 5.298380019685 3.9
OS 5.3 3.9
OC 5.31413996063 3.89413996063 5.299999901575 3.880010334646 Y
OS 5.48913996063 3.71913996063
OC 5.495 3.705 5.475010334646 3.704999901575 Y
OS 5.495 3.213280019685
OS 5.528280019685 3.18
OS 5.631719980315 3.18
OS 5.66 3.208280019685
OS 5.66 3.25
OC 5.66586003937 3.26413996063 5.679989665354 3.249999901575 Y
OS 5.78 3.378280019685
OS 5.78 3.54771003937
OC 5.772980019685 3.567 5.802993110236 3.567 Y
OC 5.77956003937 3.58576003937 5.803012992126 3.567 Y
OS 5.78 3.58631003937
OS 5.78 3.59656003937
OS 5.7795 3.597130019685
OC 5.7795 3.636869980315 5.801991141732 3.617 Y
OS 5.78 3.63743996063
OS 5.78 3.645530019685
OS 5.77943996063 3.64611003937
OC 5.770980019685 3.667 5.801001476378 3.667 Y
OC 5.78 3.68845 5.800994586614 3.667 Y
OS 5.78 3.73771003937
OC 5.772980019685 3.757 5.802993110236 3.757 Y
OC 5.803 3.787019980315 5.803 3.757 Y
OC 5.814630019685 3.784669980315 5.802987007874 3.75700265748 Y
OS 5.815869980315 3.78415
OS 5.95586003937 3.92413996063
OC 5.97 3.93 5.970000098425 3.910010334646 Y
OS 6.04 3.93
OS 6.04 4.274119980315
OS 6.01813996063 4.295980019685
OS 0.58756003937 4.295980019685
OS 0.565 4.273419980315
OS 0.565 3.883280019685
OE
OB 0.08 0.257169980315 H
OS 0.201819980315 0.257169980315
OC 0.20445 0.264180019685 0.201818503937 0.261168897638 N
OC 0.15726003937 0.36808996063 0.295283661417 0.368101968504 Y
OS 0.15726003937 0.36811003937
OC 0.4333 0.36811003937 0.295280019685 0.36811003937 Y
OS 0.4333 0.36808996063
OC 0.38611003937 0.264180019685 0.295276377953 0.368101968504 Y
OC 0.38873996063 0.257169980315 0.388741535433 0.261168897638 N
OS 0.51055 0.257169980315
OS 0.51055 0.4626
OC 0.629919980315 0.581969980315 0.629919980315 0.4626 Y
OS 1.16536003937 0.581969980315
OS 1.16571003937 0.583530019685
OC 1.22428996063 0.583530019685 1.195 0.576937204724 Y
OS 1.22463996063 0.581969980315
OS 1.273619980315 0.581969980315
OC 1.39298996063 0.4626 1.273619980315 0.4626 Y
OS 1.39298996063 0.257169980315
OS 1.54795 0.257169980315
OS 1.54795 0.430119980315
OC 1.66 0.57666003937 1.699798129921 0.43012007874 Y
OS 1.66 1.121719980315
OS 0.92171003937 1.86001003937
OS 0.920369980315 1.85921003937
OC 0.90501003937 1.854980019685 0.905004822835 1.885001377953 Y
OS 0.905 1.854980019685
OC 0.874980019685 1.885 0.905 1.885 Y
OS 0.874980019685 1.88501003937
OC 0.87921003937 1.900369980315 0.905001377953 1.885004822835 Y
OS 0.88001003937 1.90171003937
OS 0.56586003937 2.21586003937
OC 0.56 2.23 0.579989665354 2.230000098425 Y
OS 0.56 2.239
OC 0.56 2.291 0.574993307087 2.265 Y
OS 0.56 2.864
OC 0.56 2.916 0.574993307087 2.89 Y
OS 0.56 3.831719980315
OS 0.53086003937 3.86086003937
OC 0.525 3.875 0.544989665354 3.875000098425 Y
OS 0.525 4.272419980315
OS 0.50143996063 4.295980019685
OS 0.08 4.295980019685
OS 0.08 2.58718996063
OC 0.08 2.46321003937 0.060393208661 2.5252 Y
OS 0.08 2.38718996063
OC 0.08 2.26321003937 0.060393208661 2.3252 Y
OS 0.08 2.016319980315
OC 0.08 1.89233996063 0.060393208661 1.954330019685 Y
OS 0.08 1.816319980315
OC 0.08 1.69233996063 0.060393208661 1.754330019685 Y
OS 0.08 1.44545
OC 0.08 1.321469980315 0.060393208661 1.38346003937 Y
OS 0.08 1.24545
OC 0.08 1.121469980315 0.060393208661 1.18346003937 Y
OS 0.08 0.87458996063
OC 0.08 0.75061003937 0.060393208661 0.8126 Y
OS 0.08 0.67458996063
OC 0.12541003937 0.6126 0.060393208661 0.612599901575 Y
OC 0.08 0.55061003937 0.060393208661 0.612600098425 Y
OS 0.08 0.257169980315
OE
OB 0.43331003937 3.73031003937 I
OC 0.43331003937 3.73031003937 0.295280019685 3.73031003937 Y
OE
OB 0.688980019685 3.560980019685 I
OS 0.688980019685 3.589019980315
OS 0.749019980315 3.589019980315
OS 0.749019980315 3.560980019685
OS 0.688980019685 3.560980019685
OE
OB 1.3307 1.840430019685 I
OC 1.3307 1.840430019685 1.260669980315 1.840430019685 Y
OE
OB 1.4977 1.060430019685 I
OC 1.4977 1.060430019685 1.435669980315 1.060430019685 Y
OE
OB 1.5227 2.680430019685 I
OC 1.5227 2.680430019685 1.460669980315 2.680430019685 Y
OE
OB 2.39006003937 0.679980019685 I
OS 2.39006003937 0.750019980315
OS 2.4201 0.750019980315
OS 2.4201 0.679980019685
OS 2.39006003937 0.679980019685
OE
OB 2.70108996063 3.09646003937 I
OC 2.70108996063 3.09646003937 2.55906003937 3.09646003937 Y
OE
OB 2.70108996063 4.120080019685 I
OC 2.70108996063 4.120080019685 2.55906003937 4.120080019685 Y
OE
OB 2.4562 0.748980019685 I
OS 2.4562 0.777019980315
OS 2.51623996063 0.777019980315
OS 2.51623996063 0.748980019685
OS 2.4562 0.748980019685
OE
OB 2.7477 1.121430019685 I
OC 2.7477 1.121430019685 2.685669980315 1.121430019685 Y
OE
OB 2.7477 2.559430019685 I
OC 2.7477 2.559430019685 2.685669980315 2.559430019685 Y
OE
OB 2.629380019685 0.338980019685 I
OS 2.629380019685 0.399019980315
OS 2.6574 0.399019980315
OS 2.6574 0.338980019685
OS 2.629380019685 0.338980019685
OE
OB 2.65306003937 0.748980019685 I
OS 2.65306003937 0.777019980315
OS 2.713080019685 0.777019980315
OS 2.713080019685 0.748980019685
OS 2.65306003937 0.748980019685
OE
OB 2.783 1.971980019685 I
OS 2.783 2.002019980315
OS 2.853019980315 2.002019980315
OS 2.853019980315 1.971980019685
OS 2.783 1.971980019685
OE
OB 2.78686003937 0.338980019685 I
OS 2.78686003937 0.399019980315
OS 2.814880019685 0.399019980315
OS 2.814880019685 0.338980019685
OS 2.78686003937 0.338980019685
OE
OB 2.9307 1.040430019685 I
OC 2.9307 1.040430019685 2.860669980315 1.040430019685 Y
OE
OB 2.80453996063 0.748980019685 I
OS 2.80453996063 0.777019980315
OS 2.86456003937 0.777019980315
OS 2.86456003937 0.748980019685
OS 2.80453996063 0.748980019685
OE
OB 2.829980019685 1.823980019685 I
OS 2.829980019685 1.894019980315
OS 2.860019980315 1.894019980315
OS 2.860019980315 1.823980019685
OS 2.829980019685 1.823980019685
OE
OB 2.94433996063 0.338980019685 I
OS 2.94433996063 0.399019980315
OS 2.97236003937 0.399019980315
OS 2.97236003937 0.338980019685
OS 2.94433996063 0.338980019685
OE
OB 2.94433996063 0.434980019685 I
OS 2.94433996063 0.495019980315
OS 2.97236003937 0.495019980315
OS 2.97236003937 0.434980019685
OS 2.94433996063 0.434980019685
OE
OB 3.10516003937 0.875 I
OS 3.125 0.89483996063
OS 3.167469980315 0.852369980315
OS 3.147630019685 0.832530019685
OS 3.10516003937 0.875
OE
OB 3.213080019685 1.888980019685 I
OS 3.213080019685 1.917
OS 3.273119980315 1.917
OS 3.273119980315 1.888980019685
OS 3.213080019685 1.888980019685
OE
OB 3.359980019685 1.142980019685 I
OS 3.359980019685 1.213019980315
OS 3.390019980315 1.213019980315
OS 3.390019980315 1.142980019685
OS 3.359980019685 1.142980019685
OE
OB 3.398980019685 1.069980019685 I
OS 3.398980019685 1.100019980315
OS 3.469019980315 1.100019980315
OS 3.469019980315 1.069980019685
OS 3.398980019685 1.069980019685
OE
OB 3.439 1.884980019685 I
OS 3.439 1.945
OS 3.467019980315 1.945
OS 3.467019980315 1.884980019685
OS 3.439 1.884980019685
OE
OB 3.49563996063 1.03206003937 I
OS 3.49563996063 1.062080019685
OS 3.56566003937 1.062080019685
OS 3.56566003937 1.03206003937
OS 3.49563996063 1.03206003937
OE
OB 3.637 1.869580019685 I
OS 3.637 1.9296
OS 3.665019980315 1.9296
OS 3.665019980315 1.869580019685
OS 3.637 1.869580019685
OE
OB 3.871930019685 1.417019980315 I
OC 3.871930019685 1.443080019685 3.871930019685 1.43005 Y
OS 3.9113 1.443080019685
OC 3.9113 1.417019980315 3.9113 1.43005 Y
OS 3.871930019685 1.417019980315
OE
OB 3.871930019685 1.49576003937 I
OC 3.871930019685 1.521819980315 3.871930019685 1.508790059055 Y
OS 3.9113 1.521819980315
OC 3.9113 1.49576003937 3.9113 1.508790059055 Y
OS 3.871930019685 1.49576003937
OE
OB 3.871930019685 1.5745 I
OC 3.871930019685 1.60056003937 3.871930019685 1.587530019685 Y
OS 3.9113 1.60056003937
OC 3.9113 1.5745 3.9113 1.587530019685 Y
OS 3.871930019685 1.5745
OE
OB 3.871930019685 1.65323996063 I
OC 3.871930019685 1.6793 3.871930019685 1.666269980315 Y
OS 3.9113 1.6793
OC 3.9113 1.65323996063 3.9113 1.666269980315 Y
OS 3.871930019685 1.65323996063
OE
OB 3.997480019685 1.145980019685 I
OS 3.997480019685 1.176
OS 4.067519980315 1.176
OS 4.067519980315 1.145980019685
OS 3.997480019685 1.145980019685
OE
OB 4.029419980315 1.49576003937 I
OC 4.029419980315 1.521819980315 4.029419980315 1.508790059055 Y
OS 4.06878996063 1.521819980315
OC 4.06878996063 1.49576003937 4.06878996063 1.508790059055 Y
OS 4.029419980315 1.49576003937
OE
OB 4.3575 1.150980019685 I
OS 4.3575 1.181
OS 4.427519980315 1.181
OS 4.427519980315 1.150980019685
OS 4.3575 1.150980019685
OE
OB 4.462480019685 1.417019980315 I
OC 4.462480019685 1.443080019685 4.462480019685 1.43005 Y
OS 4.50185 1.443080019685
OC 4.50185 1.417019980315 4.50185 1.43005 Y
OS 4.462480019685 1.417019980315
OE
OB 4.5223 1.20666003937 I
OS 4.5223 1.236680019685
OS 4.592319980315 1.236680019685
OS 4.592319980315 1.20666003937
OS 4.5223 1.20666003937
OE
OB 4.61996003937 1.2989 I
OC 4.61996003937 1.32496003937 4.61996003937 1.311930019685 Y
OS 4.659330019685 1.32496003937
OC 4.659330019685 1.2989 4.659330019685 1.311930019685 Y
OS 4.61996003937 1.2989
OE
OB 4.6987 1.4564 I
OC 4.6987 1.48243996063 4.6987 1.469419980315 Y
OS 4.738069980315 1.48243996063
OC 4.738069980315 1.4564 4.738069980315 1.469419980315 Y
OS 4.6987 1.4564
OE
OB 4.72503996063 1.3513 I
OS 4.72503996063 1.390669980315
OC 4.7511 1.390669980315 4.738069980315 1.390669980315 Y
OS 4.7511 1.3513
OC 4.72503996063 1.3513 4.738069980315 1.3513 Y
OE
OB 5.082969980315 3.09646003937 I
OC 5.082969980315 3.09646003937 4.94093996063 3.09646003937 Y
OE
OB 5.082969980315 4.120080019685 I
OC 5.082969980315 4.120080019685 4.94093996063 4.120080019685 Y
OE
OB 6.190030019685 2.094 I
OC 6.190030019685 2.094 5.99 2.094 Y
OE
OB 5.974969980315 1.045 I
OC 5.984369980315 1.1056 6.174999507874 1.045001377953 Y
OC 5.97846003937 1.12348996063 6.008502165354 1.123493208661 Y
OS 5.97846003937 1.1235
OC 6.00696003937 1.1535 6.008499507874 1.1235 Y
OC 6.175 1.245030019685 6.175000098425 1.045012598425 Y
OC 6.375030019685 1.045 6.175 1.045 Y
OC 6.362830019685 0.97621003937 6.174992913386 1.045 Y
OC 6.365 0.96501003937 6.334998523622 0.965007480315 Y
OS 6.365 0.965
OC 6.342730019685 0.93601003937 6.334996161417 0.965 Y
OC 6.175 0.844969980315 6.174999901575 1.045000984252 Y
OC 5.974969980315 1.045 6.175 1.045 Y
OE
OB 6.1856 2.230719980315 I
OS 6.1856 2.29076003937
OS 6.213619980315 2.29076003937
OS 6.213619980315 2.230719980315
OS 6.1856 2.230719980315
OE
OB 6.424580019685 3.34448996063 I
OC 6.424580019685 3.34448996063 6.34055 3.34448996063 Y
OE
OB 6.424580019685 3.67518996063 I
OC 6.424580019685 3.67518996063 6.34055 3.67518996063 Y
OE
SE
P 4.31 4.065 6 P 0 8 0;1=0
P 4.31 4.115 6 P 0 8 0;1=0
P 4.61 2.3 6 P 0 8 0;1=0
P 4.50185 2.05996004 4 P 0 8 0;1=1
P 4.49 2.275 6 P 0 8 0;1=0
P 4.435 2.315 6 P 0 8 0;1=0
P 4.49 2.325 6 P 0 8 0;1=0
P 4.435 2.365 6 P 0 8 0;1=0
P 3.655 2.465 6 P 0 8 0;1=0
P 3.125 1.605 6 P 0 8 0;1=0
P 3.65 2.68 6 P 0 8 0;1=2
P 3.12 2.645 6 P 0 8 0;1=2
P 4.1869 2.09933002 4 P 0 8 0;1=1
P 3.765 2.69 6 P 0 8 0;1=0
P 4.50185 1.50878996 4 P 0 8 0;1=1
P 4.3 3.865 4 P 0 8 0;1=3
P 3.36525 3.305 3 P 0 8 0;1=4
P 3.37 3.44 4 P 0 8 0;1=3
P 4.795 0.925 4 P 0 8 0;1=3
P 4.08 3.27 4 P 0 8 0;1=3
P 3.95 3.82 4 P 0 8 0;1=3
P 3.746 1.782 4 P 0 8 0;1=3
P 4.06878996 1.58753002 4 P 0 8 0;1=1
P 4.205 0.82 4 P 0 8 0;1=3
P 3.82286004 0.86213996 6 P 0 8 0;1=0
P 3.705 0.84 4 P 0 8 0;1=3
P 0.496 2.13455 6 P 0 8 0;1=0
P 0.528 2.72 6 P 0 8 0;1=0
P 0.575 1.015 6 P 0 8 0;1=0
P 0.48956998 1.53618996 6 P 0 8 0;1=0
P 4.65933002 1.98121998 4 P 0 8 0;1=1
P 4.06878996 1.90248002 4 P 0 8 0;1=1
P 4.50185 1.39066998 4 P 0 8 0;1=1
P 4.06878996 2.1387 4 P 0 8 0;1=1
P 4.22626998 2.05996004 4 P 0 8 0;1=1
P 3.95066998 2.05996004 4 P 0 8 0;1=1
P 4.22626998 2.02058996 4 P 0 8 0;1=1
P 4.26563996 2.09933002 4 P 0 8 0;1=1
P 4.26563996 2.05996004 4 P 0 8 0;1=1
P 4.50185 1.90248002 4 P 0 8 0;1=1
P 4.73806998 2.09933002 4 P 0 8 0;1=1
P 4.02941998 2.02058996 4 P 0 8 0;1=1
P 4.50185 1.86311004 4 P 0 8 0;1=1
P 4.6987 2.05996004 4 P 0 8 0;1=1
P 4.61996004 1.94185 4 P 0 8 0;1=1
P 4.61996004 1.98121998 4 P 0 8 0;1=1
P 4.26563996 2.02058996 4 P 0 8 0;1=1
P 4.61996004 1.90248002 4 P 0 8 0;1=1
P 4.58058996 1.98121998 4 P 0 8 0;1=1
P 4.54121998 2.02058996 4 P 0 8 0;1=1
P 4.34436998 2.09933002 4 P 0 8 0;1=1
P 4.06878996 2.09933002 4 P 0 8 0;1=5
P 4.6987 1.50878996 4 P 0 8 0;1=1
P 4.54121998 1.98121998 4 P 0 8 0;1=1
P 4.06878996 2.05996004 4 P 0 8 0;1=1
P 4.65933002 1.50878996 4 P 0 8 0;1=1
P 3.95066998 2.09933002 4 P 0 8 0;1=1
P 4.61996004 1.54816004 4 P 0 8 0;1=1
P 3.99005 2.09933002 4 P 0 8 0;1=5
P 4.58058996 1.54816004 4 P 0 8 0;1=1
P 4.6987 1.94185 4 P 0 8 0;1=1
P 4.50185 2.02058996 4 P 0 8 0;1=1
P 4.46248002 2.02058996 4 P 0 8 0;1=1
P 4.42311004 1.98121998 4 P 0 8 0;1=1
P 4.46248002 1.94185 4 P 0 8 0;1=1
P 4.38373996 1.86311004 4 P 0 8 0;1=1
P 4.38373996 1.82373996 4 P 0 8 0;1=1
P 4.46248002 1.98121998 4 P 0 8 0;1=1
P 4.10816004 1.94185 4 P 0 8 0;1=1
P 4.02941998 1.98121998 4 P 0 8 0;1=1
P 4.58058996 2.17806998 4 P 0 8 0;1=1
P 4.73806998 1.90248002 4 P 0 8 0;1=1
P 4.54121998 2.1387 4 P 0 8 0;1=1
P 4.10816004 2.02058996 4 P 0 8 0;1=1
P 4.50185 2.1387 4 P 0 8 0;1=1
P 3.99005 1.94185 4 P 0 8 0;1=1
P 4.02941998 1.94185 4 P 0 8 0;1=1
P 4.50185 2.09933002 4 P 0 8 0;1=1
P 4.14753002 2.02058996 4 P 0 8 0;1=1
P 4.61996004 2.17806998 4 P 0 8 0;1=1
P 4.02941998 1.86311004 4 P 0 8 0;1=1
P 4.06878996 1.43005 4 P 0 8 0;1=1
P 4.54121998 1.54816004 4 P 0 8 0;1=1
P 4.26563996 1.50878996 4 P 0 8 0;1=1
P 4.1869 1.94185 4 P 0 8 0;1=1
P 4.14753002 1.46941998 4 P 0 8 0;1=1
P 4.1869 1.46941998 4 P 0 8 0;1=1
P 4.1869 2.1387 4 P 0 8 0;1=1
P 4.6987 1.43005 4 P 0 8 0;1=1
P 4.10816004 1.39066998 4 P 0 8 0;1=1
P 4.65933002 1.43005 4 P 0 8 0;1=1
P 4.14753002 1.39066998 4 P 0 8 0;1=1
P 4.61996004 1.43005 4 P 0 8 0;1=1
P 4.10816004 1.43005 4 P 0 8 0;1=1
P 4.58058996 1.43005 4 P 0 8 0;1=1
P 4.14753002 1.43005 4 P 0 8 0;1=1
P 4.1869 1.43005 4 P 0 8 0;1=1
P 4.22626998 1.43005 4 P 0 8 0;1=1
P 4.54121998 1.46941998 4 P 0 8 0;1=1
P 4.22626998 1.39066998 4 P 0 8 0;1=1
P 4.50185 1.46941998 4 P 0 8 0;1=1
P 4.26563996 1.39066998 4 P 0 8 0;1=1
P 4.61996004 1.46941998 4 P 0 8 0;1=1
P 4.26563996 1.31193002 4 P 0 8 0;1=1
P 4.61996004 1.50878996 4 P 0 8 0;1=1
P 4.34436998 1.31193002 4 P 0 8 0;1=1
P 4.58058996 1.46941998 4 P 0 8 0;1=1
P 4.34436998 1.3513 4 P 0 8 0;1=1
P 4.54121998 1.50878996 4 P 0 8 0;1=1
P 4.34436998 1.39066998 4 P 0 8 0;1=1
P 4.1869 1.50878996 4 P 0 8 0;1=1
P 4.46248002 1.50878996 4 P 0 8 0;1=1
P 4.22626998 1.50878996 4 P 0 8 0;1=1
P 4.26563996 1.43005 4 P 0 8 0;1=5
P 4.26563996 1.46941998 4 P 0 8 0;1=1
P 4.38373996 1.39066998 4 P 0 8 0;1=1
P 4.38373996 1.43005 4 P 0 8 0;1=1
P 4.54121998 1.31193002 4 P 0 8 0;1=1
P 4.49876004 1.31501998 4 P 0 8 0;1=1
P 4.34436998 1.98121998 4 P 0 8 0;1=1
P 4.57843996 1.35345 4 P 0 8 0;1=1
P 3.9113 1.3513 4 P 0 8 0;1=1
P 4.54121998 1.3513 4 P 0 8 0;1=1
P 3.95066998 1.3513 4 P 0 8 0;1=1
P 4.45938996 1.35438996 4 P 0 8 0;1=1
P 3.99 1.31188002 4 P 0 8 0;1=1
P 4.46248002 1.39066998 4 P 0 8 0;1=1
P 4.65933002 1.3513 4 P 0 8 0;1=1
P 3.99 1.35125 4 P 0 8 0;1=1
P 4.61996004 1.3513 4 P 0 8 0;1=1
P 4.6987 1.86311004 4 P 0 8 0;1=1
P 4.46248002 2.05996004 4 P 0 8 0;1=1
P 4.06873996 1.31188002 4 P 0 8 0;1=1
P 4.65933002 1.82373996 4 P 0 8 0;1=1
P 4.42311004 2.05996004 4 P 0 8 0;1=1
P 4.10811004 1.31188002 4 P 0 8 0;1=1
P 4.58058996 1.39066998 4 P 0 8 0;1=1
P 4.02941998 1.39066998 4 P 0 8 0;1=1
P 4.54121998 1.39066998 4 P 0 8 0;1=1
P 4.06878996 1.39066998 4 P 0 8 0;1=1
P 4.73806998 1.78436998 4 P 0 8 0;1=1
P 4.73806998 1.31193002 4 P 0 8 0;1=1
P 4.1869 1.31193002 4 P 0 8 0;1=1
P 4.73806998 1.70563996 4 P 0 8 0;1=1
P 4.6987 1.31193002 4 P 0 8 0;1=1
P 4.22626998 1.31193002 4 P 0 8 0;1=1
P 4.10816004 1.3513 4 P 0 8 0;1=1
P 4.14753002 1.3513 4 P 0 8 0;1=1
P 4.6987 1.39066998 4 P 0 8 0;1=1
P 4.1869 1.3513 4 P 0 8 0;1=1
P 4.65933002 1.39066998 4 P 0 8 0;1=1
P 4.22626998 1.3513 4 P 0 8 0;1=1
P 4.73806998 2.17806998 4 P 0 8 0;1=1
P 4.73806998 2.1387 4 P 0 8 0;1=1
P 4.58058996 2.09933002 4 P 0 8 0;1=1
P 4.54121998 2.09933002 4 P 0 8 0;1=1
P 4.58058996 1.86311004 4 P 0 8 0;1=1
P 4.65933002 2.05996004 4 P 0 8 0;1=1
P 4.58058996 2.05996004 4 P 0 8 0;1=1
P 4.54121998 1.90248002 4 P 0 8 0;1=1
P 4.58058996 2.02058996 4 P 0 8 0;1=1
P 4.22626998 1.98121998 4 P 0 8 0;1=1
P 4.26563996 1.94185 4 P 0 8 0;1=1
P 4.10816004 1.98121998 4 P 0 8 0;1=1
P 4.14753002 1.98121998 4 P 0 8 0;1=1
P 4.61996004 2.1387 4 P 0 8 0;1=1
P 4.6987 1.70563996 4 P 0 8 0;1=1
P 4.6987 1.66626998 4 P 0 8 0;1=1
P 1.45 3.59 6 P 0 8 0;1=0
P 1.56 3.165 6 P 0 8 0;1=2
P 1.56 3.205 6 P 0 8 0;1=0
P 0.72 3.463 6 P 0 8 0;1=2
P 0.42326004 3.4315 8 P 0 8 0;1=6
P 0.40553996 3.4008 8 P 0 8 0;1=6
P 0.2815 3.4315 8 P 0 8 0;1=6
P 0.26378002 3.4008 8 P 0 8 0;1=6
P 0.71 3.305 4 P 0 8 0;1=3
P 1.14 3.52 6 P 0 8 0;1=0
P 1.245 3.52 6 P 0 8 0;1=0
P 4.705 3.95 3 P 0 8 0;1=4
P 4.705 3.91 6 P 0 8 0;1=2
P 1.566 2.95 6 P 0 8 0;1=0
P 1.045 3.77 6 P 0 8 0;1=2
P 1.515 3.58 6 P 0 8 0;1=2
P 6.145 4.035 6 P 0 8 0;1=0
P 1.37 3.64 6 P 0 8 0;1=2
P 1.667 3.438 6 P 0 8 0;1=2
P 1.591 3.546 6 P 0 8 0;1=2
P 1.13 3.445 6 P 0 8 0;1=2
P 0.95 3.445 6 P 0 8 0;1=2
P 2.19 3.488 6 P 0 8 0;1=2
P 2.192 3.388 6 P 0 8 0;1=2
P 1.41916004 3.33916004 6 P 0 8 0;1=2
P 1.407 3.2 6 P 0 8 0;1=2
P 1.495 3.11033996 6 P 0 8 0;1=2
P 1.535 3.105 4 P 0 8 0;1=3
P 1.15253002 3.06246998 6 P 0 8 0;1=2
P 0.95 3.215 6 P 0 8 0;1=2
P 0.945 3.125 6 P 0 8 0;1=2
P 1.175 2.9 6 P 0 8 0;1=2
P 1.025 3.02 6 P 0 8 0;1=2
P 5.275 3.891 6 P 0 8 0;1=0
P 0.74 1.005 6 P 0 8 0;1=0
P 0.79 1.005 6 P 0 8 0;1=0
P 0.84 1.005 6 P 0 8 0;1=0
P 1.568 3.011 6 P 0 8 0;1=0
P 1.738 3.241 6 P 0 8 0;1=0
P 1.765 2.9 6 P 0 8 0;1=0
P 1.78 3.095 6 P 0 8 0;1=0
P 1.795 2.946 6 P 0 8 0;1=0
P 5.2 0.87 6 P 0 8 0;1=0
P 4.47 3.21998002 6 P 0 8 0;1=0
P 4.385 3.645 6 P 0 8 0;1=0
P 0.78 3.305 4 P 0 8 0;1=3
P 1.03 3.515 6 P 0 8 0;1=0
P 1.19 3.52 6 P 0 8 0;1=0
P 0.95 2.915 4 P 0 8 0;1=3
P 0.945 2.99 4 P 0 8 0;1=3
P 0.885 3.03 4 P 0 8 0;1=3
P 0.875 2.955 4 P 0 8 0;1=3
P 0.795 3.085 4 P 0 8 0;1=3
P 0.55 3.36 6 P 0 8 0;1=0
P 0.3701 3.4008 8 P 0 8 0;1=6
P 0.55 3.554 6 P 0 8 0;1=0
P 0.31693996 3.4315 8 P 0 8 0;1=6
P 5.92 1.57063002 6 P 0 8 0;1=0
P 6.22 1.57 6 P 0 8 0;1=0
P 5.92 1.46 6 P 0 8 0;1=0
P 6.22 1.465 6 P 0 8 0;1=0
P 5.92 1.68 6 P 0 8 0;1=0
P 6.22035 1.67063002 6 P 0 8 0;1=0
P 5.92 1.78 6 P 0 8 0;1=0
P 6.22 1.755 6 P 0 8 0;1=0
P 6.09423996 4.13778996 6 P 0 8 0;1=0
P 3.51 3.08 6 P 0 8 0;1=0
P 1.025 2.9 6 P 0 8 0;1=2
P 4.42311004 1.94185 4 P 0 8 0;1=1
P 3.46 3.065 6 P 0 8 0;1=0
P 1.125 2.9 6 P 0 8 0;1=2
P 4.42311004 1.90248002 4 P 0 8 0;1=1
P 3.035 1.64 6 P 0 8 0;1=2
P 3.445 2.65 4 P 0 8 0;1=3
P 1.1288 0.7302 5 P 0 8 0;1=7
P 3.075 1.605 6 P 0 8 0;1=2
P 3.365 2.95 3 P 0 8 0;1=4
P 0.755 0.62 4 P 0 8 0;1=3
P 0.715 0.77 6 P 0 8 0;1=0
P 0.83 3.445 6 P 0 8 0;1=0
P 0.795 3.485 6 P 0 8 0;1=0
P 0.83 3.525 6 P 0 8 0;1=0
P 0.951 3.519 6 P 0 8 0;1=0
P 0.82951004 3.2794 6 P 0 8 0;1=0
P 0.79 3.155 6 P 0 8 0;1=0
P 0.78635 3.24491998 6 P 0 8 0;1=0
P 1.26 3.18 6 P 0 8 0;1=0
P 1.295 3.28 6 P 0 8 0;1=0
P 1.075 3.02 6 P 0 8 0;1=0
P 1.125 3.02 6 P 0 8 0;1=0
P 1.073 3.825 4 P 0 8 0;1=8
P 0.703 3.575 4 P 0 8 0;1=8
P 0.35238002 3.4315 8 P 0 8 0;1=6
P 0.33466004 3.4008 8 P 0 8 0;1=6
P 0.735 3.575 4 P 0 8 0;1=8
P 1.105 3.825 4 P 0 8 0;1=8
P 0.38781998 3.4315 8 P 0 8 0;1=6
P 0.29921998 3.4008 8 P 0 8 0;1=6
P 0.995 3.7 4 P 0 8 0;1=3
P 4.285 3.46 6 P 0 8 0;1=2
P 2.15 3.438 6 P 0 8 0;1=0
P 2.05 3.538 6 P 0 8 0;1=0
P 2.05 3.488 6 P 0 8 0;1=0
P 1.29 3.215 6 P 0 8 0;1=2
P 1.0541 3.185 6 P 0 8 0;1=0
P 1.3 3.49663996 6 P 0 8 0;1=2
P 1.04018996 3.47425 6 P 0 8 0;1=2
P 4.205 3.66 6 P 0 8 0;1=0
P 0.975 3.41 6 P 0 8 0;1=2
P 4.225 3.545 6 P 0 8 0;1=0
P 1.015 3.41 6 P 0 8 0;1=2
P 3.95 3.6 6 P 0 8 0;1=0
P 0.835 3.6 6 P 0 8 0;1=2
P 3.95 3.7 6 P 0 8 0;1=0
P 0.915 3.595 6 P 0 8 0;1=2
P 4.1184 3.5362 6 P 0 8 0;1=2
P 4.085 3.11 6 P 0 8 0;1=0
P 4.51 3.065 6 P 0 8 0;1=2
P 4.33381998 3.60466004 6 P 0 8 0;1=0
P 4.34 3.28 6 P 0 8 0;1=2
P 4.335 3.665 6 P 0 8 0;1=0
P 4.09 3.71338996 6 P 0 8 0;1=0
P 3.38 1.025 6 P 0 8 0;1=2
P 4.585 0.865 6 P 0 8 0;1=0
P 0.62 3.235 6 P 0 8 0;1=2
P 3.925 3.239 6 P 0 8 0;1=0
P 0.825 3.39 6 P 0 8 0;1=2
P 0.795 3.4179 6 P 0 8 0;1=2
P 3.795 3.758 6 P 0 8 0;1=0
P 3.62 1.28 6 P 0 8 0;1=2
P 5.195 0.755 6 P 0 8 0;1=0
P 4.96 0.85 6 P 0 8 0;1=2
P 0.66 3.185 6 P 0 8 0;1=2
P 3.62 1.235 6 P 0 8 0;1=2
P 5.195 0.815 6 P 0 8 0;1=0
P 4.937 0.79161004 6 P 0 8 0;1=2
P 0.66 3.235 6 P 0 8 0;1=2
P 4.205 3.81 6 P 0 8 0;1=2
P 5.814 2.821 5 P 0 8 0;1=7
P 4.19 3.735 6 P 0 8 0;1=2
P 5.814 2.721 5 P 0 8 0;1=7
P 3.895 3.7 6 P 0 8 0;1=2
P 5.815 3.021 5 P 0 8 0;1=7
P 4.135 3.735 6 P 0 8 0;1=2
P 5.814 2.621 5 P 0 8 0;1=7
P 2.3 3.475 6 P 0 8 0;1=2
P 5.045 3.405 6 P 0 8 0;1=2
P 6.33 2.67 5 P 0 8 0;1=7
P 1.35 3.12 6 P 0 8 0;1=2
P 2.255 3.475 6 P 0 8 0;1=2
P 5.09 3.405 6 P 0 8 0;1=2
P 6.33 2.865 6 P 0 8 0;1=0
P 1.46 3.34 6 P 0 8 0;1=2
P 4.575 2.235 6 P 0 8 0;1=2
P 4.50185 1.94185 4 P 0 8 0;1=1
P 4.705 0.825 6 P 0 8 0;1=0
P 4.575 2.275 6 P 0 8 0;1=2
P 4.38373996 1.98121998 4 P 0 8 0;1=1
P 4.755 0.825 6 P 0 8 0;1=0
P 1.26 0.72 6 P 0 8 0;1=0
P 4.6987 1.82373996 4 P 0 8 0;1=1
P 0.842 0.75 6 P 0 8 0;1=0
P 4.73806998 1.82373996 4 P 0 8 0;1=1
P 4.10816004 1.90248002 4 P 0 8 0;1=5
P 3.73648996 1.85735 6 P 0 8 0;1=2
P 4.10816004 1.82373996 4 P 0 8 0;1=1
P 4.345 3.02 6 P 0 8 0;1=2
P 4.075 3.005 6 P 0 8 0;1=2
P 3.925 3.291 6 P 0 8 0;1=0
P 4.14753002 1.82373996 4 P 0 8 0;1=1
P 4.39 3.02 6 P 0 8 0;1=2
P 4.13 3.005 6 P 0 8 0;1=2
P 3.795 3.81 6 P 0 8 0;1=0
P 4.615 3.11 6 P 0 8 0;1=2
P 4.6987 1.90248002 4 P 0 8 0;1=1
P 4.4 3.325 6 P 0 8 0;1=0
P 4.615 2.68408996 6 P 0 8 0;1=2
P 4.15 2.468 6 P 0 8 0;1=2
P 6.22 1.415 6 P 0 8 0;1=0
P 4.685 2.7 6 P 0 8 0;1=2
P 4.209 2.468 6 P 0 8 0;1=2
P 4.34436998 2.1387 4 P 0 8 0;1=1
P 6.22 1.516 6 P 0 8 0;1=0
P 4.975 2.26 6 P 0 8 0;1=2
P 4.093 2.468 6 P 0 8 0;1=2
P 6.22 1.62 6 P 0 8 0;1=0
P 4.925 2.26 6 P 0 8 0;1=0
P 4.037 2.468 6 P 0 8 0;1=2
P 6.22 1.815 6 P 0 8 0;1=0
P 5.92 1.41 6 P 0 8 0;1=0
P 5.09 2.155 6 P 0 8 0;1=2
P 3.801 2.468 6 P 0 8 0;1=2
P 4.10816004 2.09933002 4 P 0 8 0;1=1
P 5.92 1.515 6 P 0 8 0;1=0
P 5.135 2.155 6 P 0 8 0;1=2
P 3.86 2.468 6 P 0 8 0;1=2
P 4.14753002 2.09933002 4 P 0 8 0;1=1
P 5.92 1.63 6 P 0 8 0;1=0
P 5.115 2.065 6 P 0 8 0;1=2
P 3.919 2.468 6 P 0 8 0;1=2
P 5.92 1.73 6 P 0 8 0;1=0
P 5.13 2.105 6 P 0 8 0;1=2
P 3.978 2.468 6 P 0 8 0;1=2
P 4.685 2.645 6 P 0 8 0;1=2
P 4.1 3.38 6 P 0 8 0;1=0
P 4.53 2.5 6 P 0 8 0;1=2
P 3.9 3.385 6 P 0 8 0;1=0
P 4.485 3.115 6 P 0 8 0;1=0
P 4.575 2.374 6 P 0 8 0;1=2
P 4.485 2.5 6 P 0 8 0;1=2
P 4.29441998 3.10075 6 P 0 8 0;1=0
P 4.61 2.345 6 P 0 8 0;1=2
P 4.54 3.125 6 P 0 8 0;1=0
P 4.085 3.21998002 6 P 0 8 0;1=0
P 4.35 2.505 6 P 0 8 0;1=2
P 5.365 0.79 6 P 0 8 0;1=0
P 5.365 0.845 6 P 0 8 0;1=0
P 4.0661 3.5341 6 P 0 8 0;1=0
P 3.83 3.466 5 P 0 8 0;1=7
P 4.35143002 3.06643002 6 P 0 8 0;1=2
P 3.7 3.325 6 P 0 8 0;1=0
P 3.5825 3.4005 3 P 0 8 0;1=4
P 4.33 3.1432 6 P 0 8 0;1=2
P 3.83 3.235 6 P 0 8 0;1=0
P 4.085 3.165 6 P 0 8 0;1=2
P 3.415 3.335 3 P 0 8 0;1=4
P 0.74 1.3 6 P 0 8 0;1=2
P 1.26 0.62 5 P 0 8 0;1=7
P 0.785 0.8225 6 P 0 8 0;1=2
P 0.695 1.3 6 P 0 8 0;1=2
P 1.26 0.67 5 P 0 8 0;1=7
P 0.76321004 0.783 6 P 0 8 0;1=2
P 3.32 3.015 4 P 0 8 0;1=3
P 3.24 3.01 4 P 0 8 0;1=3
P 0.606 1.57 6 P 0 8 0;1=0
P 0.835 1.73 6 P 0 8 0;1=0
P 0.355 3.27 6 P 0 8 0;1=0
P 0.28 3.27 6 P 0 8 0;1=0
P 0.13 3.187 6 P 0 8 0;1=0
P 0.69023002 1.98523996 6 P 0 8 0;1=2
P 0.125 2.195 6 P 0 8 0;1=0
P 0.69 1.93 6 P 0 8 0;1=2
P 0.125 2.145 6 P 0 8 0;1=0
P 0.69 1.875 6 P 0 8 0;1=2
P 0.125 2.045 6 P 0 8 0;1=0
P 0.13 2.73326998 6 P 0 8 0;1=0
P 0.287 2.743 6 P 0 8 0;1=0
P 0.125 2.615 6 P 0 8 0;1=0
P 0.735 1.19 6 P 0 8 0;1=2
P 0.125 1.06 6 P 0 8 0;1=0
P 0.68 1.19 6 P 0 8 0;1=2
P 0.125 1.01 6 P 0 8 0;1=0
P 0.675 1.145 6 P 0 8 0;1=2
P 0.125 0.91 6 P 0 8 0;1=0
P 0.125 1.62 6 P 0 8 0;1=0
P 0.13 1.57 6 P 0 8 0;1=0
P 0.1362 1.4872 6 P 0 8 0;1=0
P 2.937 3.173 6 P 0 8 0;1=0
P 3.01 3.17 6 P 0 8 0;1=2
P 0.896 2.489 3 P 0 8 0;1=4
P 4.31168996 4.01168996 3 P 0 8 0;1=4
P 4.319 3.922 3 P 0 8 0;1=4
P 4.5 4.115 6 P 0 8 0;1=0
P 1.315 2.905 5 P 0 8 0;1=9
P 2.932 3.295 5 P 0 8 0;1=9
P 0.915 1.4 6 P 0 8 0;1=2
P 1.42 0.69535 5 P 0 8 0;1=7
P 4.5 4.165 6 P 0 8 0;1=0
P 1.36 2.905 5 P 0 8 0;1=9
P 2.896 3.301 5 P 0 8 0;1=9
P 0.965 1.4 6 P 0 8 0;1=2
P 1.4207 0.779 5 P 0 8 0;1=7
P 4.65933002 2.02058996 4 P 0 8 0;1=5
P 4.33 3.535 6 P 0 8 0;1=2
P 4.44 4.065 3 P 0 8 0;1=4
P 4.61996004 2.05996004 4 P 0 8 0;1=1
P 4.395 3.415 5 P 0 8 0;1=9
P 4.44 4.115 3 P 0 8 0;1=4
P 4.61996004 2.09933002 4 P 0 8 0;1=1
P 4.425 3.36088996 5 P 0 8 0;1=9
P 0.638 2.74 5 P 0 8 0;1=9
P 0.825 2.305 3 P 0 8 0;1=4
P 0.755 2.825 5 P 0 8 0;1=9
P 0.795 2.345 3 P 0 8 0;1=4
P 5.97613002 4.13778996 6 P 0 8 0;1=0
P 5.90748002 4.18725 6 P 0 8 0;1=0
P 4.06878996 2.02058996 4 P 0 8 0;1=1
P 0.905 1.935 6 P 0 8 0;1=0
P 3.99005 2.05996004 4 P 0 8 0;1=1
P 0.945 1.97 6 P 0 8 0;1=0
P 4.02941998 2.05996004 4 P 0 8 0;1=1
P 0.905 1.885 6 P 0 8 0;1=0
P 0.63 2.15 6 P 0 8 0;1=2
P 3.95066998 2.02058996 4 P 0 8 0;1=1
P 0.985 2.185 6 P 0 8 0;1=0
P 0.287 2.62508002 6 P 0 8 0;1=2
P 0.43 2.555 6 P 0 8 0;1=0
P 3.95066998 1.98121998 4 P 0 8 0;1=1
P 0.63 2.105 6 P 0 8 0;1=2
P 0.99 2.015 6 P 0 8 0;1=2
P 0.242 2.62508002 6 P 0 8 0;1=0
P 3.99005 1.98121998 4 P 0 8 0;1=1
P 0.63 2.06 6 P 0 8 0;1=2
P 0.99 1.975 6 P 0 8 0;1=2
P 4.02941998 1.82373996 4 P 0 8 0;1=1
P 0.935 1.3 6 P 0 8 0;1=0
P 3.95066998 1.90248002 4 P 0 8 0;1=1
P 0.87 1.255 6 P 0 8 0;1=0
P 3.95066998 1.86311004 4 P 0 8 0;1=1
P 0.935 1.25 6 P 0 8 0;1=0
P 4.06878996 1.94185 4 P 0 8 0;1=1
P 0.92 1.73 6 P 0 8 0;1=0
P 0.281 1.48798002 6 P 0 8 0;1=2
P 4.06878996 1.86311004 4 P 0 8 0;1=1
P 0.985 1.655 6 P 0 8 0;1=0
P 0.371 1.48798002 6 P 0 8 0;1=2
P 4.06878996 1.82373996 4 P 0 8 0;1=1
P 0.985 1.59 6 P 0 8 0;1=0
P 0.236 1.48798002 6 P 0 8 0;1=2
P 0.345 3.09 6 P 0 8 0;1=2
P 3.84091004 2.00091004 6 P 0 8 0;1=0
P 0.99 1.885 6 P 0 8 0;1=2
P 0.395 3.09 6 P 0 8 0;1=2
P 3.87193002 2.09933002 4 P 0 8 0;1=5
P 0.99 2.065 6 P 0 8 0;1=2
P 0.445 3.09 6 P 0 8 0;1=0
P 3.9113 2.09933002 4 P 0 8 0;1=1
P 0.975 2.14 6 P 0 8 0;1=2
P 0.53 2.005 6 P 0 8 0;1=0
P 0.552 2.535 6 P 0 8 0;1=0
P 0.455 1.825 6 P 0 8 0;1=0
P 0.16038996 1.85433002 10 P 0 8 0;1=10
P 0.46 2.195 6 P 0 8 0;1=0
P 0.16038996 2.4252 10 P 0 8 0;1=10
P 0.445 0.735 6 P 0 8 0;1=0
P 0.16038996 0.7126 10 P 0 8 0;1=10
P 0.455 1.0439 6 P 0 8 0;1=0
P 0.16038996 1.28346004 10 P 0 8 0;1=10
P 0.535 1.835 6 P 0 8 0;1=0
P 0.532 2.40186998 6 P 0 8 0;1=0
P 0.505 0.60228002 6 P 0 8 0;1=0
P 0.5374 1.26 6 P 0 8 0;1=0
P 0.48 2.005 6 P 0 8 0;1=0
P 0.485 2.525 6 P 0 8 0;1=0
P 0.515 0.835 6 P 0 8 0;1=0
P 0.475 1.405 6 P 0 8 0;1=0
P 6.335 0.965 6 P 0 8 0;1=0
P 6.335 1.02 6 P 0 8 0;1=0
P 6.335 1.08 6 P 0 8 0;1=0
P 2.085 3.017 5 P 0 8 0;1=7
P 2.135 3.017 5 P 0 8 0;1=7
P 2.185 3.017 5 P 0 8 0;1=7
P 6.0085 1.1235 6 P 0 8 0;1=0
P 2.22 3.3 5 P 0 8 0;1=7
P 5.8 1.048 4 P 0 8 0;1=3
P 4.34436998 2.02058996 4 P 0 8 0;1=1
P 5.285 2.99 5 P 0 8 0;1=9
P 3.125 3.075 6 P 0 8 0;1=2
P 4.34436998 2.17806998 4 P 0 8 0;1=1
P 2.017 3.279 4 P 0 8 0;1=3
P 0.636 2.915 4 P 0 8 0;1=3
P 4.38373996 2.17806998 4 P 0 8 0;1=1
P 2.97 3.105 6 P 0 8 0;1=0
P 5.91 2.785 6 P 0 8 0;1=0
P 5.91 2.615 5 P 0 8 0;1=7
P 5.91 2.915 6 P 0 8 0;1=0
P 5.91 2.715 6 P 0 8 0;1=0
P 0.54 2.135 6 P 0 8 0;1=2
P 0.67 1.09 6 P 0 8 0;1=0
P 4.61996004 1.66626998 4 P 0 8 0;1=1
P 0.45 2.13 6 P 0 8 0;1=2
P 4.6987 2.09933002 4 P 0 8 0;1=1
P 0.965 2.355 6 P 0 8 0;1=0
P 4.5806 1.70563996 4 P 0 8 0;1=1
P 0.735 1.125 6 P 0 8 0;1=0
P 0.48231998 2.6453 6 P 0 8 0;1=2
P 3.755 3.505 5 P 0 8 0;1=9
P 4.6987 2.1387 4 P 0 8 0;1=1
P 0.525 2.78 6 P 0 8 0;1=2
P 4.6 0.76 6 P 0 8 0;1=2
P 4.61996004 1.78436998 4 P 0 8 0;1=1
P 0.905 1.05 6 P 0 8 0;1=2
P 4.175 0.75 6 P 0 8 0;1=2
P 0.51765 0.966 3 P 0 8 0;1=4
P 2.078 0.8301 6 P 0 8 0;1=2
P 0.46 0.82 3 P 0 8 0;1=4
P 4.65933002 1.78436998 4 P 0 8 0;1=1
P 0.5413 1.525 6 P 0 8 0;1=0
P 4.61996004 1.70563996 4 P 0 8 0;1=1
P 0.625 1.005 6 P 0 8 0;1=2
P 4.65933002 1.70563996 4 P 0 8 0;1=1
P 0.935 1.105 6 P 0 8 0;1=0
P 0.4839 1.28311998 6 P 0 8 0;1=2
P 1.128 0.666 3 P 0 8 0;1=4
P 5.97613002 4.27558002 6 P 0 8 0;1=0
P 4.14753002 1.86311004 4 P 0 8 0;1=1
P 0.945 1.63 6 P 0 8 0;1=2
P 0.635 0.845 4 P 0 8 0;1=3
P 4.1869 1.86311004 4 P 0 8 0;1=1
P 0.975 1.72 6 P 0 8 0;1=2
P 0.644 0.7 4 P 0 8 0;1=3
P 0.555 0.59 6 P 0 8 0;1=0
P 3.935 3.91 5 P 0 8 0;1=7
P 0.835 1.885 6 P 0 8 0;1=2
P 3.885 3.91 5 P 0 8 0;1=7
P 0.835 1.93 6 P 0 8 0;1=2
P 3.985 3.91 5 P 0 8 0;1=7
P 0.835 1.78 6 P 0 8 0;1=2
P 0.645 1.295 4 P 0 8 0;1=3
P 4.1869 1.90248002 4 P 0 8 0;1=1
P 0.955 1.92 6 P 0 8 0;1=2
P 0.565 1.13 4 P 0 8 0;1=3
P 4.14753002 1.90248002 4 P 0 8 0;1=1
P 0.885 1.49 6 P 0 8 0;1=0
P 0.99 1.755 6 P 0 8 0;1=2
P 3.935 4 5 P 0 8 0;1=9
P 0.332 2.62508002 6 P 0 8 0;1=0
P 3.885 4 5 P 0 8 0;1=9
P 0.405 2.62 6 P 0 8 0;1=0
P 3.985 4 5 P 0 8 0;1=9
P 0.19 2.625 6 P 0 8 0;1=0
P 0.62 1.995 4 P 0 8 0;1=3
P 4.34436998 1.82373996 4 P 0 8 0;1=1
P 0.75 1.417 6 P 0 8 0;1=2
P 4.26563996 1.82373996 4 P 0 8 0;1=1
P 0.952 1.51 6 P 0 8 0;1=0
P 0.545 1.71 4 P 0 8 0;1=3
P 0.415 1.275 6 P 0 8 0;1=2
P 0.87 1.2 6 P 0 8 0;1=2
P 0.7558 4.19003996 5 P 0 8 0;1=7
P 3.98 4.185 5 P 0 8 0;1=9
P 0.465 1.33 6 P 0 8 0;1=2
P 0.87 1.3 6 P 0 8 0;1=2
P 0.705 4.19 5 P 0 8 0;1=7
P 4.03 4.185 5 P 0 8 0;1=9
P 0.41408996 1.32591004 6 P 0 8 0;1=2
P 0.89 1.105 6 P 0 8 0;1=2
P 0.805 4.205 6 P 0 8 0;1=0
P 3.93 4.185 5 P 0 8 0;1=9
P 0.647 2.517 4 P 0 8 0;1=3
P 4.22626998 1.82373996 4 P 0 8 0;1=1
P 0.939 1.552 6 P 0 8 0;1=2
P 0.575 2.265 4 P 0 8 0;1=3
P 4.22626998 1.86311004 4 P 0 8 0;1=1
P 0.957 2.275 6 P 0 8 0;1=0
P 4.168 4.24 5 P 0 8 0;1=9
P 0.855 4.205 5 P 0 8 0;1=9
P 0.15 2.79 6 P 0 8 0;1=0
P 0.326 1.487 6 P 0 8 0;1=2
P 0.09 2.86 6 P 0 8 0;1=0
P 0.9 4.205 5 P 0 8 0;1=9
P 4.22336998 4.24 5 P 0 8 0;1=9
P 0.416 1.48798002 6 P 0 8 0;1=2
P 0.09 2.79 6 P 0 8 0;1=0
P 0.98 4.2 5 P 0 8 0;1=9
P 4.14 4.19 5 P 0 8 0;1=9
P 0.191 1.48798002 6 P 0 8 0;1=2
P 4.10463002 3.83 5 P 0 8 0;1=7
P 0.33 3.145 6 P 0 8 0;1=2
P 4.05463002 3.83 5 P 0 8 0;1=7
P 0.43 3.145 6 P 0 8 0;1=2
P 4.15463002 3.83 5 P 0 8 0;1=7
P 0.18 3.145 6 P 0 8 0;1=2
P 0.869 2.672 6 P 0 8 0;1=2
P 0.871 2.713 3 P 0 8 0;1=4
P 0.686 2.74 5 P 0 8 0;1=9
P 0.64248002 2.58 6 P 0 8 0;1=2
P 0.736 2.525 5 P 0 8 0;1=9
P 0.714 2.329 6 P 0 8 0;1=2
P 3.429 2.468 3 P 0 8 0;1=4
P 3.51 2.33243002 6 P 0 8 0;1=2
P 3.278 2.468 3 P 0 8 0;1=4
P 3.243 2.547 3 P 0 8 0;1=4
P 3.385 2.135 4 P 0 8 0;1=3
P 3.24 2.36 3 P 0 8 0;1=4
P 3.285 2.38645 3 P 0 8 0;1=4
P 0.832 2.603 6 P 0 8 0;1=0
P 0.77963996 2.601 3 P 0 8 0;1=4
P 0.695 2.578 6 P 0 8 0;1=0
P 0.72 2.714 3 P 0 8 0;1=4
P 0.825 2.732 3 P 0 8 0;1=4
P 6.01953002 2.18853002 6 P 0 8 0;1=0
P 4.415 2.975 3 P 0 8 0;1=4
P 6.09423996 4.27558002 6 P 0 8 0;1=0
P 0.959 2.789 6 P 0 8 0;1=2
P 0.845 2.18 6 P 0 8 0;1=0
P 5.955 2.39 4 P 0 8 0;1=3
P 5.94153002 2.205 5 P 0 8 0;1=7
P 6.01901998 2.001 5 P 0 8 0;1=7
P 5.87 1.84 4 P 0 8 0;1=3
P 3.4593 2.17 5 P 0 8 0;1=7
P 3.44 2.12 6 P 0 8 0;1=0
P 4.34436998 1.94185 4 P 0 8 0;1=1
P 3.18 2.685 3 P 0 8 0;1=4
P 3.523 1.75 5 P 0 8 0;1=9
P 4.712 1.157 4 P 0 8 0;1=3
P 4.42311004 1.50878996 4 P 0 8 0;1=1
P 4.61996004 1.6269 4 P 0 8 0;1=3
P 4.29 1.235 4 P 0 8 0;1=3
P 4.38373996 1.46941998 4 P 0 8 0;1=1
P 4.15 1.235 4 P 0 8 0;1=3
P 4.34436998 1.50878996 4 P 0 8 0;1=1
P 5.035 1.49 4 P 0 8 0;1=3
P 4.65933002 1.58753002 4 P 0 8 0;1=1
P 4.185 1.17 4 P 0 8 0;1=3
P 4.34436998 1.46941998 4 P 0 8 0;1=1
P 4.816 1.258 4 P 0 8 0;1=3
P 4.665 1.104 4 P 0 8 0;1=3
P 4.38373996 1.3513 4 P 0 8 0;1=1
P 4.91 1.54 4 P 0 8 0;1=3
P 4.768 1.207 4 P 0 8 0;1=3
P 4.42311004 1.46941998 4 P 0 8 0;1=1
P 5.03 1.55 4 P 0 8 0;1=3
P 4.58058996 1.6269 4 P 0 8 0;1=1
P 4.828 1.103 4 P 0 8 0;1=3
P 4.42311004 1.43005 4 P 0 8 0;1=1
P 4.83 1.33 4 P 0 8 0;1=3
P 4.22 1.235 4 P 0 8 0;1=3
P 3.83128002 1.78371998 5 P 0 8 0;1=9
P 6.02558996 4.175 6 P 0 8 0;1=0
P 6.1437 4.175 6 P 0 8 0;1=0
P 3.87193002 1.86311004 4 P 0 8 0;1=1
P 4.14753002 2.05996004 4 P 0 8 0;1=1
P 5.83 2.97 6 P 0 8 0;1=2
P 5.89953002 2.366 5 P 0 8 0;1=7
P 3.61123996 3.49876004 3 P 0 8 0;1=4
P 4.54121998 1.94185 4 P 0 8 0;1=1
P 4.22626998 1.94185 4 P 0 8 0;1=1
P 1.96496998 0.76501998 5 P 0 8 0;1=7
P 4.1869 1.98121998 4 P 0 8 0;1=1
P 3.12 2.565 6 P 0 8 0;1=2
P 3.119 2.299 6 P 0 8 0;1=0
P 4.26563996 1.90248002 4 P 0 8 0;1=1
P 3.385 2.59 6 P 0 8 0;1=0
P 5.155 2.01 6 P 0 8 0;1=2
P 6.025 1.83 6 P 0 8 0;1=0
P 4.1869 2.05996004 4 P 0 8 0;1=1
P 4.34436998 1.90248002 4 P 0 8 0;1=1
P 2.554 2.901 6 P 0 8 0;1=0
P 4.75 1.63 4 P 0 8 0;1=5
P 3.205 1.7 6 P 0 8 0;1=0
P 4.775 1.705 6 P 0 8 0;1=2
P 4.84 1.855 6 P 0 8 0;1=0
P 4.58058996 1.82373996 4 P 0 8 0;1=1
P 4.65933002 1.86311004 4 P 0 8 0;1=1
P 4.815 1.93 6 P 0 8 0;1=0
P 4.885 3.46 6 P 0 8 0;1=2
P 4.61996004 1.86311004 4 P 0 8 0;1=1
P 4.83501004 3.46 6 P 0 8 0;1=0
P 3.125 2.254 6 P 0 8 0;1=2
P 4.26563996 1.86311004 4 P 0 8 0;1=5
P 3.12 2.69 6 P 0 8 0;1=2
P 4.565 3.055 6 P 0 8 0;1=2
P 4.3 3.81 6 P 0 8 0;1=0
P 1.3825 3.7225 5 P 0 8 0;1=9
P 5.905 3.015 5 P 0 8 0;1=7
P 5.41 0.96 4 P 0 8 0;1=3
P 4.85033002 1.74933996 6 P 0 8 0;1=2
P 4.54121998 1.78436998 4 P 0 8 0;1=1
P 5.26 2.955 6 P 0 8 0;1=2
P 3.625 0.92 4 P 0 8 0;1=8
P 6.19961004 2.27673996 4 P 0 8 0;1=8
P 3.657 0.92 4 P 0 8 0;1=8
P 6.19961004 2.24473996 4 P 0 8 0;1=8
P 3.3255 2.1355 6 P 0 8 0;1=0
P 3.35153002 2.17875 6 P 0 8 0;1=2
P 3.44 2.95 3 P 0 8 0;1=4
P 3.27923002 2.21576998 6 P 0 8 0;1=2
P 3.3435 2.82 3 P 0 8 0;1=4
P 4.46 2.94 6 P 0 8 0;1=0
P 4.47 2.83 6 P 0 8 0;1=0
P 3.222 3.385 5 P 0 8 0;1=9
P 3.98 3.365 6 P 0 8 0;1=2
P 3.7 3.37 6 P 0 8 0;1=2
P 3.55 3.37 6 P 0 8 0;1=2
P 4.175 3.37 6 P 0 8 0;1=2
P 3.71 3.26 6 P 0 8 0;1=2
P 3.55 3.28 5 P 0 8 0;1=9
P 3.414 3.235 6 P 0 8 0;1=2
P 3.795 2.375 6 P 0 8 0;1=2
P 3.99005 2.02058996 4 P 0 8 0;1=1
P 4.34436998 1.86311004 4 P 0 8 0;1=1
P 4.02941998 1.90248002 4 P 0 8 0;1=1
P 3.855 1.96153996 4 P 0 8 0;1=1
P 3.9113 1.86311004 4 P 0 8 0;1=1
P 4.06878996 1.78436998 4 P 0 8 0;1=1
P 4.1869 1.82373996 4 P 0 8 0;1=1
P 3.86 2.5925 6 P 0 8 0;1=2
P 3.758 2.552 6 P 0 8 0;1=2
P 3.735 2.47 6 P 0 8 0;1=2
P 5.0395 1.335 6 P 0 8 0;1=2
P 3.839 3.846 6 P 0 8 0;1=2
P 4.384 3.824 6 P 0 8 0;1=2
P 4.95 3.46 6 P 0 8 0;1=2
P 5.19 3.075 6 P 0 8 0;1=2
P 5.375 3.04 6 P 0 8 0;1=2
P 5.41 2.815 6 P 0 8 0;1=2
P 5.544 2.675 6 P 0 8 0;1=2
P 5.62 2.5487 6 P 0 8 0;1=2
P 5.42 2.9645 6 P 0 8 0;1=2
P 4.43 3.865 5 P 0 8 0;1=9
P 5.221 4.165 6 P 0 8 0;1=2
P 4.32 3.965 5 P 0 8 0;1=9
P 4.535 3.815 6 P 0 8 0;1=2
P 4.509 3.309 6 P 0 8 0;1=2
P 4.235 4.155 6 P 0 8 0;1=2
P 4.505 3.685 6 P 0 8 0;1=2
P 5.975 4.219 6 P 0 8 0;1=2
P 5.84 4.219 6 P 0 8 0;1=2
P 4.655 0.785 6 P 0 8 0;1=2
P 4.635 0.92 6 P 0 8 0;1=2
P 5.249 0.99 6 P 0 8 0;1=2
P 5.33 0.82 6 P 0 8 0;1=2
P 2.0477 0.6778 6 P 0 8 0;1=2
P 0.78 2.915 6 P 0 8 0;1=2
P 0.674 2.271 6 P 0 8 0;1=2
P 0.857 2.365 6 P 0 8 0;1=2
P 0.677 2.402 6 P 0 8 0;1=2
P 6.04 3.98 6 P 0 8 0;1=2
P 3.795 4.175 6 P 0 8 0;1=2
P 3.66 3.5085 6 P 0 8 0;1=2
P 3.105 3.21 6 P 0 8 0;1=2
P 5.55 4.02 6 P 0 8 0;1=2
P 5.01 2.635 6 P 0 8 0;1=0
P 5 2.78798996 5 P 0 8 0;1=7
P 5.226 2.762 5 P 0 8 0;1=7
P 5.765 0.98 4 P 0 8 0;1=3
P 1.385 3.875 5 P 0 8 0;1=7
P 5.31 2.855 6 P 0 8 0;1=2
P 4.608 2.942 6 P 0 8 0;1=2
P 4.25 3.81 6 P 0 8 0;1=2
P 5.345 2.536 4 P 0 8 0;1=3
P 5.224 2.707 5 P 0 8 0;1=7
P 5.005 2.711 5 P 0 8 0;1=7
P 3.793 3.05 3 P 0 8 0;1=4
P 3.96981004 3.04481998 6 P 0 8 0;1=0
P 3.948 2.813 6 P 0 8 0;1=0
P 4.831 2.728 4 P 0 8 0;1=3
P 3.55 1.415 6 P 0 8 0;1=2
P 3.525 1.415 6 P 0 8 0;1=2
P 3.5 1.415 6 P 0 8 0;1=2
P 3.475 1.415 6 P 0 8 0;1=2
P 3.655 2.795 4 P 0 8 0;1=3
P 3.745 2.76 6 P 0 8 0;1=2
P 3.7 2.76 6 P 0 8 0;1=2
P 3.822 2.81 6 P 0 8 0;1=2
P 3.78 2.81 6 P 0 8 0;1=2
P 3.894 2.811 6 P 0 8 0;1=0
P 3.916 3.048 3 P 0 8 0;1=4
P 5.589 2.025 6 P 0 8 0;1=0
P 5.546 2.024 6 P 0 8 0;1=2
P 5.69943002 2.233 6 P 0 8 0;1=0
P 5.48158002 2.28033002 5 P 0 8 0;1=7
P 4.50185 1.66626998 4 P 0 8 0;1=1
P 4.42311004 1.66626998 4 P 0 8 0;1=1
P 4.38373996 1.70563996 4 P 0 8 0;1=1
P 4.26563996 1.70563996 4 P 0 8 0;1=1
P 4.14753002 1.66626998 4 P 0 8 0;1=1
P 4.1869 1.70563996 4 P 0 8 0;1=1
P 4.50185 1.58753002 4 P 0 8 0;1=1
P 4.46248002 1.6269 4 P 0 8 0;1=1
P 4.46248002 1.54816004 4 P 0 8 0;1=1
P 4.38373996 1.54816004 4 P 0 8 0;1=1
P 4.42311004 1.58753002 4 P 0 8 0;1=1
P 4.34436998 1.58753002 4 P 0 8 0;1=1
P 4.26563996 1.54816004 4 P 0 8 0;1=1
P 4.22626998 1.58753002 4 P 0 8 0;1=1
P 4.14753002 1.58753002 4 P 0 8 0;1=1
P 4.1869 1.6269 4 P 0 8 0;1=1
P 4.1869 1.54816004 4 P 0 8 0;1=1
P 5.145 1.57 6 P 0 8 0;1=2
P 5.145 1.54 6 P 0 8 0;1=2
P 5.145 1.44 6 P 0 8 0;1=0
P 5.145 1.48 6 P 0 8 0;1=2
P 5.145 1.51 6 P 0 8 0;1=2
P 5.76 2.465 4 P 0 8 0;1=3
P 4.2136 3.5997 3 P 0 8 0;1=4
P 3.755 3.092 6 P 0 8 0;1=2
P 3.99005 1.66626998 4 P 0 8 0;1=1
P 4.06878996 1.54816004 4 P 0 8 0;1=1
P 4.06878996 1.6269 4 P 0 8 0;1=1
P 4.02941998 1.58753002 4 P 0 8 0;1=1
P 3.99005 1.50878996 4 P 0 8 0;1=1
P 3.679 1.54228002 6 P 0 8 0;1=2
P 3.714 1.543 6 P 0 8 0;1=2
P 3.784 1.543 6 P 0 8 0;1=2
P 3.749 1.54228002 6 P 0 8 0;1=2
P 3.605 1.545 6 P 0 8 0;1=2
P 3.50085 1.543 6 P 0 8 0;1=2
P 3.53481998 1.54156998 6 P 0 8 0;1=2
P 3.57 1.542 6 P 0 8 0;1=2
P 5.4227 1.724 6 P 0 8 0;1=2
P 5.3977 1.724 6 P 0 8 0;1=2
P 5.58 1.615 4 P 0 8 0;1=3
P 5.3977 1.699 6 P 0 8 0;1=2
P 5.3977 1.749 6 P 0 8 0;1=2
P 5.4227 1.699 6 P 0 8 0;1=2
P 5.4352 1.7497 6 P 0 8 0;1=2
P 5.654 2.447 6 P 0 8 0;1=2
P 5.667 2.275 5 P 0 8 0;1=7
P 5.595 2.28 5 P 0 8 0;1=7
P 5.483 2.226 6 P 0 8 0;1=0
P 5.6695 2.2 6 P 0 8 0;1=2
P 5.771 2.279 5 P 0 8 0;1=7
P 5.789 2.366 6 P 0 8 0;1=2
P 5.6 2.4 6 P 0 8 0;1=2
P 5.6 4.01 4 P 0 8 0;1=3
P 5.55568996 3.88051004 3 P 0 8 0;1=4
P 5.765 2.197 6 P 0 8 0;1=0
P 5.71 2.179 6 P 0 8 0;1=2
P 5.41 2.164 6 P 0 8 0;1=0
P 5.458 2.165 6 P 0 8 0;1=2
P 5.465 2.405 6 P 0 8 0;1=2
P 5.53121998 2.27978996 5 P 0 8 0;1=7
P 3.817 0.924 5 P 0 8 0;1=7
P 4.25 0.877 6 P 0 8 0;1=0
P 5.495 0.694 5 P 0 8 0;1=7
P 5.49 0.635 6 P 0 8 0;1=0
P 5.725 0.60301004 5 P 0 8 0;1=7
P 5.686 0.76 5 P 0 8 0;1=7
P 5.7287 0.6757 5 P 0 8 0;1=7
P 5.38558002 4.13778996 6 P 0 8 0;1=0
P 5.485 4.11 6 P 0 8 0;1=0
P 5.725 4.135 6 P 0 8 0;1=0
P 5.6218 4.13778996 6 P 0 8 0;1=0
P 5.323 4.257 5 P 0 8 0;1=7
P 3.83 3.335 3 P 0 8 0;1=4
P 3.415 3.285 3 P 0 8 0;1=4
P 3.83 3.285 3 P 0 8 0;1=4
P 3.415 3.385 3 P 0 8 0;1=4
P 4.83871004 1.98241004 6 P 0 8 0;1=0
P 4.80288002 2.03788002 6 P 0 8 0;1=0
P 4.97 3.41 6 P 0 8 0;1=0
P 4.38373996 1.90248002 4 P 0 8 0;1=1
P 4.81 3.41 6 P 0 8 0;1=2
P 4.42311004 2.09933002 4 P 0 8 0;1=5
P 3.48863002 4.105 6 P 0 8 0;1=0
P 2.987 3.235 5 P 0 8 0;1=9
P 0.7595 1.642 5 P 0 8 0;1=7
P 2.987 3.27 5 P 0 8 0;1=9
P 0.761 1.544 5 P 0 8 0;1=7
P 4.54121998 1.82373996 4 P 0 8 0;1=1
P 4.79246004 1.78463996 6 P 0 8 0;1=0
P 4.54121998 2.17806998 4 P 0 8 0;1=5
P 0.955 1.455 6 P 0 8 0;1=0
P 1.512 0.75191004 6 P 0 8 0;1=2
P 1.8091 0.6339 5 P 0 8 0;1=7
P 1.459 0.752 5 P 0 8 0;1=9
P 0.905 1.445 6 P 0 8 0;1=2
P 2.40508002 0.731 5 P 0 8 0;1=9
P 4.06878996 1.66626998 3 P 0 8 0;1=11
P 2.40508002 0.699 5 P 0 8 0;1=9
P 4.02941998 1.66626998 3 P 0 8 0;1=11
P 4.4085 1.16598996 5 P 0 8 0;1=9
P 4.46248002 1.43005 3 P 0 8 0;1=11
P 4.3765 1.16598996 5 P 0 8 0;1=9
P 4.50185 1.43005 3 P 0 8 0;1=11
P 4.0485 1.16098996 5 P 0 8 0;1=9
P 4.06878996 1.50878996 3 P 0 8 0;1=11
P 4.0165 1.16098996 5 P 0 8 0;1=9
P 4.02941998 1.50878996 3 P 0 8 0;1=11
P 4.82 2.125 4 P 0 8 0;1=3
P 4.38373996 1.78436998 4 P 0 8 0;1=1
P 3.54663996 1.04706998 5 P 0 8 0;1=9
P 4.6987 1.46941998 3 P 0 8 0;1=11
P 3.51463996 1.04706998 5 P 0 8 0;1=9
P 4.73806998 1.46941998 3 P 0 8 0;1=11
P 3.44998996 1.085 5 P 0 8 0;1=9
P 4.73806998 1.39066998 3 P 0 8 0;1=11
P 3.41798996 1.085 5 P 0 8 0;1=9
P 4.73806998 1.3513 3 P 0 8 0;1=11
P 3.445 1.815 6 P 0 8 0;1=2
P 4.58058996 1.90248002 4 P 0 8 0;1=1
P 4.65933002 1.94185 4 P 0 8 0;1=1
P 4.785 3.46 6 P 0 8 0;1=0
P 4.54121998 1.6269 4 P 0 8 0;1=1
P 4.9097 1.385 5 P 0 8 0;1=7
P 4.54121998 1.66626998 4 P 0 8 0;1=1
P 4.84 1.66 6 P 0 8 0;1=0
P 4.81 1.725 6 P 0 8 0;1=0
P 3.375 1.194 5 P 0 8 0;1=9
P 4.5413 1.22166998 5 P 0 8 0;1=9
P 4.61996004 1.31193002 3 P 0 8 0;1=11
P 3.375 1.162 5 P 0 8 0;1=9
P 4.5733 1.22166998 5 P 0 8 0;1=9
P 4.65933002 1.31193002 3 P 0 8 0;1=11
P 5.3 4.065 4 P 0 8 0;1=3
P 4.10816004 1.70563996 4 P 0 8 0;1=1
P 4.365 2.33 6 P 0 8 0;1=2
P 4.38373996 2.02058996 4 P 0 8 0;1=5
P 4.38373996 2.05996004 4 P 0 8 0;1=1
P 4.485 2.375 6 P 0 8 0;1=0
P 4.38373996 2.09933002 4 P 0 8 0;1=1
P 4.54121998 1.58753002 4 P 0 8 0;1=1
P 4.9097 1.335 5 P 0 8 0;1=7
P 4.26563996 1.78436998 4 P 0 8 0;1=1
P 4.365 2.375 6 P 0 8 0;1=0
P 3.465 1.74 6 P 0 8 0;1=2
P 3.44 1.03 6 P 0 8 0;1=0
P 6.285 1.895 6 P 0 8 0;1=2
P 6.258 2.15873996 5 P 0 8 0;1=9
P 6.275 2.05373996 6 P 0 8 0;1=2
P 6.335 2.05906004 5 P 0 8 0;1=7
P 1.77 3.98 6 P 0 8 0;1=0
P 1.75 3.945 6 P 0 8 0;1=2
P 1.5315 3.9459 5 P 0 8 0;1=7
P 1.517 4.113 6 P 0 8 0;1=0
P 1.511 3.863 5 P 0 8 0;1=7
P 1.5153 4.063 5 P 0 8 0;1=7
P 1.521 3.993 5 P 0 8 0;1=7
P 1.579 3.874 6 P 0 8 0;1=0
P 1.585 4.052 6 P 0 8 0;1=2
P 1.435 4.18 6 P 0 8 0;1=2
P 1.522 4.163 5 P 0 8 0;1=7
P 1.4 4.01 6 P 0 8 0;1=2
P 5.14 3.74 6 P 0 8 0;1=2
P 5.175 3.74 6 P 0 8 0;1=2
P 5.18 3.825 6 P 0 8 0;1=2
P 5.675 4.03 6 P 0 8 0;1=2
P 1.56 3.29 6 P 0 8 0;1=2
P 1.56 3.25 6 P 0 8 0;1=2
P 3.245 2.955 6 P 0 8 0;1=2
P 3.21 2.955 6 P 0 8 0;1=2
P 3.175 2.955 6 P 0 8 0;1=2
P 2.59 3.445 6 P 0 8 0;1=2
P 2.55 3.445 6 P 0 8 0;1=2
P 2.51 3.445 6 P 0 8 0;1=2
P 2.47 3.445 6 P 0 8 0;1=2
P 2.2 3.96 6 P 0 8 0;1=2
P 2.25 3.96 4 P 0 8 0;1=3
P 1.351 4.126 6 P 0 8 0;1=2
P 2.165 3.96 6 P 0 8 0;1=2
P 2.155 3.925 6 P 0 8 0;1=2
P 2.19 3.925 6 P 0 8 0;1=2
P 3.23 4.015 6 P 0 8 0;1=0
P 3.2 3.985 6 P 0 8 0;1=2
P 5.9065 2.4568 6 P 0 8 0;1=2
P 3.745 4.185 4 P 0 8 0;1=3
P 3.47 3.912 6 P 0 8 0;1=0
P 3.69 4.135 4 P 0 8 0;1=3
P 3.48278996 4.05678002 6 P 0 8 0;1=2
P 3.476 3.988 6 P 0 8 0;1=0
P 3.437 4.099 6 P 0 8 0;1=0
P 3.598 3.977 6 P 0 8 0;1=2
P 3.477 3.816 6 P 0 8 0;1=0
P 3.405 3.916 6 P 0 8 0;1=2
P 5.68326004 3.712 6 P 0 8 0;1=0
P 5.686 3.807 6 P 0 8 0;1=0
P 5.50643002 4.009 3 P 0 8 0;1=4
P 5.686 3.76 6 P 0 8 0;1=0
P 5.675 3.865 6 P 0 8 0;1=0
P 5.718 3.965 4 P 0 8 0;1=3
P 6.05315 3.67518996 20 P 0 8 0;1=12
P 6.05315 3.50983996 20 P 0 8 0;1=13
P 6.05315 3.34448996 20 P 0 8 0;1=13
P 0.828 3.846 6 P 0 8 0;1=2
P 5.66 3.47 4 P 0 8 0;1=3
P 5.68 3.567 3 P 0 8 0;1=4
P 5.406 3.863 6 P 0 8 0;1=0
P 3.46 4.16 6 P 0 8 0;1=2
P 3.495 4.15 6 P 0 8 0;1=2
P 3.5 4.195 6 P 0 8 0;1=2
P 3.53 4.165 6 P 0 8 0;1=2
P 5.769 4.031 6 P 0 8 0;1=2
P 5.644 3.967 6 P 0 8 0;1=0
P 5.803 3.907 6 P 0 8 0;1=2
P 1.45 3.78 6 P 0 8 0;1=2
P 1.485 3.76 5 P 0 8 0;1=7
P 1.485 3.8 6 P 0 8 0;1=2
P 5.406 2.346 4 P 0 8 0;1=3
P 5.375 2.32 6 P 0 8 0;1=2
P 5.34 2.315 6 P 0 8 0;1=2
P 5.43 3.6 6 P 0 8 0;1=0
P 5.433 3.651 6 P 0 8 0;1=2
P 5.43 3.7 6 P 0 8 0;1=2
P 5.39 3.6 6 P 0 8 0;1=2
P 5.393 3.651 6 P 0 8 0;1=2
P 5.39 3.7 6 P 0 8 0;1=2
P 1.6055 4.134 6 P 0 8 0;1=2
P 1.60581998 4.1 6 P 0 8 0;1=2
P 1.606 4.174 5 P 0 8 0;1=7
P 1.636 3.786 6 P 0 8 0;1=2
P 1.591 3.826 6 P 0 8 0;1=2
P 1.633 3.829 5 P 0 8 0;1=7
P 3.408 4.152 6 P 0 8 0;1=2
P 3.363 4.192 6 P 0 8 0;1=2
P 3.363 4.152 6 P 0 8 0;1=2
P 3.363 4.232 6 P 0 8 0;1=0
P 3.393 3.877 6 P 0 8 0;1=2
P 3.393 3.84 6 P 0 8 0;1=2
P 3.392 3.803 6 P 0 8 0;1=2
P 3.607 4.062 6 P 0 8 0;1=2
P 1.352 4.084 6 P 0 8 0;1=0
P 1.95 0.5455 5 P 0 8 0;1=7
P 5.681 3.617 6 P 0 8 0;1=0
P 5.681 3.664 6 P 0 8 0;1=0
P 5.40318002 2.70436004 5 P 0 8 0;1=7
P 0.55921998 1.40543002 6 P 0 8 0;1=0
P 0.57 0.835 6 P 0 8 0;1=0
P 3.584 1.827 5 P 0 8 0;1=7
P 1.535 3.905 5 P 0 8 0;1=9
P 1.98135 0.365 5 P 0 8 0;1=9
P 1.7317 0.7084 6 P 0 8 0;1=0
P 1.91535 0.412 5 P 0 8 0;1=9
P 1.8039 0.7072 5 P 0 8 0;1=7
P 3.2271 1.90298996 4 P 0 8 0;1=8
P 3.45301004 1.89898996 4 P 0 8 0;1=8
P 3.2591 1.90298996 4 P 0 8 0;1=8
P 3.45301004 1.93098996 4 P 0 8 0;1=8
P 1.26066998 2.64043002 13 P 0 8 0;1=14
P 5.035 3.945 6 P 0 8 0;1=0
P 5.075 3.945 6 P 0 8 0;1=2
P 2.97771998 1.88693996 6 P 0 8 0;1=2
P 3.00995 1.87611004 6 P 0 8 0;1=2
P 2.86066998 2.64043002 13 P 0 8 0;1=14
P 2.105 0.305 5 P 0 8 0;1=9
P 2.235 0.5825 6 P 0 8 0;1=2
P 3.405 0.635 6 P 0 8 0;1=2
P 5.295 0.605 6 P 0 8 0;1=0
P 5.91 4.04 6 P 0 8 0;1=0
P 2.135 0.54 6 P 0 8 0;1=2
P 5.215 0.6 6 P 0 8 0;1=0
P 6.025 4.04 6 P 0 8 0;1=0
P 3.36 0.6106 6 P 0 8 0;1=2
P 0.96 2.41 6 P 0 8 0;1=2
P 0.68 2.355 6 P 0 8 0;1=2
P 2.38 3.45 6 P 0 8 0;1=2
P 1.41 3.795 6 P 0 8 0;1=2
P 3.445 3.613 6 P 0 8 0;1=2
P 3.365 3.613 6 P 0 8 0;1=0
P 3.25 3.63 6 P 0 8 0;1=2
P 3.325 3.613 6 P 0 8 0;1=2
P 3.405 3.613 6 P 0 8 0;1=2
P 3.48418002 3.613 6 P 0 8 0;1=2
P 3.645 4.135 6 P 0 8 0;1=2
P 3.655 3.059 6 P 0 8 0;1=2
P 3.614 3.099 6 P 0 8 0;1=2
P 3.614 3.058 6 P 0 8 0;1=2
P 3.614 3.015 6 P 0 8 0;1=2
P 5.236 2.811 6 P 0 8 0;1=2
P 4.3305 2.914 6 P 0 8 0;1=15
P 4.3815 2.838 6 P 0 8 0;1=15
P 4.29 2.74 4 P 0 8 0;1=3
P 4.456 2.783 6 P 0 8 0;1=2
P 4.355 2.745 6 P 0 8 0;1=2
P 4.346 2.783 6 P 0 8 0;1=2
P 4.4 2.785 6 P 0 8 0;1=2
P 4 2.655 6 P 0 8 0;1=2
P 5.022 2.407 6 P 0 8 0;1=2
P 4.923 2.408 6 P 0 8 0;1=2
P 4.972 2.406 6 P 0 8 0;1=2
P 4.971 2.447 6 P 0 8 0;1=2
P 5.2871 2.275 6 P 0 8 0;1=2
P 5.62533002 1.02001004 6 P 0 8 0;1=2
P 5.65933002 1.02 6 P 0 8 0;1=2
P 3.804 0.816 5 P 0 8 0;1=9
P 4.23 0.7295 6 P 0 8 0;1=2
P 2.31 0.715 6 P 0 8 0;1=2
P 2.31 0.68 6 P 0 8 0;1=2
P 2.595 0.547 6 P 0 8 0;1=2
P 3.51 2.37 6 P 0 8 0;1=2
P 0.29 2.915 6 P 0 8 0;1=0
P 0.28 2.965 6 P 0 8 0;1=0
P 0.285 3.02 6 P 0 8 0;1=0
P 2.977 3.351 3 P 0 8 0;1=4
P 3.36525 3.255 3 P 0 8 0;1=4
P 3.36525 3.205 3 P 0 8 0;1=4
P 1.8062 0.7789 5 P 0 8 0;1=7
P 3.073 0.613 5 P 0 8 0;1=7
P 2.54526998 0.339 5 P 0 8 0;1=9
P 2.527 0.44 3 P 0 8 0;1=4
P 5.73991004 4.27558002 6 P 0 8 0;1=0
P 5.38558002 4.27558002 6 P 0 8 0;1=0
P 5.50368996 4.27558002 6 P 0 8 0;1=0
P 5.6218 4.27558002 6 P 0 8 0;1=0
P 5.875 1.9 6 P 0 8 0;1=0
P 3.865 3.65 6 P 0 8 0;1=2
P 6.06901998 1.86 6 P 0 8 0;1=0
P 3.81 3.65 6 P 0 8 0;1=2
P 5.97 1.999 5 P 0 8 0;1=7
P 4.62 2.245 6 P 0 8 0;1=2
P 5.801 3.667 6 P 0 8 0;1=2
P 3.8 2.045 6 P 0 8 0;1=2
P 1.275 2.905 6 P 0 8 0;1=2
P 5.061 2.806 6 P 0 8 0;1=2
P 3.995 1.2 6 P 0 8 0;1=2
P 4.07 1.2 6 P 0 8 0;1=2
P 4.0805 1.16098996 5 P 0 8 0;1=9
P 4.092 1.005 5 P 0 8 0;1=9
P 4.135 0.885 6 P 0 8 0;1=2
P 4.13621998 0.75 5 P 0 8 0;1=9
P 4.13401998 0.54196998 5 P 0 8 0;1=9
P 4.09401998 0.54196998 5 P 0 8 0;1=9
P 4.05401998 0.54196998 5 P 0 8 0;1=9
P 4.01401998 0.54196998 5 P 0 8 0;1=9
P 2.985 1.845 6 P 0 8 0;1=2
P 2.845 1.907 5 P 0 8 0;1=9
P 2.845 1.811 5 P 0 8 0;1=9
P 2.822 1.79121004 6 P 0 8 0;1=2
P 2.71 1.845 6 P 0 8 0;1=2
P 2.2 0.69 6 P 0 8 0;1=2
P 2.15 0.69 6 P 0 8 0;1=2
P 1.9216 0.7784 6 P 0 8 0;1=2
P 2.0195 0.2905 5 P 0 8 0;1=9
P 1.91535 0.289 5 P 0 8 0;1=9
P 1.78196004 0.50601004 5 P 0 8 0;1=9
P 1.80341004 0.47225 5 P 0 8 0;1=9
P 1.63543002 0.52158996 5 P 0 8 0;1=9
P 3.65101004 1.85158996 5 P 0 8 0;1=9
P 3.45301004 1.86698996 5 P 0 8 0;1=9
P 3.473 1.79 6 P 0 8 0;1=2
P 3.1951 1.90298996 5 P 0 8 0;1=9
P 3.2911 1.90298996 5 P 0 8 0;1=9
P 2.958 0.289 5 P 0 8 0;1=9
P 2.88056998 0.289 5 P 0 8 0;1=9
P 2.95835 0.321 5 P 0 8 0;1=9
P 2.80051998 0.289 5 P 0 8 0;1=9
P 2.80086998 0.321 5 P 0 8 0;1=9
P 2.63506998 0.763 5 P 0 8 0;1=9
P 2.78655 0.763 5 P 0 8 0;1=9
P 2.73106998 0.763 5 P 0 8 0;1=9
P 2.7233 0.54871004 6 P 0 8 0;1=2
P 2.64338996 0.417 5 P 0 8 0;1=9
P 2.72308996 0.289 5 P 0 8 0;1=9
P 2.64303996 0.289 5 P 0 8 0;1=9
P 2.64338996 0.321 5 P 0 8 0;1=9
P 2.53421998 0.763 5 P 0 8 0;1=9
P 2.595 0.701 6 P 0 8 0;1=2
P 2.44618996 0.289 5 P 0 8 0;1=9
P 2.54526998 0.289 5 P 0 8 0;1=9
P 2.43821998 0.763 5 P 0 8 0;1=9
P 2.40508002 0.667 5 P 0 8 0;1=9
P 2.40508002 0.763 5 P 0 8 0;1=9
P 2.327 0.291 5 P 0 8 0;1=9
P 3.56 1.305 6 P 0 8 0;1=2
P 3.535 1.305 6 P 0 8 0;1=2
P 3.51 1.305 6 P 0 8 0;1=2
P 3.54 1.28 6 P 0 8 0;1=2
P 3.57863996 1.04706998 5 P 0 8 0;1=9
P 3.593 0.92 5 P 0 8 0;1=9
P 3.65401998 0.54196998 5 P 0 8 0;1=9
P 3.61401998 0.54196998 5 P 0 8 0;1=9
P 3.57401998 0.54196998 5 P 0 8 0;1=9
P 3.53401998 0.54196998 5 P 0 8 0;1=9
P 3.49401998 0.54196998 5 P 0 8 0;1=9
P 3.375 1.226 5 P 0 8 0;1=9
P 3.375 1.13 5 P 0 8 0;1=9
P 3.48263996 1.04706998 5 P 0 8 0;1=9
P 3.48198996 1.085 5 P 0 8 0;1=9
P 3.38598996 1.085 5 P 0 8 0;1=9
P 3.33401998 0.54196998 5 P 0 8 0;1=9
P 3.45401998 0.54196998 5 P 0 8 0;1=9
P 3.41401998 0.54196998 5 P 0 8 0;1=9
P 3.37401998 0.54196998 5 P 0 8 0;1=9
P 3.17025 0.82975 5 P 0 8 0;1=9
P 3.17401998 0.54196998 5 P 0 8 0;1=9
P 3.21401998 0.54196998 5 P 0 8 0;1=9
P 3.25401998 0.54196998 5 P 0 8 0;1=9
P 3.29401998 0.54196998 5 P 0 8 0;1=9
P 3.10236998 0.89763002 5 P 0 8 0;1=9
P 3.035 0.694 6 P 0 8 0;1=2
P 2.98726004 0.49471004 5 P 0 8 0;1=9
P 2.98726004 0.43528996 5 P 0 8 0;1=9
P 3.07708002 0.289 5 P 0 8 0;1=9
P 2.88255 0.763 5 P 0 8 0;1=9
P 2.95835 0.417 5 P 0 8 0;1=9
P 2.80086998 0.417 5 P 0 8 0;1=9
P 3.9845 1.16098996 5 P 0 8 0;1=9
P 3.9 1.005 5 P 0 8 0;1=9
P 3.964 1.005 5 P 0 8 0;1=7
P 3.97401998 0.54196998 5 P 0 8 0;1=9
P 3.93401998 0.54196998 5 P 0 8 0;1=9
P 3.89401998 0.54196998 5 P 0 8 0;1=9
P 3.85401998 0.54196998 5 P 0 8 0;1=9
P 3.798 1.771 6 P 0 8 0;1=2
P 3.647 1.694 6 P 0 8 0;1=2
P 3.676 1.693 6 P 0 8 0;1=2
P 3.718 1.32 6 P 0 8 0;1=2
P 3.743 1.32 6 P 0 8 0;1=2
P 3.718 1.29 6 P 0 8 0;1=2
P 3.743 1.29 6 P 0 8 0;1=2
P 3.67 1.26 6 P 0 8 0;1=2
P 3.84 1.095 6 P 0 8 0;1=2
P 3.84 1.0298 6 P 0 8 0;1=2
P 3.76838002 1.0023 6 P 0 8 0;1=2
P 3.735 0.94 5 P 0 8 0;1=9
P 3.689 0.92 5 P 0 8 0;1=9
P 3.805 0.774 5 P 0 8 0;1=9
P 3.735 0.78 5 P 0 8 0;1=9
P 3.795 0.725 5 P 0 8 0;1=7
P 3.81401998 0.54196998 5 P 0 8 0;1=9
P 3.77401998 0.54196998 5 P 0 8 0;1=9
P 3.73401998 0.54196998 5 P 0 8 0;1=9
P 3.69401998 0.54196998 5 P 0 8 0;1=9
P 3.551 1.694 6 P 0 8 0;1=2
P 3.576 1.694 6 P 0 8 0;1=2
P 3.526 1.694 6 P 0 8 0;1=2
P 3.501 1.694 6 P 0 8 0;1=2
P 3.636 1.766 6 P 0 8 0;1=2
P 2.86066998 1.04043002 13 P 0 8 0;1=14
P 4.6053 1.22166998 5 P 0 8 0;1=9
P 1.041 3.825 5 P 0 8 0;1=9
P 1.137 3.825 5 P 0 8 0;1=9
P 6.56038996 1.41205 5 P 0 8 0;1=9
P 6.56038996 1.37205 5 P 0 8 0;1=9
P 6.56038996 1.33205 5 P 0 8 0;1=9
P 6.56038996 1.29205 5 P 0 8 0;1=9
P 6.56038996 1.25205 5 P 0 8 0;1=9
P 6.56038996 1.21205 5 P 0 8 0;1=9
P 6.56038996 1.17205 5 P 0 8 0;1=9
P 6.56038996 1.13205 5 P 0 8 0;1=9
P 6.56038996 1.09205 5 P 0 8 0;1=9
P 5.9645 2.1035 6 P 0 8 0;1=15
P 6.0155 2.0845 6 P 0 8 0;1=15
P 0.22703996 0.43635 7 P 0 8 0;1=16
P 0.19878002 0.36811004 7 P 0 8 0;1=16
P 0.22703996 0.29986998 7 P 0 8 0;1=16
P 0.29528002 0.27161004 7 P 0 8 0;1=16
P 0.36351998 0.29986998 7 P 0 8 0;1=16
P 0.39178002 0.36811004 7 P 0 8 0;1=16
P 0.36351998 0.43635 7 P 0 8 0;1=16
P 0.29528002 0.46461004 7 P 0 8 0;1=16
P 6.33215 0.72178002 7 P 0 8 0;1=16
P 6.30388996 0.65353996 7 P 0 8 0;1=16
P 6.33215 0.5853 7 P 0 8 0;1=16
P 6.40038996 0.55703996 7 P 0 8 0;1=16
P 6.46863002 0.5853 7 P 0 8 0;1=16
P 6.49688996 0.65353996 7 P 0 8 0;1=16
P 6.46863002 0.72178002 7 P 0 8 0;1=16
P 6.40038996 0.75003996 7 P 0 8 0;1=16
P 6.33215 4.24658996 7 P 0 8 0;1=16
P 6.30388996 4.17835 7 P 0 8 0;1=16
P 6.33215 4.11011004 7 P 0 8 0;1=16
P 6.40038996 4.08185 7 P 0 8 0;1=16
P 6.46863002 4.11011004 7 P 0 8 0;1=16
P 6.49688996 4.17835 7 P 0 8 0;1=16
P 6.46863002 4.24658996 7 P 0 8 0;1=16
P 6.40038996 4.27485 7 P 0 8 0;1=16
P 5.92 1.36 6 P 0 8 0;1=0
P 6.22 1.36 6 P 0 8 0;1=2
P 5.99 0.925 6 P 0 8 0;1=2
P 5.803 3.857 6 P 0 8 0;1=2
P 1.355 3.905 6 P 0 8 0;1=2
P 1.21168996 3.96891998 6 P 0 8 0;1=2
P 0.42 2.368 6 P 0 8 0;1=2
P 5.325 2.725 6 P 0 8 0;1=2
P 1.6985 2.9895 6 P 0 8 0;1=15
P 1.6615 3.0405 6 P 0 8 0;1=15
P 5.6435 0.6535 6 P 0 8 0;1=15
P 5.1265 2.6815 6 P 0 8 0;1=15
P 5.0895 2.7325 6 P 0 8 0;1=15
P 4.1915 4.0395 6 P 0 8 0;1=15
P 4.0965 3.9445 6 P 0 8 0;1=15
P 4.1235 3.9715 6 P 0 8 0;1=15
P 4.1645 3.9715 6 P 0 8 0;1=15
P 4.1645 4.0125 6 P 0 8 0;1=15
P 4.1235 4.0125 6 P 0 8 0;1=15
P 4.0965 4.0395 6 P 0 8 0;1=15
P 4.1915 3.9445 6 P 0 8 0;1=15
P 4.5 4.07 6 P 0 8 0;1=2
P 4.31 4.16 6 P 0 8 0;1=2
P 1.41 2.985 6 P 0 8 0;1=2
P 1.45 2.965 6 P 0 8 0;1=2
P 1.51 3.242 6 P 0 8 0;1=2
P 1.89 3.26 6 P 0 8 0;1=2
P 1.895 3.19 6 P 0 8 0;1=2
P 1.9 3.055 6 P 0 8 0;1=2
P 1.9 3.015 6 P 0 8 0;1=2
P 1.65 2.94 6 P 0 8 0;1=2
P 1.685 2.94 6 P 0 8 0;1=2
P 5.17 2.125 6 P 0 8 0;1=2
P 4.96 1.79258002 6 P 0 8 0;1=2
P 4.59 3.26 6 P 0 8 0;1=2
P 2.866 1.987 5 P 0 8 0;1=9
P 2.77 1.987 5 P 0 8 0;1=9
P 4.5093 1.22166998 5 P 0 8 0;1=9
P 0.04 2.85618996 5 P 0 8 0;1=9
P 0.04 2.81618996 5 P 0 8 0;1=9
P 0.04 3.13618996 5 P 0 8 0;1=9
P 0.04 3.09618996 5 P 0 8 0;1=9
P 0.04 3.05618996 5 P 0 8 0;1=9
P 0.04 3.01618996 5 P 0 8 0;1=9
P 3.49 3.03 6 P 0 8 0;1=2
P 3.555 3.065 6 P 0 8 0;1=2
P 3.695 2.675 6 P 0 8 0;1=2
P 3.725 2.32 6 P 0 8 0;1=2
P 0.945 1.05 6 P 0 8 0;1=2
P 4.635 0.865 6 P 0 8 0;1=2
P 0.866 1.413 6 P 0 8 0;1=2
P 2.885 3.17 6 P 0 8 0;1=2
P 0.83 4.17 6 P 0 8 0;1=2
P 0.455 1.26 6 P 0 8 0;1=2
P 0.175 0.91 6 P 0 8 0;1=2
P 0.17 2.045 6 P 0 8 0;1=2
P 0.455 1.61 6 P 0 8 0;1=2
P 1.32 3.755 6 P 0 8 0;1=2
P 1.25095 3.06095 6 P 0 8 0;1=2
P 0.95593002 3.33346998 6 P 0 8 0;1=2
P 0.575 2.89 6 P 0 8 0;1=0
P 0.16 3.025 6 P 0 8 0;1=2
P 0.16 3.075 6 P 0 8 0;1=2
P 0.72 3.35 6 P 0 8 0;1=2
P 0.635 3.596 6 P 0 8 0;1=2
P 0.671 3.575 5 P 0 8 0;1=9
P 0.767 3.575 5 P 0 8 0;1=9
P 1.4213 3.2563 6 P 0 8 0;1=2
P 4.472 3.475 6 P 0 8 0;1=2
P 5.97703002 1.87 6 P 0 8 0;1=2
P 0.606 1.612 6 P 0 8 0;1=2
P 5.33 0.87 6 P 0 8 0;1=2
P 6.26988996 2.37988996 6 P 0 8 0;1=2
P 4.46 3.745 6 P 0 8 0;1=2
P 3.83 3.415 6 P 0 8 0;1=2
P 3.55 3.325 5 P 0 8 0;1=9
P 6.335 3.015 6 P 0 8 0;1=2
P 1.667 3.388 6 P 0 8 0;1=2
P 1.591 3.504 6 P 0 8 0;1=2
P 1.045 3.055 6 P 0 8 0;1=2
P 1.42 3.5 6 P 0 8 0;1=2
P 1.235 3.475 6 P 0 8 0;1=2
P 1.2 3.715 6 P 0 8 0;1=2
P 1.409 3.554 6 P 0 8 0;1=2
P 1.2 3.68 6 P 0 8 0;1=2
P 1.155 3.89 6 P 0 8 0;1=2
P 1.17 3.97 6 P 0 8 0;1=2
P 1.27 3.97061004 6 P 0 8 0;1=2
P 1.29 3.705 6 P 0 8 0;1=2
P 1.355 3.83 6 P 0 8 0;1=2
P 1.355 3.96 6 P 0 8 0;1=2
P 1.185 3.79 6 P 0 8 0;1=2
P 1.32 3.79 6 P 0 8 0;1=2
P 1.29 3.65 6 P 0 8 0;1=2
P 5.803 3.567 6 P 0 8 0;1=2
P 5.43 3.967 6 P 0 8 0;1=2
P 6.165 1.94873996 6 P 0 8 0;1=2
P 1.038 0.7624 6 P 0 8 0;1=2
P 4.037 2.593 6 P 0 8 0;1=2
P 3.978 2.593 6 P 0 8 0;1=2
P 4.81 0.707 6 P 0 8 0;1=2
P 6.47 1.135 6 P 0 8 0;1=2
P 4.595 3.22 6 P 0 8 0;1=2
P 4.175 3.52 6 P 0 8 0;1=2
P 3.98 3.52 6 P 0 8 0;1=2
P 3.973 3.207 6 P 0 8 0;1=2
P 4.075 3.05 6 P 0 8 0;1=2
P 3.839 3.726 6 P 0 8 0;1=2
P 4.1 3.58543002 6 P 0 8 0;1=2
P 5.637 3.524 6 P 0 8 0;1=0
P 5.276 3.189 6 P 0 8 0;1=2
P 5.329 3.189 6 P 0 8 0;1=2
P 5.386 3.189 6 P 0 8 0;1=2
P 5.271 3.456 6 P 0 8 0;1=2
P 5.271 3.406 6 P 0 8 0;1=2
P 5.324 3.456 6 P 0 8 0;1=2
P 5.381 3.456 6 P 0 8 0;1=2
P 5.324 3.406 6 P 0 8 0;1=2
P 5.381 3.406 6 P 0 8 0;1=2
P 5.802 3.617 6 P 0 8 0;1=2
P 5.763 3.712 6 P 0 8 0;1=2
P 5.803 3.757 6 P 0 8 0;1=2
P 5.803 3.807 6 P 0 8 0;1=2
P 5.602 3.865 6 P 0 8 0;1=2
P 5.645 3.79 6 P 0 8 0;1=2
P 5.48556998 3.877 6 P 0 8 0;1=0
P 5.237 3.777 6 P 0 8 0;1=2
P 5.282 3.777 6 P 0 8 0;1=2
P 5.237 3.841 6 P 0 8 0;1=2
P 5.322 3.777 6 P 0 8 0;1=2
P 5.385 4.07875 6 P 0 8 0;1=2
P 0.199 2.83 6 P 0 8 0;1=2
P 1.2 3.645 6 P 0 8 0;1=2
P 1.1 3.64 6 P 0 8 0;1=2
P 1.065 3.64 6 P 0 8 0;1=2
P 1.03 3.64 6 P 0 8 0;1=2
P 0.99 3.5 6 P 0 8 0;1=2
P 0.664 0.774 6 P 0 8 0;1=2
P 0.833 0.871 6 P 0 8 0;1=2
P 0.66 0.911 6 P 0 8 0;1=2
P 0.695 1 6 P 0 8 0;1=2
P 0.485 2.715 6 P 0 8 0;1=2
P 0.51771998 2.45073996 6 P 0 8 0;1=2
P 0.675 2.229 6 P 0 8 0;1=2
P 0.575 2.185 6 P 0 8 0;1=2
P 0.51771998 1.87986998 6 P 0 8 0;1=2
P 0.539 1.57 6 P 0 8 0;1=2
P 0.51771998 1.305 6 P 0 8 0;1=2
P 0.476 0.689 6 P 0 8 0;1=2
P 0.614 1.049 6 P 0 8 0;1=2
P 0.51771998 0.736 6 P 0 8 0;1=2
P 0.47 1 6 P 0 8 0;1=2
P 0.677 0.65 6 P 0 8 0;1=2
P 4.546 1.085 6 P 0 8 0;1=2
P 0.43705 3.51576004 19 P 0 8 0;1=17
P 0.43705 3.31655 19 P 0 8 0;1=17
P 0.24806998 3.47245 19 P 0 8 0;1=17
P 0.24806998 3.35985 19 P 0 8 0;1=17
P 0.24606004 3.4315 8 P 0 8 0;1=6
P 0.4587 3.4315 8 P 0 8 0;1=6
P 0.44098002 3.4008 8 P 0 8 0;1=6
P 0.22833996 3.4008 8 P 0 8 0;1=6
P 5.75071998 1.655 6 P 0 8 0;1=2
P 1.76 4.16 6 P 0 8 0;1=2
P 2.26 3.785 6 P 0 8 0;1=2
P 2.215 3.785 6 P 0 8 0;1=2
P 3.843 3.687 6 P 0 8 0;1=2
P 0.61488996 3.32328996 6 P 0 8 0;1=2
P 5.335 1.245 6 P 0 8 0;1=2
P 5.345 1.3 6 P 0 8 0;1=2
P 5.345 1.365 6 P 0 8 0;1=2
P 3.645 2.13 6 P 0 8 0;1=2
P 3.67 2.13 6 P 0 8 0;1=2
P 3.11 1.935 6 P 0 8 0;1=2
P 4.294 1.075 6 P 0 8 0;1=2
P 4.5 1.082 6 P 0 8 0;1=2
P 5.385 1.895 6 P 0 8 0;1=2
P 5.425 1.895 6 P 0 8 0;1=2
P 5.76458996 1.61971004 6 P 0 8 0;1=2
P 5.34 1.605 6 P 0 8 0;1=2
P 5.44 1.59 6 P 0 8 0;1=2
P 4.54123002 1.70563996 4 P 0 8 0;1=1
P 4.73806998 1.66626998 4 P 0 8 0;1=1
P 4.26563996 2.17806998 4 P 0 8 0;1=1
P 4.6987 1.3513 4 P 0 8 0;1=1
P 4.57843996 1.31408002 4 P 0 8 0;1=1
P 4.54121998 1.43005 4 P 0 8 0;1=1
P 4.42311004 1.54816004 4 P 0 8 0;1=1
P 4.42311004 1.39066998 4 P 0 8 0;1=1
P 4.38373996 1.58753002 4 P 0 8 0;1=1
P 4.38373996 1.50878996 4 P 0 8 0;1=1
P 4.38373996 1.6269 4 P 0 8 0;1=1
P 4.34436998 1.54816004 4 P 0 8 0;1=1
P 4.34436998 1.66626998 4 P 0 8 0;1=1
P 4.34436998 1.6269 4 P 0 8 0;1=1
P 4.26563996 1.58753002 4 P 0 8 0;1=1
P 4.26563996 1.3513 4 P 0 8 0;1=1
P 4.26563996 1.6269 4 P 0 8 0;1=1
P 4.26563996 1.66626998 4 P 0 8 0;1=1
P 4.22626998 1.54816004 4 P 0 8 0;1=1
P 4.22626998 1.46941998 4 P 0 8 0;1=1
P 4.22626998 1.6269 4 P 0 8 0;1=1
P 4.1869 1.58753002 4 P 0 8 0;1=1
P 4.14753002 1.54816004 4 P 0 8 0;1=1
P 4.14753002 1.31193002 4 P 0 8 0;1=1
P 4.10816004 1.54816004 4 P 0 8 0;1=1
P 4.10816004 1.50878996 4 P 0 8 0;1=1
P 4.10816004 1.46941998 4 P 0 8 0;1=1
P 4.06878996 1.46941998 4 P 0 8 0;1=1
P 4.02941998 1.46941998 4 P 0 8 0;1=1
P 4.02941998 1.43005 4 P 0 8 0;1=1
P 3.99005 1.43005 4 P 0 8 0;1=1
P 3.99005 1.39066998 4 P 0 8 0;1=1
P 3.95066998 1.39066998 4 P 0 8 0;1=1
P 3.87193002 2.17806998 4 P 0 8 0;1=1
P 3.9113 2.05996004 4 P 0 8 0;1=1
P 3.95066998 1.94185 4 P 0 8 0;1=1
P 4.10816004 1.86311004 4 P 0 8 0;1=1
P 3.99005 1.82373996 4 P 0 8 0;1=1
P 4.1869 1.78436998 4 P 0 8 0;1=1
P 4.10816004 1.78436998 4 P 0 8 0;1=1
P 3.99005 1.78436998 4 P 0 8 0;1=1
P 3.87193002 1.78436998 4 P 0 8 0;1=1
P 3.95066998 1.78436998 4 P 0 8 0;1=1
P 3.9113 1.78436998 4 P 0 8 0;1=1
P 4.22626998 1.70563996 4 P 0 8 0;1=1
P 4.14753002 1.70563996 4 P 0 8 0;1=1
P 4.06878996 1.70563996 4 P 0 8 0;1=1
P 4.02941998 1.70563996 4 P 0 8 0;1=1
P 3.87193002 1.70563996 4 P 0 8 0;1=1
P 4.1869 1.66626998 4 P 0 8 0;1=1
P 4.10816004 1.66626998 4 P 0 8 0;1=1
P 3.95066998 1.66626998 4 P 0 8 0;1=1
P 3.87193002 1.6269 4 P 0 8 0;1=1
P 4.14753002 1.6269 4 P 0 8 0;1=1
P 4.10816004 1.6269 4 P 0 8 0;1=1
P 4.02941998 1.6269 4 P 0 8 0;1=1
P 4.10816004 1.58753002 4 P 0 8 0;1=1
P 3.99005 1.58753002 4 P 0 8 0;1=1
P 3.87193002 1.54816004 4 P 0 8 0;1=1
P 4.02941998 1.54816004 4 P 0 8 0;1=1
P 3.95066998 1.50878996 4 P 0 8 0;1=1
P 3.87193002 1.46941998 4 P 0 8 0;1=1
P 3.87193002 1.39066998 4 P 0 8 0;1=1
P 3.9113 1.39066998 4 P 0 8 0;1=1
P 3.87193002 1.3513 4 P 0 8 0;1=1
P 4.6987 2.17806998 4 P 0 8 0;1=1
P 4.58058996 2.1387 4 P 0 8 0;1=1
P 4.50185 1.98121998 4 P 0 8 0;1=1
P 4.46248002 2.09933002 4 P 0 8 0;1=1
P 4.38373996 1.94185 4 P 0 8 0;1=1
P 4.34436998 2.05996004 4 P 0 8 0;1=1
P 4.22626998 1.90248002 4 P 0 8 0;1=1
P 4.1869 2.02058996 4 P 0 8 0;1=1
P 4.14753002 2.1387 4 P 0 8 0;1=1
P 4.06878996 1.98121998 4 P 0 8 0;1=1
P 4.02941998 2.09933002 4 P 0 8 0;1=1
P 4.73806998 2.05996004 4 P 0 8 0;1=1
P 4.61996004 2.02058996 4 P 0 8 0;1=1
P 4.65933002 1.90248002 4 P 0 8 0;1=1
P 4.54121998 1.86311004 4 P 0 8 0;1=1
P 4.42311004 1.82373996 4 P 0 8 0;1=1
P 4.6987 1.78436998 4 P 0 8 0;1=1
P 4.46248002 1.78436998 4 P 0 8 0;1=1
P 4.50185 1.70563996 4 P 0 8 0;1=1
P 4.42311004 1.70563996 4 P 0 8 0;1=1
P 4.34436998 1.70563996 4 P 0 8 0;1=1
P 4.46248002 1.66626998 4 P 0 8 0;1=1
P 4.58058996 1.66626998 4 P 0 8 0;1=1
P 4.38373996 1.66626998 4 P 0 8 0;1=1
P 4.50185 1.6269 4 P 0 8 0;1=1
P 4.42311004 1.6269 4 P 0 8 0;1=1
P 4.61996004 1.58753002 4 P 0 8 0;1=1
P 4.46248002 1.58753002 4 P 0 8 0;1=1
P 4.50185 1.54816004 4 P 0 8 0;1=1
P 4.65933002 1.46941998 4 P 0 8 0;1=1
P 0.12878002 0.21716998 5 P 0 8 0;1=9
P 0.16878002 0.21716998 5 P 0 8 0;1=9
P 0.20878002 0.21716998 5 P 0 8 0;1=9
P 0.24878002 0.21716998 5 P 0 8 0;1=9
P 0.08413002 4.33598002 5 P 0 8 0;1=9
P 0.04413002 4.33598002 5 P 0 8 0;1=9
P 0.04 4.29618996 5 P 0 8 0;1=9
P 0.04 4.25618996 5 P 0 8 0;1=9
P 0.04 4.21618996 5 P 0 8 0;1=9
P 0.04 4.17618996 5 P 0 8 0;1=9
P 0.04 4.13618996 5 P 0 8 0;1=9
P 0.04 4.09618996 5 P 0 8 0;1=9
P 0.04 4.05618996 5 P 0 8 0;1=9
P 0.04 4.01618996 5 P 0 8 0;1=9
P 0.04 3.97618996 5 P 0 8 0;1=9
P 0.04 3.93618996 5 P 0 8 0;1=9
P 0.04 3.89618996 5 P 0 8 0;1=9
P 0.04 3.85618996 5 P 0 8 0;1=9
P 0.04 3.81618996 5 P 0 8 0;1=9
P 0.04 3.77618996 5 P 0 8 0;1=9
P 0.04 3.73618996 5 P 0 8 0;1=9
P 0.04 3.69618996 5 P 0 8 0;1=9
P 0.04 3.65618996 5 P 0 8 0;1=9
P 0.04 3.61618996 5 P 0 8 0;1=9
P 0.04 3.57618996 5 P 0 8 0;1=9
P 0.04 3.53618996 5 P 0 8 0;1=9
P 0.04 3.49618996 5 P 0 8 0;1=9
P 0.04 3.45618996 5 P 0 8 0;1=9
P 0.04 3.41618996 5 P 0 8 0;1=9
P 0.04 3.37618996 5 P 0 8 0;1=9
P 0.04 2.97618996 5 P 0 8 0;1=9
P 0.04 2.93618996 5 P 0 8 0;1=9
P 0.04 2.89618996 5 P 0 8 0;1=9
P 0.04 0.49618996 5 P 0 8 0;1=9
P 0.04 0.45618996 5 P 0 8 0;1=9
P 0.04 0.41618996 5 P 0 8 0;1=9
P 0.04 0.37618996 5 P 0 8 0;1=9
P 0.04 0.33618996 5 P 0 8 0;1=9
P 0.04 0.29618996 5 P 0 8 0;1=9
P 0.04 0.25618996 5 P 0 8 0;1=9
P 0.04878002 0.21716998 5 P 0 8 0;1=9
P 0.08878002 0.21716998 5 P 0 8 0;1=9
P 2.76413002 4.33598002 5 P 0 8 0;1=9
P 2.72413002 4.33598002 5 P 0 8 0;1=9
P 2.68413002 4.33598002 5 P 0 8 0;1=9
P 2.64413002 4.33598002 5 P 0 8 0;1=9
P 2.60413002 4.33598002 5 P 0 8 0;1=9
P 0.55055 0.45073002 5 P 0 8 0;1=9
P 0.55558002 0.49041004 5 P 0 8 0;1=9
P 0.57858996 0.52313002 5 P 0 8 0;1=9
P 0.61463002 0.54048002 5 P 0 8 0;1=9
P 0.55055 0.29073002 5 P 0 8 0;1=9
P 0.55055 0.33073002 5 P 0 8 0;1=9
P 0.55055 0.37073002 5 P 0 8 0;1=9
P 0.55055 0.41073002 5 P 0 8 0;1=9
P 0.48878002 0.21716998 5 P 0 8 0;1=9
P 0.52878002 0.21716998 5 P 0 8 0;1=9
P 0.55055 0.25073002 5 P 0 8 0;1=9
P 0.44413002 4.33598002 5 P 0 8 0;1=9
P 0.40413002 4.33598002 5 P 0 8 0;1=9
P 0.36413002 4.33598002 5 P 0 8 0;1=9
P 0.32413002 4.33598002 5 P 0 8 0;1=9
P 0.28878002 0.21716998 5 P 0 8 0;1=9
P 0.32878002 0.21716998 5 P 0 8 0;1=9
P 0.36878002 0.21716998 5 P 0 8 0;1=9
P 0.40878002 0.21716998 5 P 0 8 0;1=9
P 0.44878002 0.21716998 5 P 0 8 0;1=9
P 0.28413002 4.33598002 5 P 0 8 0;1=9
P 0.24413002 4.33598002 5 P 0 8 0;1=9
P 0.20413002 4.33598002 5 P 0 8 0;1=9
P 0.16413002 4.33598002 5 P 0 8 0;1=9
P 0.12413002 4.33598002 5 P 0 8 0;1=9
P 0.889 0.67 6 P 0 8 0;1=2
P 0.6546 0.54196998 5 P 0 8 0;1=9
P 0.6946 0.54196998 5 P 0 8 0;1=9
P 0.7346 0.54196998 5 P 0 8 0;1=9
P 0.7746 0.54196998 5 P 0 8 0;1=9
P 0.8146 0.54196998 5 P 0 8 0;1=9
P 0.64413002 4.33598002 5 P 0 8 0;1=9
P 0.60413002 4.33598002 5 P 0 8 0;1=9
P 0.56413002 4.33598002 5 P 0 8 0;1=9
P 0.52413002 4.33598002 5 P 0 8 0;1=9
P 0.48413002 4.33598002 5 P 0 8 0;1=9
P 0.8575 2.0275 6 P 0 8 0;1=2
P 1.195 0.57693996 6 P 0 8 0;1=2
P 0.8546 0.54196998 5 P 0 8 0;1=9
P 0.8946 0.54196998 5 P 0 8 0;1=9
P 0.9346 0.54196998 5 P 0 8 0;1=9
P 0.9746 0.54196998 5 P 0 8 0;1=9
P 0.80413002 4.33598002 5 P 0 8 0;1=9
P 0.76413002 4.33598002 5 P 0 8 0;1=9
P 0.72413002 4.33598002 5 P 0 8 0;1=9
P 0.68413002 4.33598002 5 P 0 8 0;1=9
P 0.66 4.19 6 P 0 8 0;1=2
P 0.67 2.831 5 P 0 8 0;1=9
P 0.79248002 2.661 5 P 0 8 0;1=9
P 0.80148002 2.53648002 6 P 0 8 0;1=2
P 0.715 2.478 6 P 0 8 0;1=2
P 0.714 2.217 6 P 0 8 0;1=2
P 0.74593002 2.02206998 6 P 0 8 0;1=2
P 1.0146 0.54196998 5 P 0 8 0;1=9
P 1.0546 0.54196998 5 P 0 8 0;1=9
P 1.0946 0.54196998 5 P 0 8 0;1=9
P 1.1346 0.54196998 5 P 0 8 0;1=9
P 1.1746 0.54196998 5 P 0 8 0;1=9
P 1.00413002 4.33598002 5 P 0 8 0;1=9
P 0.96413002 4.33598002 5 P 0 8 0;1=9
P 0.92413002 4.33598002 5 P 0 8 0;1=9
P 0.88413002 4.33598002 5 P 0 8 0;1=9
P 0.84413002 4.33598002 5 P 0 8 0;1=9
P 1.025 4.2 6 P 0 8 0;1=2
P 0.94 4.2 6 P 0 8 0;1=2
P 0.858 2.87451998 3 P 0 8 0;1=4
P 0.988 2.724 6 P 0 8 0;1=2
P 0.987 2.683 6 P 0 8 0;1=0
P 0.856 2.637 5 P 0 8 0;1=9
P 0.93031998 2.46476998 6 P 0 8 0;1=2
P 0.872 2.583 6 P 0 8 0;1=2
P 0.868 2.3 5 P 0 8 0;1=9
P 1.401 3.956 6 P 0 8 0;1=2
P 1.40123002 3.91603996 6 P 0 8 0;1=2
P 1.48 3.7 6 P 0 8 0;1=2
P 1.38163002 0.21716998 5 P 0 8 0;1=9
P 1.42163002 0.21716998 5 P 0 8 0;1=9
P 1.46163002 0.21716998 5 P 0 8 0;1=9
P 1.50163002 0.21716998 5 P 0 8 0;1=9
P 1.54163002 0.21716998 5 P 0 8 0;1=9
P 1.36413002 4.33598002 5 P 0 8 0;1=9
P 1.32413002 4.33598002 5 P 0 8 0;1=9
P 1.28413002 4.33598002 5 P 0 8 0;1=9
P 1.24413002 4.33598002 5 P 0 8 0;1=9
P 1.20413002 4.33598002 5 P 0 8 0;1=9
P 1.515 3.7 6 P 0 8 0;1=2
P 1.385 0.75 5 P 0 8 0;1=9
P 1.44 0.625 5 P 0 8 0;1=9
P 1.5184 0.79935 5 P 0 8 0;1=9
P 1.2146 0.54196998 5 P 0 8 0;1=9
P 1.2546 0.54196998 5 P 0 8 0;1=9
P 1.2945 0.53916998 5 P 0 8 0;1=9
P 1.3292 0.51926004 5 P 0 8 0;1=9
P 1.34976998 0.48496004 5 P 0 8 0;1=9
P 1.35298996 0.44508996 5 P 0 8 0;1=9
P 1.35298996 0.40508996 5 P 0 8 0;1=9
P 1.35298996 0.36508996 5 P 0 8 0;1=9
P 1.35298996 0.32508996 5 P 0 8 0;1=9
P 1.35298996 0.28508996 5 P 0 8 0;1=9
P 1.35298996 0.24508996 5 P 0 8 0;1=9
P 1.16413002 4.33598002 5 P 0 8 0;1=9
P 1.12413002 4.33598002 5 P 0 8 0;1=9
P 1.08413002 4.33598002 5 P 0 8 0;1=9
P 1.04413002 4.33598002 5 P 0 8 0;1=9
P 1.96413002 4.33598002 5 P 0 8 0;1=9
P 1.92413002 4.33598002 5 P 0 8 0;1=9
P 1.915 4.13 6 P 0 8 0;1=2
P 1.88413002 4.33598002 5 P 0 8 0;1=9
P 1.84413002 4.33598002 5 P 0 8 0;1=9
P 1.80413002 4.33598002 5 P 0 8 0;1=9
P 1.76413002 4.33598002 5 P 0 8 0;1=9
P 1.746 4.061 6 P 0 8 0;1=2
P 1.746 4.106 6 P 0 8 0;1=0
P 1.751 3.871 6 P 0 8 0;1=2
P 1.746 4.016 6 P 0 8 0;1=2
P 1.751 3.826 6 P 0 8 0;1=0
P 1.786 3.746 6 P 0 8 0;1=2
P 1.786 3.786 6 P 0 8 0;1=2
P 2.0966 3.315 5 P 0 8 0;1=9
P 1.72413002 4.33598002 5 P 0 8 0;1=9
P 1.68413002 4.33598002 5 P 0 8 0;1=9
P 1.64413002 4.33598002 5 P 0 8 0;1=9
P 1.60413002 4.33598002 5 P 0 8 0;1=9
P 1.56413002 4.33598002 5 P 0 8 0;1=9
P 1.671 4.056 5 P 0 8 0;1=9
P 1.5086 0.674 6 P 0 8 0;1=0
P 1.59111998 0.45653996 5 P 0 8 0;1=9
P 1.60736004 0.49308996 5 P 0 8 0;1=9
P 1.58795 0.29666998 5 P 0 8 0;1=9
P 1.58795 0.33666998 5 P 0 8 0;1=9
P 1.58795 0.37666998 5 P 0 8 0;1=9
P 1.58795 0.41666998 5 P 0 8 0;1=9
P 1.58163002 0.21716998 5 P 0 8 0;1=9
P 1.58795 0.25666998 5 P 0 8 0;1=9
P 1.52413002 4.33598002 5 P 0 8 0;1=9
P 1.48413002 4.33598002 5 P 0 8 0;1=9
P 1.44413002 4.33598002 5 P 0 8 0;1=9
P 1.40413002 4.33598002 5 P 0 8 0;1=9
P 2.56413002 4.33598002 5 P 0 8 0;1=9
P 2.52413002 4.33598002 5 P 0 8 0;1=9
P 2.48413002 4.33598002 5 P 0 8 0;1=9
P 2.44413002 4.33598002 5 P 0 8 0;1=9
P 2.40413002 4.33598002 5 P 0 8 0;1=9
P 2.36413002 4.33598002 5 P 0 8 0;1=9
P 2.32413002 4.33598002 5 P 0 8 0;1=9
P 2.28413002 4.33598002 5 P 0 8 0;1=9
P 2.295 4.15 6 P 0 8 0;1=2
P 2.285 3.825 6 P 0 8 0;1=0
P 2.24413002 4.33598002 5 P 0 8 0;1=9
P 2.20413002 4.33598002 5 P 0 8 0;1=9
P 2.16413002 4.33598002 5 P 0 8 0;1=9
P 2.12413002 4.33598002 5 P 0 8 0;1=9
P 2.176 4.151 6 P 0 8 0;1=2
P 2.256 4.151 6 P 0 8 0;1=2
P 2.215 4.15 6 P 0 8 0;1=2
P 2.18 3.811 6 P 0 8 0;1=2
P 2.218 2.895 5 P 0 8 0;1=9
P 2.173 2.895 5 P 0 8 0;1=9
P 2.083 2.895 5 P 0 8 0;1=9
P 2.08413002 4.33598002 5 P 0 8 0;1=9
P 2.04413002 4.33598002 5 P 0 8 0;1=9
P 2.00413002 4.33598002 5 P 0 8 0;1=9
P 0.22703996 3.79855 7 P 0 8 0;1=16
P 0.19878002 3.73031004 7 P 0 8 0;1=16
P 0.22703996 3.66206998 7 P 0 8 0;1=16
P 0.29528002 3.63381004 7 P 0 8 0;1=16
P 0.36351998 3.66206998 7 P 0 8 0;1=16
P 0.39178002 3.73031004 7 P 0 8 0;1=16
P 0.36351998 3.79855 7 P 0 8 0;1=16
P 0.29528002 3.82681004 7 P 0 8 0;1=16
P 6.19961004 2.21273996 5 P 0 8 0;1=9
P 6.19961004 2.30873996 5 P 0 8 0;1=9
P 4.3445 1.16598996 5 P 0 8 0;1=9
P 4.4405 1.16598996 5 P 0 8 0;1=9
P 3.45301004 1.96298996 5 P 0 8 0;1=9
P 3.65101004 1.94758996 5 P 0 8 0;1=9
P 4.44 2.63 6 P 0 8 0;1=2
P 4.395 2.665 6 P 0 8 0;1=2
P 4.6 2.895 6 P 0 8 0;1=2
P 4.6 2.845 6 P 0 8 0;1=2
P 3.42 3.76 6 P 0 8 0;1=2
P 3.385 3.76 6 P 0 8 0;1=2
P 3.315 3.76 6 P 0 8 0;1=2
P 3.26 3.74 6 P 0 8 0;1=2
P 6.56038996 1.81205 5 P 0 8 0;1=9
P 6.56038996 1.77205 5 P 0 8 0;1=9
P 6.56038996 1.73205 5 P 0 8 0;1=9
P 6.56038996 1.69205 5 P 0 8 0;1=9
P 6.56038996 1.65205 5 P 0 8 0;1=9
P 6.56038996 1.61205 5 P 0 8 0;1=9
P 6.56038996 1.57205 5 P 0 8 0;1=9
P 6.56038996 1.53205 5 P 0 8 0;1=9
P 6.56038996 1.49205 5 P 0 8 0;1=9
P 6.56038996 1.45205 5 P 0 8 0;1=9
P 6.56038996 1.05205 5 P 0 8 0;1=9
P 6.56038996 1.01205 5 P 0 8 0;1=9
P 6.56038996 0.97205 5 P 0 8 0;1=9
P 6.56038996 0.93205 5 P 0 8 0;1=9
P 6.56038996 0.89205 5 P 0 8 0;1=9
P 6.56038996 0.85205 5 P 0 8 0;1=9
P 6.56038996 0.81205 5 P 0 8 0;1=9
P 6.56038996 0.77205 5 P 0 8 0;1=9
P 6.56038996 0.73205 5 P 0 8 0;1=9
P 6.56038996 0.69205 5 P 0 8 0;1=9
P 6.56038996 0.65205 5 P 0 8 0;1=9
P 6.56038996 0.61205 5 P 0 8 0;1=9
P 6.56038996 0.57205 5 P 0 8 0;1=9
P 6.53401998 0.54196998 5 P 0 8 0;1=9
P 6.49401998 0.54196998 5 P 0 8 0;1=9
P 6.29401998 0.54196998 5 P 0 8 0;1=9
P 6.25401998 0.54196998 5 P 0 8 0;1=9
P 6.21401998 0.54196998 5 P 0 8 0;1=9
P 6.17401998 0.54196998 5 P 0 8 0;1=9
P 6.13401998 0.54196998 5 P 0 8 0;1=9
P 6.09401998 0.54196998 5 P 0 8 0;1=9
P 6.05401998 0.54196998 5 P 0 8 0;1=9
P 6.01401998 0.54196998 5 P 0 8 0;1=9
P 5.97401998 0.54196998 5 P 0 8 0;1=9
P 5.93401998 0.54196998 5 P 0 8 0;1=9
P 5.89401998 0.54196998 5 P 0 8 0;1=9
P 5.85401998 0.54196998 5 P 0 8 0;1=9
P 5.81401998 0.54196998 5 P 0 8 0;1=9
P 5.77401998 0.54196998 5 P 0 8 0;1=9
P 5.73401998 0.54196998 5 P 0 8 0;1=9
P 5.69401998 0.54196998 5 P 0 8 0;1=9
P 5.65401998 0.54196998 5 P 0 8 0;1=9
P 5.61401998 0.54196998 5 P 0 8 0;1=9
P 5.57401998 0.54196998 5 P 0 8 0;1=9
P 5.53401998 0.54196998 5 P 0 8 0;1=9
P 5.49401998 0.54196998 5 P 0 8 0;1=9
P 5.45401998 0.54196998 5 P 0 8 0;1=9
P 5.41401998 0.54196998 5 P 0 8 0;1=9
P 5.37401998 0.54196998 5 P 0 8 0;1=9
P 5.33401998 0.54196998 5 P 0 8 0;1=9
P 5.29401998 0.54196998 5 P 0 8 0;1=9
P 5.25401998 0.54196998 5 P 0 8 0;1=9
P 5.21401998 0.54196998 5 P 0 8 0;1=9
P 5.17401998 0.54196998 5 P 0 8 0;1=9
P 5.13401998 0.54196998 5 P 0 8 0;1=9
P 5.09401998 0.54196998 5 P 0 8 0;1=9
P 5.05401998 0.54196998 5 P 0 8 0;1=9
P 5.01401998 0.54196998 5 P 0 8 0;1=9
P 4.97401998 0.54196998 5 P 0 8 0;1=9
P 4.93401998 0.54196998 5 P 0 8 0;1=9
P 4.89401998 0.54196998 5 P 0 8 0;1=9
P 4.85401998 0.54196998 5 P 0 8 0;1=9
P 4.81401998 0.54196998 5 P 0 8 0;1=9
P 4.77401998 0.54196998 5 P 0 8 0;1=9
P 4.73401998 0.54196998 5 P 0 8 0;1=9
P 4.69401998 0.54196998 5 P 0 8 0;1=9
P 4.65401998 0.54196998 5 P 0 8 0;1=9
P 4.61401998 0.54196998 5 P 0 8 0;1=9
P 4.57401998 0.54196998 5 P 0 8 0;1=9
P 4.53401998 0.54196998 5 P 0 8 0;1=9
P 4.49401998 0.54196998 5 P 0 8 0;1=9
P 4.45401998 0.54196998 5 P 0 8 0;1=9
P 4.41401998 0.54196998 5 P 0 8 0;1=9
P 4.37401998 0.54196998 5 P 0 8 0;1=9
P 4.33401998 0.54196998 5 P 0 8 0;1=9
P 4.29401998 0.54196998 5 P 0 8 0;1=9
P 4.25401998 0.54196998 5 P 0 8 0;1=9
P 4.21401998 0.54196998 5 P 0 8 0;1=9
P 4.17401998 0.54196998 5 P 0 8 0;1=9
P 2.80413002 4.33598002 5 P 0 8 0;1=9
P 2.84413002 4.33598002 5 P 0 8 0;1=9
P 2.88413002 4.33598002 5 P 0 8 0;1=9
P 2.92413002 4.33598002 5 P 0 8 0;1=9
P 2.96413002 4.33598002 5 P 0 8 0;1=9
P 3.00413002 4.33598002 5 P 0 8 0;1=9
P 3.04413002 4.33598002 5 P 0 8 0;1=9
P 3.08413002 4.33598002 5 P 0 8 0;1=9
P 3.12413002 4.33598002 5 P 0 8 0;1=9
P 3.16413002 4.33598002 5 P 0 8 0;1=9
P 3.20413002 4.33598002 5 P 0 8 0;1=9
P 3.24413002 4.33598002 5 P 0 8 0;1=9
P 3.28413002 4.33598002 5 P 0 8 0;1=9
P 3.32413002 4.33598002 5 P 0 8 0;1=9
P 3.36413002 4.33598002 5 P 0 8 0;1=9
P 3.40413002 4.33598002 5 P 0 8 0;1=9
P 3.44413002 4.33598002 5 P 0 8 0;1=9
P 3.48413002 4.33598002 5 P 0 8 0;1=9
P 3.52413002 4.33598002 5 P 0 8 0;1=9
P 3.56413002 4.33598002 5 P 0 8 0;1=9
P 3.60413002 4.33598002 5 P 0 8 0;1=9
P 3.64413002 4.33598002 5 P 0 8 0;1=9
P 3.68413002 4.33598002 5 P 0 8 0;1=9
P 3.72413002 4.33598002 5 P 0 8 0;1=9
P 3.76413002 4.33598002 5 P 0 8 0;1=9
P 3.80413002 4.33598002 5 P 0 8 0;1=9
P 3.84413002 4.33598002 5 P 0 8 0;1=9
P 3.88413002 4.33598002 5 P 0 8 0;1=9
P 3.92413002 4.33598002 5 P 0 8 0;1=9
P 3.96413002 4.33598002 5 P 0 8 0;1=9
P 4.00413002 4.33598002 5 P 0 8 0;1=9
P 4.04413002 4.33598002 5 P 0 8 0;1=9
P 4.08413002 4.33598002 5 P 0 8 0;1=9
P 4.12413002 4.33598002 5 P 0 8 0;1=9
P 4.16413002 4.33598002 5 P 0 8 0;1=9
P 4.20413002 4.33598002 5 P 0 8 0;1=9
P 4.24413002 4.33598002 5 P 0 8 0;1=9
P 4.28413002 4.33598002 5 P 0 8 0;1=9
P 4.32413002 4.33598002 5 P 0 8 0;1=9
P 4.36413002 4.33598002 5 P 0 8 0;1=9
P 4.40413002 4.33598002 5 P 0 8 0;1=9
P 4.44413002 4.33598002 5 P 0 8 0;1=9
P 4.48413002 4.33598002 5 P 0 8 0;1=9
P 4.52413002 4.33598002 5 P 0 8 0;1=9
P 4.56413002 4.33598002 5 P 0 8 0;1=9
P 4.60413002 4.33598002 5 P 0 8 0;1=9
P 4.64413002 4.33598002 5 P 0 8 0;1=9
P 4.68413002 4.33598002 5 P 0 8 0;1=9
P 4.72413002 4.33598002 5 P 0 8 0;1=9
P 4.76413002 4.33598002 5 P 0 8 0;1=9
P 4.80413002 4.33598002 5 P 0 8 0;1=9
P 4.84413002 4.33598002 5 P 0 8 0;1=9
P 4.88413002 4.33598002 5 P 0 8 0;1=9
P 4.92413002 4.33598002 5 P 0 8 0;1=9
P 4.96413002 4.33598002 5 P 0 8 0;1=9
P 5.00413002 4.33598002 5 P 0 8 0;1=9
P 5.04413002 4.33598002 5 P 0 8 0;1=9
P 5.08413002 4.33598002 5 P 0 8 0;1=9
P 5.12413002 4.33598002 5 P 0 8 0;1=9
P 5.16413002 4.33598002 5 P 0 8 0;1=9
P 5.20413002 4.33598002 5 P 0 8 0;1=9
P 5.24413002 4.33598002 5 P 0 8 0;1=9
P 5.28413002 4.33598002 5 P 0 8 0;1=9
P 5.32413002 4.33598002 5 P 0 8 0;1=9
P 5.36413002 4.33598002 5 P 0 8 0;1=9
P 5.40413002 4.33598002 5 P 0 8 0;1=9
P 5.44413002 4.33598002 5 P 0 8 0;1=9
P 5.48413002 4.33598002 5 P 0 8 0;1=9
P 5.52413002 4.33598002 5 P 0 8 0;1=9
P 5.56413002 4.33598002 5 P 0 8 0;1=9
P 5.60413002 4.33598002 5 P 0 8 0;1=9
P 5.64413002 4.33598002 5 P 0 8 0;1=9
P 5.68413002 4.33598002 5 P 0 8 0;1=9
P 5.72413002 4.33598002 5 P 0 8 0;1=9
P 5.76413002 4.33598002 5 P 0 8 0;1=9
P 5.80413002 4.33598002 5 P 0 8 0;1=9
P 5.84413002 4.33598002 5 P 0 8 0;1=9
P 5.88413002 4.33598002 5 P 0 8 0;1=9
P 5.92413002 4.33598002 5 P 0 8 0;1=9
P 5.96413002 4.33598002 5 P 0 8 0;1=9
P 6.00413002 4.33598002 5 P 0 8 0;1=9
P 6.04413002 4.33598002 5 P 0 8 0;1=9
P 6.08413002 4.33598002 5 P 0 8 0;1=9
P 6.12413002 4.33598002 5 P 0 8 0;1=9
P 6.16413002 4.33598002 5 P 0 8 0;1=9
P 6.20413002 4.33598002 5 P 0 8 0;1=9
P 6.24413002 4.33598002 5 P 0 8 0;1=9
P 6.28413002 4.33598002 5 P 0 8 0;1=9
P 6.32413002 4.33598002 5 P 0 8 0;1=9
P 6.36413002 4.33598002 5 P 0 8 0;1=9
P 6.40413002 4.33598002 5 P 0 8 0;1=9
P 6.44413002 4.33598002 5 P 0 8 0;1=9
P 6.48413002 4.33598002 5 P 0 8 0;1=9
P 6.52413002 4.33598002 5 P 0 8 0;1=9
P 6.56038996 4.31908996 5 P 0 8 0;1=9
P 6.56038996 4.27908996 5 P 0 8 0;1=9
P 6.56038996 4.23908996 5 P 0 8 0;1=9
P 6.56038996 4.19908996 5 P 0 8 0;1=9
P 6.56038996 4.15908996 5 P 0 8 0;1=9
P 6.56038996 4.11908996 5 P 0 8 0;1=9
P 6.56038996 4.07908996 5 P 0 8 0;1=9
P 6.56038996 4.03908996 5 P 0 8 0;1=9
P 6.56038996 3.99908996 5 P 0 8 0;1=9
P 6.56038996 3.95908996 5 P 0 8 0;1=9
P 6.56038996 3.91908996 5 P 0 8 0;1=9
P 6.56038996 3.87908996 5 P 0 8 0;1=9
P 6.56038996 3.83908996 5 P 0 8 0;1=9
P 6.56038996 3.79908996 5 P 0 8 0;1=9
P 6.56038996 3.75908996 5 P 0 8 0;1=9
P 6.56038996 3.71908996 5 P 0 8 0;1=9
P 6.56038996 3.67908996 5 P 0 8 0;1=9
P 6.56038996 3.63908996 5 P 0 8 0;1=9
P 6.56038996 3.59908996 5 P 0 8 0;1=9
P 6.56038996 3.55908996 5 P 0 8 0;1=9
P 6.56038996 3.51908996 5 P 0 8 0;1=9
P 6.56038996 3.47908996 5 P 0 8 0;1=9
P 6.56038996 3.43908996 5 P 0 8 0;1=9
P 6.56038996 3.39908996 5 P 0 8 0;1=9
P 6.56038996 3.35908996 5 P 0 8 0;1=9
P 6.56038996 3.31908996 5 P 0 8 0;1=9
P 6.56038996 3.27908996 5 P 0 8 0;1=9
P 6.56038996 3.23908996 5 P 0 8 0;1=9
P 6.56038996 3.19908996 5 P 0 8 0;1=9
P 6.56038996 3.15908996 5 P 0 8 0;1=9
P 6.56038996 3.11908996 5 P 0 8 0;1=9
P 6.56038996 2.35585 5 P 0 8 0;1=9
P 5.119 2.762 6 P 0 8 0;1=2
P 5.63341004 0.62101998 6 P 0 8 0;1=2
P 5.59941004 0.6212 6 P 0 8 0;1=2
P 2.419 2.388 6 P 0 8 0;1=2
P 2.805 2.243 6 P 0 8 0;1=2
P 2.7526 2.23 6 P 0 8 0;1=2
P 4.278 1.003 6 P 0 8 0;1=2
P 3.08966998 2.04 6 P 0 8 0;1=2
P 2.41441004 2.15 6 P 0 8 0;1=2
P 2.69 2.15 6 P 0 8 0;1=2
P 5.83 1.92 6 P 0 8 0;1=2
P 5.805 1.945 6 P 0 8 0;1=2
P 5.045 3.76 6 P 0 8 0;1=2
P 5.05 3.795 6 P 0 8 0;1=2
P 4.54 3.97 6 P 0 8 0;1=2
P 4.54 3.935 6 P 0 8 0;1=2
P 4.62 2.5 6 P 0 8 0;1=2
P 3.305 2.915 6 P 0 8 0;1=2
P 3.145 2.765 6 P 0 8 0;1=2
P 6.105 2.27 6 P 0 8 0;1=2
P 6.141 2.241 6 P 0 8 0;1=2
P 2.54 2.135 6 P 0 8 0;1=2
P 2.59 2.23 6 P 0 8 0;1=2
P 5.859 0.796 6 P 0 8 0;1=2
P 5.80643002 0.609 6 P 0 8 0;1=2
P 5.805 0.658 6 P 0 8 0;1=2
P 5.37 0.69 6 P 0 8 0;1=2
P 5.43956998 0.60543002 6 P 0 8 0;1=2
P 6.335 1.96873996 6 P 0 8 0;1=2
P 5.59 0.888 6 P 0 8 0;1=2
P 4.933 1.215 6 P 0 8 0;1=2
P 4.894 1.263 6 P 0 8 0;1=2
P 4.79866998 1.38866998 6 P 0 8 0;1=2
P 5.0395 1.43 6 P 0 8 0;1=2
P 4.44 2.5 6 P 0 8 0;1=2
P 4.965 1.925 6 P 0 8 0;1=2
P 4.96 2.055 6 P 0 8 0;1=2
P 5.346 1.52 6 P 0 8 0;1=2
P 5.346 1.483 6 P 0 8 0;1=2
P 4.96 1.675 6 P 0 8 0;1=2
P 3.99 2.25 6 P 0 8 0;1=2
P 3.99 2.21406998 6 P 0 8 0;1=2
P 3.7206 2.13 6 P 0 8 0;1=2
P 3.6956 2.13 6 P 0 8 0;1=2
P 4.78 1.98 6 P 0 8 0;1=2
P 5.6065 0.7045 6 P 0 8 0;1=15
P 5.602 0.815 6 P 0 8 0;1=2
P 5.59 0.85 6 P 0 8 0;1=2
P 5.625 0.746 6 P 0 8 0;1=2
P 4.22 0.775 6 P 0 8 0;1=2
P 4.345 0.77 6 P 0 8 0;1=2
P 4.4843 0.8954 6 P 0 8 0;1=2
P 4.442 1.005 6 P 0 8 0;1=2
P 4.31 1.165 6 P 0 8 0;1=2
P 4.414 0.781 6 P 0 8 0;1=0
P 4.335 1.005 6 P 0 8 0;1=2
P 4.23 1.005 6 P 0 8 0;1=2
P 3.12 2.955 6 P 0 8 0;1=2
P 2.995 2.955 6 P 0 8 0;1=2
P 2.92 2.9472 6 P 0 8 0;1=2
P 2.88 2.93 6 P 0 8 0;1=2
P 3.01 3.12 6 P 0 8 0;1=2
P 5.121 2.447 6 P 0 8 0;1=2
P 5.121 2.407 6 P 0 8 0;1=2
P 5.298 2.23 6 P 0 8 0;1=2
P 5.332 2.2 6 P 0 8 0;1=0
P 5.369 2.015 6 P 0 8 0;1=2
P 5.435 2.05 6 P 0 8 0;1=2
P 5.409 2.015 6 P 0 8 0;1=2
P 5.071 2.407 6 P 0 8 0;1=2
P 4.815 1.82016004 6 P 0 8 0;1=2
P 4.44 2.26 6 P 0 8 0;1=2
P 3.67 2.41243002 6 P 0 8 0;1=2
P 3.67 2.32 6 P 0 8 0;1=0
P 3.54975 2.479 6 P 0 8 0;1=2
P 3.605 2.43 6 P 0 8 0;1=2
P 3.55 2.425 6 P 0 8 0;1=2
P 3.415 2.335 6 P 0 8 0;1=2
P 3.505 2.295 6 P 0 8 0;1=2
P 3.40953002 2.37 6 P 0 8 0;1=2
P 3.116 2.524 6 P 0 8 0;1=2
P 3.12 2.344 6 P 0 8 0;1=2
P 3.12 2.17 6 P 0 8 0;1=0
P 3.512 1.966 6 P 0 8 0;1=2
P 4.395 3.37891998 5 P 0 8 0;1=9
P 4.44 4.165 5 P 0 8 0;1=9
P 2.86151004 3.295 5 P 0 8 0;1=9
P 3.21898996 3.43 6 P 0 8 0;1=2
P 3.548 2.898 5 P 0 8 0;1=9
P 3.621 2.91 6 P 0 8 0;1=2
P 3.658 2.861 6 P 0 8 0;1=2
P 3.658 2.911 6 P 0 8 0;1=2
P 3.623 2.861 6 P 0 8 0;1=2
P 3.615 2.961 6 P 0 8 0;1=2
P 3.253 3.917 6 P 0 8 0;1=2
P 3.253 3.962 6 P 0 8 0;1=2
P 3.248 4.107 6 P 0 8 0;1=2
P 3.213 4.167 6 P 0 8 0;1=2
P 3.248 4.152 6 P 0 8 0;1=2
P 3.213 4.236 6 P 0 8 0;1=0
P 3.253 3.872 6 P 0 8 0;1=2
P 4.465 2.895 5 P 0 8 0;1=9
P 4.093 2.863 6 P 0 8 0;1=2
P 4.091 2.813 6 P 0 8 0;1=2
P 4.092 2.917 6 P 0 8 0;1=2
P 3.78 2.735 6 P 0 8 0;1=2
P 3.435 2.589 6 P 0 8 0;1=2
P 3.5485 2.761 5 P 0 8 0;1=9
P 3.285 2.589 6 P 0 8 0;1=0
P 4.775 2.59 6 P 0 8 0;1=2
P 4.71 2.592 6 P 0 8 0;1=0
P 4.918 2.777 6 P 0 8 0;1=2
P 4.925 2.722 6 P 0 8 0;1=2
P 3.106 3.305 5 P 0 8 0;1=9
P 3.222 3.25 5 P 0 8 0;1=9
P 3.975 3.129 6 P 0 8 0;1=2
P 3.998 2.784 6 P 0 8 0;1=2
P 3.83 2.932 6 P 0 8 0;1=2
P 3.78 2.932 6 P 0 8 0;1=2
P 3.703 2.911 6 P 0 8 0;1=2
P 3.748 2.911 6 P 0 8 0;1=2
P 3.933 3.125 6 P 0 8 0;1=2
P 3.6 4.024 6 P 0 8 0;1=2
P 3.631 4.228 6 P 0 8 0;1=2
P 3.60311004 4.0988 6 P 0 8 0;1=2
P 3.631 4.183 6 P 0 8 0;1=2
P 3.38 3.15 6 P 0 8 0;1=2
P 4.43 3.965 5 P 0 8 0;1=9
P 4.43 4.015 5 P 0 8 0;1=9
P 4.714 3.633 6 P 0 8 0;1=2
P 4.71 3.47 6 P 0 8 0;1=2
P 4.94093996 4.12008002 17 P 0 8 0;1=18
P 4.94093996 3.09646004 17 P 0 8 0;1=18
P 3.8865 2.9265 6 P 0 8 0;1=15
P 2.55906004 4.12008002 17 P 0 8 0;1=18
P 2.55906004 3.09646004 17 P 0 8 0;1=18
P 5.815 2.67 6 P 0 8 0;1=2
P 5.517 2.563 6 P 0 8 0;1=2
P 5.49 2.675 6 P 0 8 0;1=2
P 5.3035 2.5748 6 P 0 8 0;1=2
P 5.122 2.587 6 P 0 8 0;1=2
P 5.123 2.544 6 P 0 8 0;1=2
P 5.121 2.495 6 P 0 8 0;1=2
P 5.121 2.625 6 P 0 8 0;1=2
P 5.41346004 3.03506998 6 P 0 8 0;1=2
P 5.814 2.9225 6 P 0 8 0;1=2
P 5.25176004 4.11925 6 P 0 8 0;1=2
P 5.88778996 3.34448996 12 P 0 8 0;1=13
P 5.88778996 3.50983996 12 P 0 8 0;1=13
P 5.88778996 3.67518996 12 P 0 8 0;1=13
P 5.538 2.402 6 P 0 8 0;1=2
P 5.666 2.129 5 P 0 8 0;1=9
P 5.647 2.044 6 P 0 8 0;1=2
P 5.687 2.043 6 P 0 8 0;1=2
P 5.732 2.043 6 P 0 8 0;1=2
P 5.865 2.3 6 P 0 8 0;1=2
P 6.36 2.16141998 6 P 0 8 0;1=2
P 6.51581998 2.24803996 18 P 0 8 0;1=19
P 6.51581998 1.97243996 18 P 0 8 0;1=20
P 6.40951998 2.20866998 9 P 0 8 0;1=21
P 6.40951998 2.01181004 9 P 0 8 0;1=21
P 0.06038996 1.38346004 11 P 0 8 0;1=22
P 0.26038996 1.38346004 11 P 0 8 0;1=22
P 0.06038996 1.18346004 11 P 0 8 0;1=22
P 0.26038996 1.18346004 11 P 0 8 0;1=22
P 0.06038996 0.8126 11 P 0 8 0;1=22
P 0.26038996 0.8126 11 P 0 8 0;1=22
P 0.06038996 0.6126 11 P 0 8 0;1=22
P 0.26038996 0.6126 11 P 0 8 0;1=22
P 0.06038996 2.5252 11 P 0 8 0;1=22
P 0.26038996 2.5252 11 P 0 8 0;1=22
P 0.06038996 2.3252 11 P 0 8 0;1=22
P 0.26038996 2.3252 11 P 0 8 0;1=22
P 0.06038996 1.95433002 11 P 0 8 0;1=22
P 0.26038996 1.95433002 11 P 0 8 0;1=22
P 0.06038996 1.75433002 11 P 0 8 0;1=22
P 0.26038996 1.75433002 11 P 0 8 0;1=22
P 1.26066998 1.84043002 13 P 0 8 0;1=14
P 5.91901998 2.003 5 P 0 8 0;1=7
P 6.06901998 2.004 5 P 0 8 0;1=7
P 3.49 0.825 5 P 0 8 0;1=7
P 2.65966998 0.93443002 13 P 0 8 0;1=14
P 6.095 2.545 6 P 0 8 0;1=0
P 5.07 1.885 6 P 0 8 0;1=2
P 5.33 0.995 5 P 0 8 0;1=9
P 3.54 0.825 6 P 0 8 0;1=2
P 6.04 2.545 6 P 0 8 0;1=0
P 5.07 1.925 6 P 0 8 0;1=2
P 5.33 0.95 5 P 0 8 0;1=9
P 2.53966998 0.93443002 13 P 0 8 0;1=14
P 2.802 1.987 5 P 0 8 0;1=9
P 2.834 1.987 5 P 0 8 0;1=9
P 2.845 1.875 5 P 0 8 0;1=9
P 2.845 1.843 5 P 0 8 0;1=9
P 2.77866998 0.93443002 13 P 0 8 0;1=14
P 4.97 1.54 4 P 0 8 0;1=3
P 4.9806 1.855 6 P 0 8 0;1=0
P 1.26066998 1.04043002 13 P 0 8 0;1=14
P 0.724 2.646 6 P 0 8 0;1=0
P 0.758 2.743 3 P 0 8 0;1=4
P 3.235 2.63 4 P 0 8 0;1=3
P 3.275 2.32 3 P 0 8 0;1=4
P 3.24 2.275 6 P 0 8 0;1=0
P 3.305 2.65 4 P 0 8 0;1=3
P 3.375 2.65 4 P 0 8 0;1=3
P 3.326 2.466 3 P 0 8 0;1=4
P 2.1481 0.7881 5 P 0 8 0;1=7
P 5.08 1.105 6 P 0 8 0;1=2
P 5.225 1.145 6 P 0 8 0;1=2
P 5.132 0.66 6 P 0 8 0;1=2
P 2.0816 0.7399 6 P 0 8 0;1=2
P 2.03 0.75 5 P 0 8 0;1=7
P 5.08 1.155 6 P 0 8 0;1=2
P 5.08 1.055 6 P 0 8 0;1=2
P 2.0788 0.7874 5 P 0 8 0;1=7
P 2.29581998 0.48918002 4 P 0 8 0;1=3
P 2.633 0.522 5 P 0 8 0;1=9
P 3.455 0.87 6 P 0 8 0;1=2
P 0.9225 0.9775 6 P 0 8 0;1=2
P 4.82 0.835 6 P 0 8 0;1=0
P 0.8825 1.7725 6 P 0 8 0;1=2
P 3.405 0.87 6 P 0 8 0;1=2
P 0.965 0.98 6 P 0 8 0;1=2
P 0.91 1.815 6 P 0 8 0;1=0
P 4.78 0.78 6 P 0 8 0;1=2
P 4.42311004 1.86311004 3 P 0 8 0;1=11
P 3.65101004 1.88358996 4 P 0 8 0;1=8
P 4.46248002 1.86311004 3 P 0 8 0;1=11
P 3.65101004 1.91558996 4 P 0 8 0;1=8
P 3.065 1.695 4 P 0 8 0;1=3
P 2.98283996 1.75183996 6 P 0 8 0;1=2
P 2.225 3.245 6 P 0 8 0;1=2
P 4.595 2.62 6 P 0 8 0;1=2
P 4.025 3.08 6 P 0 8 0;1=2
P 0.62 3.07 6 P 0 8 0;1=2
P 5.865 1.125 6 P 0 8 0;1=0
P 5.865 1.07 6 P 0 8 0;1=0
P 2.265 3.34 6 P 0 8 0;1=2
P 4.57 2.585 6 P 0 8 0;1=2
P 4.02 3.03 6 P 0 8 0;1=2
P 0.645 2.9675 6 P 0 8 0;1=2
P 5.48828996 4.16328996 6 P 0 8 0;1=0
P 3.99005 1.90248002 4 P 0 8 0;1=1
P 5.55315 4.175 6 P 0 8 0;1=0
P 3.99005 1.86311004 4 P 0 8 0;1=1
P 5.67126004 4.175 6 P 0 8 0;1=0
P 3.95066998 1.82373996 4 P 0 8 0;1=1
P 5.78936998 4.175 6 P 0 8 0;1=0
P 3.9113 1.82373996 4 P 0 8 0;1=1
P 4.205 2.295 4 P 0 8 0;1=3
P 4.65933002 1.6269 4 P 0 8 0;1=3
P 4.254 2.296 4 P 0 8 0;1=3
P 4.23 2.354 4 P 0 8 0;1=3
P 4.915 1.485 4 P 0 8 0;1=3
P 4.65933002 1.54816004 4 P 0 8 0;1=1
P 3.94 2.235 4 P 0 8 0;1=3
P 4.85 1.54 4 P 0 8 0;1=3
P 4.149 2.298 4 P 0 8 0;1=3
P 4.161 2.354 4 P 0 8 0;1=3
P 3.75 2.1 4 P 0 8 0;1=3
P 4.975 1.485 4 P 0 8 0;1=3
P 4.58058996 1.58753002 4 P 0 8 0;1=1
P 3.8 2.1 4 P 0 8 0;1=3
P 4.73806998 1.54816004 4 P 0 8 0;1=3
P 3.9 2.325 4 P 0 8 0;1=3
P 4.73806998 1.50878996 4 P 0 8 0;1=3
P 3.83 2.325 4 P 0 8 0;1=3
P 0.846 2.489 3 P 0 8 0;1=4
P 3.28 3.065 6 P 0 8 0;1=2
P 0.796 2.489 3 P 0 8 0;1=4
P 3.325 3.065 6 P 0 8 0;1=2
P 5.03 3.546 3 P 0 8 0;1=4
P 4.935 3.59 3 P 0 8 0;1=4
P 4.67 3.555 4 P 0 8 0;1=3
P 4.885 3.59 5 P 0 8 0;1=7
P 4.70461998 3.69461998 3 P 0 8 0;1=4
P 4.50185 1.82373996 4 P 0 8 0;1=1
P 5.395 2.92 6 P 0 8 0;1=0
P 5.015 1.925 6 P 0 8 0;1=2
P 5.39976998 2.75123996 5 P 0 8 0;1=7
P 4.46248002 1.82373996 4 P 0 8 0;1=1
P 5.375 2.96606998 5 P 0 8 0;1=7
P 4.58058996 1.78436998 4 P 0 8 0;1=1
P 5.4525 2.563 5 P 0 8 0;1=7
P 3.545 0.6092 6 P 0 8 0;1=2
P 1.395 0.625 5 P 0 8 0;1=7
P 5.085 0.645 6 P 0 8 0;1=2
P 3.495 0.61 6 P 0 8 0;1=2
P 5.04 0.645 6 P 0 8 0;1=2
P 1.485 0.625 5 P 0 8 0;1=7
P 3.99005 1.6269 3 P 0 8 0;1=11
P 2.95835 0.385 4 P 0 8 0;1=8
P 3.95066998 1.6269 3 P 0 8 0;1=11
P 2.95835 0.353 4 P 0 8 0;1=8
P 3.9113 1.66626998 3 P 0 8 0;1=11
P 2.80086998 0.385 4 P 0 8 0;1=8
P 3.87193002 1.66626998 3 P 0 8 0;1=11
P 2.80086998 0.353 4 P 0 8 0;1=8
P 3.99005 1.70563996 3 P 0 8 0;1=11
P 2.64338996 0.385 4 P 0 8 0;1=8
P 3.95066998 1.70563996 3 P 0 8 0;1=11
P 2.64338996 0.353 4 P 0 8 0;1=8
P 3.9113 1.58753002 3 P 0 8 0;1=11
P 2.95835 0.481 4 P 0 8 0;1=8
P 2.95835 0.449 4 P 0 8 0;1=8
P 3.87193002 1.58753002 3 P 0 8 0;1=11
P 3.125 0.875 4 P 0 8 0;1=8
P 3.99005 1.54816004 3 P 0 8 0;1=11
P 3.14763002 0.85236998 4 P 0 8 0;1=8
P 3.95066998 1.54816004 3 P 0 8 0;1=11
P 2.81855 0.763 4 P 0 8 0;1=8
P 3.9113 1.50878996 3 P 0 8 0;1=11
P 2.85055 0.763 4 P 0 8 0;1=8
P 3.87193002 1.50878996 3 P 0 8 0;1=11
P 2.66706998 0.763 4 P 0 8 0;1=8
P 3.99005 1.46941998 3 P 0 8 0;1=11
P 2.69906998 0.763 4 P 0 8 0;1=8
P 3.95066998 1.46941998 3 P 0 8 0;1=11
P 2.47021998 0.763 4 P 0 8 0;1=8
P 3.9113 1.43005 3 P 0 8 0;1=11
P 2.50221998 0.763 4 P 0 8 0;1=8
P 3.87193002 1.43005 3 P 0 8 0;1=11
P 1.889 0.5496 6 P 0 8 0;1=2
P 2.435 0.4865 3 P 0 8 0;1=4
P 3.56 3.023 6 P 0 8 0;1=0
P 3.57 2.955 6 P 0 8 0;1=0
P 4.975 2.14 6 P 0 8 0;1=2
P 5.03005 0.99493996 6 P 0 8 0;1=0
P 5.638 3.907 6 P 0 8 0;1=0
P 1.8317 0.5639 5 P 0 8 0;1=7
P 2.68566998 1.12143002 14 P 0 8 0;1=23
P 2.68566998 2.55943002 14 P 0 8 0;1=23
P 1.46066998 2.68043002 14 P 0 8 0;1=23
P 1.43566998 1.06043002 14 P 0 8 0;1=23
P 6.40038996 0.65353996 16 P 0 8 0;1=24
P 0.29528002 3.73031004 16 P 0 8 0;1=24
P 0.29528002 0.36811004 16 P 0 8 0;1=24
P 6.40038996 4.17835 16 P 0 8 0;1=24
P 6.34055 3.34448996 15 P 0 8 0;1=25
P 6.34055 3.67518996 15 P 0 8 0;1=25
L 3.80999961 -1.25 3.80999961 -1.33 1 N 0 ;0
L 3.80999961 -1.33 3.8500003 -1.33 1 N 0 ;0
L 3.90999902 -1.25 3.90199892 -1.25266614 1 N 0 ;0
L 3.90199892 -1.25266614 3.8960002 -1.25933386 1 N 0 ;0
L 3.8960002 -1.25933386 3.89199921 -1.26733209 1 N 0 ;0
L 3.89199921 -1.26733209 3.8889999 -1.27800138 1 N 0 ;0
L 3.8889999 -1.27800138 3.8880001 -1.29000128 1 N 0 ;0
L 3.8880001 -1.29000128 3.8889999 -1.30200118 1 N 0 ;0
L 3.8889999 -1.30200118 3.89199921 -1.31266801 1 N 0 ;0
L 3.89199921 -1.31266801 3.8960002 -1.3206687 1 N 0 ;0
L 3.8960002 -1.3206687 3.90199892 -1.32733396 1 N 0 ;0
L 3.90199892 -1.32733396 3.90999902 -1.33 1 N 0 ;0
L 3.90999902 -1.33 3.91799911 -1.32733396 1 N 0 ;0
L 3.91799911 -1.32733396 3.9239997 -1.3206687 1 N 0 ;0
L 3.9239997 -1.3206687 3.92800069 -1.31266801 1 N 0 ;0
L 3.92800069 -1.31266801 3.931 -1.30200118 1 N 0 ;0
L 3.931 -1.30200118 3.9319998 -1.29000128 1 N 0 ;0
L 3.9319998 -1.29000128 3.931 -1.27800138 1 N 0 ;0
L 3.931 -1.27800138 3.92800069 -1.26733209 1 N 0 ;0
L 3.92800069 -1.26733209 3.9239997 -1.25933386 1 N 0 ;0
L 3.9239997 -1.25933386 3.91799911 -1.25266614 1 N 0 ;0
L 3.91799911 -1.25266614 3.90999902 -1.25 1 N 0 ;0
L 3.97099941 -1.296669 3.9779998 -1.28733278 1 N 0 ;0
L 3.9779998 -1.28733278 3.9840003 -1.28200049 1 N 0 ;0
L 3.9840003 -1.28200049 3.99200039 -1.27933445 1 N 0 ;0
L 3.99200039 -1.27933445 3.99900079 -1.28200049 1 N 0 ;0
L 3.99900079 -1.28200049 4.0039997 -1.28733278 1 N 0 ;0
L 4.0039997 -1.28733278 4.00800069 -1.29533346 1 N 0 ;0
L 4.00800069 -1.29533346 4.00900049 -1.30466722 1 N 0 ;0
L 4.00900049 -1.30466722 4.00800069 -1.31266801 1 N 0 ;0
L 4.00800069 -1.31266801 4.0039997 -1.3206687 1 N 0 ;0
L 4.0039997 -1.3206687 3.99799911 -1.32733396 1 N 0 ;0
L 3.99799911 -1.32733396 3.99100069 -1.33 1 N 0 ;0
L 3.99100069 -1.33 3.98300049 -1.32733396 1 N 0 ;0
L 3.98300049 -1.32733396 3.9760002 -1.31933563 1 N 0 ;0
L 3.9760002 -1.31933563 3.97199921 -1.30733337 1 N 0 ;0
L 3.97199921 -1.30733337 3.97099941 -1.29400039 1 N 0 ;0
L 3.97099941 -1.29400039 3.97299902 -1.27666831 1 N 0 ;0
L 3.97299902 -1.27666831 3.9760002 -1.26733209 1 N 0 ;0
L 3.9760002 -1.26733209 3.98099911 -1.25800079 1 N 0 ;0
L 3.98099911 -1.25800079 3.98799951 -1.25133307 1 N 0 ;0
L 3.98799951 -1.25133307 3.9949998 -1.25 1 N 0 ;0
L 3.9949998 -1.25 4.0020001 -1.25266614 1 N 0 ;0
L 4.0020001 -1.25266614 4.00700089 -1.25933386 1 N 0 ;0
L 4.04 -1.35666585 4.1 -1.35666585 1 N 0 ;0
L 4.12499892 -1.25 4.14999902 -1.33 1 N 0 ;0
L 4.14999902 -1.33 4.17500098 -1.25 1 N 0 ;0
L 4.2519998 -1.25666772 4.24599931 -1.25266614 1 N 0 ;0
L 4.24599931 -1.25266614 4.23900079 -1.25 1 N 0 ;0
L 4.23900079 -1.25 4.23100069 -1.25 1 N 0 ;0
L 4.23100069 -1.25 4.22199892 -1.25400167 1 N 0 ;0
L 4.22199892 -1.25400167 4.21500039 -1.26066683 1 N 0 ;0
L 4.21500039 -1.26066683 4.20999961 -1.26866762 1 N 0 ;0
L 4.20999961 -1.26866762 4.20599862 -1.28200049 1 N 0 ;0
L 4.20599862 -1.28200049 4.20499892 -1.29400039 1 N 0 ;0
L 4.20499892 -1.29400039 4.2070003 -1.3060003 1 N 0 ;0
L 4.2070003 -1.3060003 4.20999961 -1.31400098 1 N 0 ;0
L 4.20999961 -1.31400098 4.2160002 -1.32200177 1 N 0 ;0
L 4.2160002 -1.32200177 4.22300049 -1.32733396 1 N 0 ;0
L 4.22300049 -1.32733396 4.22999902 -1.33 1 N 0 ;0
L 4.22999902 -1.33 4.23699941 -1.33 1 N 0 ;0
L 4.23699941 -1.33 4.2439997 -1.32733396 1 N 0 ;0
L 4.2439997 -1.32733396 4.2500003 -1.32333484 1 N 0 ;0
L 4.2500003 -1.32333484 4.25500098 -1.31800266 1 N 0 ;0
L 4.3319998 -1.25666772 4.32599931 -1.25266614 1 N 0 ;0
L 4.32599931 -1.25266614 4.31900079 -1.25 1 N 0 ;0
L 4.31900079 -1.25 4.31100069 -1.25 1 N 0 ;0
L 4.31100069 -1.25 4.30199892 -1.25400167 1 N 0 ;0
L 4.30199892 -1.25400167 4.29500039 -1.26066683 1 N 0 ;0
L 4.29500039 -1.26066683 4.28999961 -1.26866762 1 N 0 ;0
L 4.28999961 -1.26866762 4.28599862 -1.28200049 1 N 0 ;0
L 4.28599862 -1.28200049 4.28499892 -1.29400039 1 N 0 ;0
L 4.28499892 -1.29400039 4.2870003 -1.3060003 1 N 0 ;0
L 4.2870003 -1.3060003 4.28999961 -1.31400098 1 N 0 ;0
L 4.28999961 -1.31400098 4.2960002 -1.32200177 1 N 0 ;0
L 4.2960002 -1.32200177 4.30300049 -1.32733396 1 N 0 ;0
L 4.30300049 -1.32733396 4.30999902 -1.33 1 N 0 ;0
L 4.30999902 -1.33 4.31699941 -1.33 1 N 0 ;0
L 4.31699941 -1.33 4.3239997 -1.32733396 1 N 0 ;0
L 4.3239997 -1.32733396 4.3300003 -1.32333484 1 N 0 ;0
L 4.3300003 -1.32333484 4.33500098 -1.31800266 1 N 0 ;0
L 4.37099941 -1.26333297 4.377 -1.25533465 1 N 0 ;0
L 4.377 -1.25533465 4.3840003 -1.25133307 1 N 0 ;0
L 4.3840003 -1.25133307 4.39200039 -1.25 1 N 0 ;0
L 4.39200039 -1.25 4.4020001 -1.25266614 1 N 0 ;0
L 4.4020001 -1.25266614 4.40900049 -1.25933386 1 N 0 ;0
L 4.40900049 -1.25933386 4.411 -1.26733209 1 N 0 ;0
L 4.411 -1.26733209 4.4100003 -1.27533533 1 N 0 ;0
L 4.4100003 -1.27533533 4.40599931 -1.28200049 1 N 0 ;0
L 4.40599931 -1.28200049 4.3859999 -1.29533346 1 N 0 ;0
L 4.3859999 -1.29533346 4.377 -1.30466722 1 N 0 ;0
L 4.377 -1.30466722 4.37099941 -1.31800266 1 N 0 ;0
L 4.37099941 -1.31800266 4.3689999 -1.33 1 N 0 ;0
L 4.3689999 -1.33 4.411 -1.33 1 N 0 ;0
L 3.16 -0.655 3.16 -1.58 2 N 0 ;0
L 1.36 -0.655 1.36 -1.58 2 N 0 ;0
L 1.36 -1.58 5.06 -1.58 2 N 0 ;0
L 5.06 -1.58 5.06 -0.655 2 N 0 ;0
L 5.06 -0.655 1.36 -0.655 2 N 0 ;0
A 1.559 -1.33655 1.559 -1.33655 1.55268002 -1.33655 1 N 0 N;0
A 1.54775 -1.205 1.54775 -1.205 1.53883002 -1.205 1 N 0 N;0
A 1.54763996 -0.99775 1.54763996 -0.99775 1.53871998 -0.99775 1 N 0 N;0
A 1.54063996 -1.10118002 1.54063996 -1.10118002 1.52603996 -1.10118002 1 N 0 N;0
A 1.49695 -1.10118002 1.49695 -1.10118002 1.48656998 -1.10118002 1 N 0 N;0
A 1.45963996 -1.10118002 1.45963996 -1.10118002 1.4533 -1.10118002 1 N 0 N;0
A 1.52135 -0.98681004 1.52135 -0.98681004 1.51503002 -0.98681004 1 N 0 N;0
A 1.79433002 -1.43586998 1.79433002 -1.43586998 1.78798996 -1.43586998 1 N 0 N;0
A 1.79841004 -1.40261004 1.79841004 -1.40261004 1.78798996 -1.40261004 1 N 0 N;0
A 1.80255 -1.36311004 1.80255 -1.36311004 1.78798996 -1.36311004 1 N 0 N;0
A 1.80668996 -1.31528002 1.80668996 -1.31528002 1.78798996 -1.31528002 1 N 0 N;0
A 1.68013002 -1.37456004 1.68013002 -1.37456004 1.67378996 -1.37456004 1 N 0 N;0
A 1.69321998 -1.35033002 1.69321998 -1.35033002 1.6843 -1.35033002 1 N 0 N;0
A 1.7108 -1.31738996 1.7108 -1.31738996 1.69798002 -1.31738996 1 N 0 N;0
A 1.89666998 -1.31511004 1.89666998 -1.31511004 1.88383996 -1.31511004 1 N 0 N;0
A 1.88198996 -1.16876004 1.88198996 -1.16876004 1.85558996 -1.16876004 1 N 0 N;0
A 1.87928002 -1.27801998 1.87928002 -1.27801998 1.86343996 -1.27801998 1 N 0 N;0
A 1.86176998 -1.23075 1.86176998 -1.23075 1.84206004 -1.23075 1 N 0 N;0
A 1.80978996 -1.25916998 1.80978996 -1.25916998 1.78798996 -1.25916998 1 N 0 N;0
A 1.74681004 -1.16876004 1.74681004 -1.16876004 1.72041004 -1.16876004 1 N 0 N;0
A 1.67813002 -1.15513002 1.67813002 -1.15513002 1.65841998 -1.15513002 1 N 0 N;0
A 1.73018002 -1.27816004 1.73018002 -1.27816004 1.71433996 -1.27816004 1 N 0 N;0
A 1.75373002 -1.23081004 1.75373002 -1.23081004 1.73405 -1.23081004 1 N 0 N;0
A 1.65531004 -1.25255 1.65531004 -1.25255 1.63661998 -1.25255 1 N 0 N;0
A 1.69808996 -1.21291998 1.69808996 -1.21291998 1.67628996 -1.21291998 1 N 0 N;0
A 1.81438996 -1.1968 1.81438996 -1.1968 1.78798996 -1.1968 1 N 0 N;0
A 1.6269 -1.1749 1.6269 -1.1749 1.61106004 -1.1749 1 N 0 N;0
A 1.58461004 -1.19126004 1.58461004 -1.19126004 1.57178002 -1.19126004 1 N 0 N;0
A 1.5853 -1.31428002 1.5853 -1.31428002 1.57488996 -1.31428002 1 N 0 N;0
A 1.61735 -1.28638996 1.61735 -1.28638996 1.60276998 -1.28638996 1 N 0 N;0
A 1.88198996 -1.03361004 1.88198996 -1.03361004 1.85558996 -1.03361004 1 N 0 N;0
A 1.71881004 -1.10118002 1.71881004 -1.10118002 1.69238996 -1.10118002 1 N 0 N;0
A 1.65183002 -1.10118002 1.65183002 -1.10118002 1.63003002 -1.10118002 1 N 0 N;0
A 1.67801998 -1.04738996 1.67801998 -1.04738996 1.65831004 -1.04738996 1 N 0 N;0
A 1.74681004 -1.03361004 1.74681004 -1.03361004 1.72041004 -1.03361004 1 N 0 N;0
A 1.69811998 -0.98951004 1.69811998 -0.98951004 1.67631998 -0.98951004 1 N 0 N;0
A 1.81438996 -1.00556004 1.81438996 -1.00556004 1.78798996 -1.00556004 1 N 0 N;0
A 1.59258002 -1.10118002 1.59258002 -1.10118002 1.5739 -1.10118002 1 N 0 N;0
A 1.58451004 -1.01148996 1.58451004 -1.01148996 1.57168002 -1.01148996 1 N 0 N;0
A 1.62681004 -1.02773996 1.62681004 -1.02773996 1.61096998 -1.02773996 1 N 0 N;0
A 1.92148002 -1.21285 1.92148002 -1.21285 1.89968002 -1.21285 1 N 0 N;0
A 1.92148002 -0.98951004 1.92148002 -0.98951004 1.89968002 -0.98951004 1 N 0 N;0
A 1.80978996 -0.9432 1.80978996 -0.9432 1.78798996 -0.9432 1 N 0 N;0
A 1.80668996 -0.88708002 1.80668996 -0.88708002 1.78798996 -0.88708002 1 N 0 N;0
A 1.80255 -0.83923996 1.80255 -0.83923996 1.78798996 -0.83923996 1 N 0 N;0
A 1.8919 -0.88538002 1.8919 -0.88538002 1.87906998 -0.88538002 1 N 0 N;0
A 1.87838996 -0.92456998 1.87838996 -0.92456998 1.86255 -0.92456998 1 N 0 N;0
A 1.65531004 -0.94981004 1.65531004 -0.94981004 1.63661998 -0.94981004 1 N 0 N;0
A 1.73123002 -0.92378002 1.73123002 -0.92378002 1.71538996 -0.92378002 1 N 0 N;0
A 1.71216998 -0.88443996 1.71216998 -0.88443996 1.69935 -0.88443996 1 N 0 N;0
A 1.86225 -0.97178002 1.86225 -0.97178002 1.84253996 -0.97178002 1 N 0 N;0
A 1.75451998 -0.97123996 1.75451998 -0.97123996 1.73483996 -0.97123996 1 N 0 N;0
A 1.61741998 -0.91601004 1.61741998 -0.91601004 1.60283996 -0.91601004 1 N 0 N;0
A 1.5853 -0.88808996 1.5853 -0.88808996 1.57488996 -0.88808996 1 N 0 N;0
A 1.79841004 -0.79975 1.79841004 -0.79975 1.78798996 -0.79975 1 N 0 N;0
A 1.79433002 -0.76648002 1.79433002 -0.76648002 1.78798996 -0.76648002 1 N 0 N;0
A 1.92135 -1.36781004 1.92135 -1.36781004 1.91503996 -1.36781004 1 N 0 N;0
A 1.91096004 -1.34658002 1.91096004 -1.34658002 1.90203996 -1.34658002 1 N 0 N;0
A 2.19078996 -1.1806 2.26591004 -1.16473002 2.21741014 -1.12088169 1 N 0 N;0
A 2.15903002 -1.1402 2.19078996 -1.18061004 2.22093406 -1.12423278 1 N 0 N;0
A 2.05721004 -1.16178996 2.08853002 -1.16658996 2.08281614 -1.09929134 1 N 0 N;0
A 2.00546998 -1.13951998 2.03345 -1.17196004 2.07793927 -1.10530069 1 N 0 N;0
A 2.03346004 -1.17195 2.0847 -1.18461004 2.07891181 -1.09801299 1 N 0 N;0
A 2.0847 -1.18461998 2.14261004 -1.15663002 2.07348435 -1.08751378 1 N 0 N;0
A 2.08853996 -1.16658002 2.13313002 -1.14451998 2.06368967 -1.06025512 1 N 0 N;0
A 1.95808002 -1.25255 1.95808002 -1.25255 1.93938996 -1.25255 1 N 0 N;0
A 1.98775 -1.28635 1.98775 -1.28635 1.97316998 -1.28635 1 N 0 N;0
A 2.27411998 -1.11835 2.15906004 -1.11835 2.21658996 -1.11611998 1 N 0 N;0
L 2.25188002 -1.11418002 2.1807 -1.11418002 1 N 0 ;0
L 2.1807 -1.11418002 2.1807 -1.11398996 1 N 8191 ;0
A 2.25188996 -1.11398996 2.18071004 -1.11398996 2.2163 -1.1124 1 N 0 N;0
A 2.08028996 -1.03428996 2.02048996 -1.08258996 2.0798126 -1.09486801 1 N 0 N;0
A 2.13151998 -1.05146004 2.0803 -1.0343 2.0802999 -1.11932195 1 N 0 N;0
A 2.1315 -1.05146998 2.14175 -1.03951004 2.1356003 -1.04461171 1 N 0 N;0
A 2.14175 -1.03951004 2.08283002 -1.01613002 2.07772461 -1.11492805 1 N 0 N;0
A 2.08283996 -1.01611998 2.00698002 -1.05835 2.08064724 -1.10143169 1 N 0 N;0
L 2.27413002 -1.12868996 2.18073996 -1.12868996 1 N 0 ;0
A 2.18075 -1.12868996 2.19083002 -1.15751998 2.22417795 -1.12968307 1 N 0 N;0
A 2.19083002 -1.15753002 2.25311004 -1.15211004 2.21927195 -1.12381791 1 N 0 N;0
L 2.15903996 -1.1402 2.15903996 -1.11835 1 N 8191 ;0
A 2.02048996 -1.0826 2.05721998 -1.16181004 2.09087933 -1.0980811 1 N 0 N;0
A 2.00698996 -1.05836004 2.00546998 -1.13953002 2.09672953 -1.10063967 1 N 0 N;0
A 2.14258996 -1.15661004 2.13313996 -1.14453002 2.13544892 -1.15246004 1 N 0 N;0
A 1.95808002 -0.94981004 1.95808002 -0.94981004 1.93938996 -0.94981004 1 N 0 N;0
A 1.90183996 -0.8525 1.90183996 -0.8525 1.89291004 -0.8525 1 N 0 N;0
A 1.91108002 -0.82726998 1.91108002 -0.82726998 1.90473996 -0.82726998 1 N 0 N;0
L 2.32081004 -1.02041004 2.32081004 -1.17625 1 N 0 ;0
A 2.49568002 -1.15528996 2.47898002 -1.16443002 2.4882003 -1.1614502 1 N 0 N;0
A 2.47896998 -1.16443996 2.50283002 -1.18086004 2.51649242 -1.13546152 1 N 0 N;0
A 2.50281998 -1.18086998 2.54318002 -1.1834 2.52887392 -1.08843022 1 N 0 N;0
A 2.52306998 -1.16761004 2.52848996 -1.16771998 2.52673258 -1.12070098 1 N 0 N;0
A 2.49566004 -1.15528996 2.52306998 -1.1676 2.5255122 -1.12549094 1 N 0 N;0
A 2.37851998 -1.15753002 2.4408 -1.15211004 2.40696191 -1.12381791 1 N 0 N;0
A 2.45358002 -1.16471998 2.44078996 -1.1521 2.44541191 -1.16020689 1 N 0 N;0
A 2.37848002 -1.1806 2.4536 -1.16473002 2.4051001 -1.12088169 1 N 0 N;0
A 2.34673002 -1.1402 2.37848996 -1.18061004 2.40863406 -1.12423278 1 N 0 N;0
A 2.2659 -1.16471998 2.25311004 -1.1521 2.25773199 -1.16020689 1 N 0 N;0
A 2.3006 -1.17626004 2.3208 -1.17626004 2.3107 -1.17386841 1 N 0 N;0
L 2.30058996 -1.17625 2.30058996 -1.02033996 1 N 0 ;0
A 2.50836998 -1.10106004 2.54306004 -1.11513002 2.56106673 -1.02093386 1 N 0 N;0
A 2.51081004 -1.07948002 2.50836998 -1.10103996 2.51886093 -1.09130915 1 N 0 N;0
A 2.53611004 -1.07688996 2.5108 -1.07948996 2.52742205 -1.11680827 1 N 0 N;0
A 2.56883996 -1.07368002 2.50178002 -1.06358996 2.5273123 -1.12178858 1 N 0 N;0
A 2.50178996 -1.06358996 2.48536998 -1.08248996 2.52926211 -1.10403986 1 N 0 N;0
L 2.48536998 -1.0825 2.48536998 -1.09748002 1 N 8191 ;0
A 2.48536998 -1.09748002 2.49956004 -1.12031004 2.51189104 -1.09682067 1 N 0 N;0
A 2.46181004 -1.11835 2.34675 -1.11835 2.40428002 -1.11611998 1 N 0 N;0
L 2.43956998 -1.11418002 2.36841004 -1.11418002 1 N 0 ;0
L 2.36841004 -1.11418002 2.36841004 -1.11398996 1 N 8191 ;0
A 2.43958002 -1.11398996 2.3684 -1.11398996 2.40398996 -1.1124 1 N 0 N;0
L 2.43956998 -1.11398996 2.43956998 -1.11418002 1 N 8191 ;0
A 2.49955 -1.1203 2.52723002 -1.12985 2.58163209 -0.92727982 1 N 0 N;0
A 2.55001998 -1.14328002 2.52723002 -1.12986004 2.51462185 -1.17733228 1 N 0 N;0
L 2.46181004 -1.12868996 2.36843996 -1.12868996 1 N 0 ;0
A 2.36843996 -1.12868996 2.37851998 -1.15751998 2.41186801 -1.12968307 1 N 0 N;0
L 2.34675 -1.1402 2.34675 -1.11835 1 N 8191 ;0
L 2.46181004 -1.11835 2.46181004 -1.12868996 1 N 8191 ;0
L 2.25188002 -1.11398996 2.25188002 -1.11418002 1 N 8191 ;0
A 2.3208 -1.02041004 2.3006 -1.02033996 2.31069163 -1.02276978 1 N 0 N;0
L 2.27413002 -1.11835 2.27413002 -1.12868996 1 N 8191 ;0
A 2.52848996 -1.16771004 2.54891998 -1.15895 2.52774557 -1.13777087 1 N 0 N;0
A 2.55608002 -1.08618002 2.53611998 -1.07688996 2.5249185 -1.12704419 1 N 0 N;0
L 2.71926004 -1.06796998 2.71926004 -1.17483996 1 N 0 ;0
A 2.78888996 -1.16296998 2.81508002 -1.16676998 2.8083499 -1.12100167 1 N 0 N;0
A 2.8151 -1.16675 2.83966004 -1.15211998 2.80521398 -1.12222392 1 N 0 N;0
A 2.85201004 -1.16508002 2.83966004 -1.15211004 2.84505768 -1.15933514 1 N 0 N;0
L 2.85201004 -1.16508002 2.84523996 -1.17161004 1 N 8191 ;0
A 2.81425 -1.1835 2.84525 -1.17161004 2.81425 -1.13714291 1 N 0 N;0
L 2.81425 -1.1835 2.79571004 -1.1835 1 N 8191 ;0
A 2.75886998 -1.16443002 2.79571998 -1.18351998 2.80278976 -1.12476142 1 N 0 N;0
A 2.74528996 -1.13568002 2.75888002 -1.16443002 2.80246565 -1.12624016 1 N 0 N;0
A 2.54316998 -1.1834 2.56906004 -1.1647 2.5305814 -1.13869892 1 N 0 N;0
A 2.56906004 -1.1647 2.57053996 -1.13728002 2.53763041 -1.14925374 1 N 0 N;0
A 2.65463996 -1.18351998 2.66863996 -1.17373996 2.65440246 -1.16826969 1 N 0 N;0
L 2.65463002 -1.1835 2.64165 -1.1835 1 N 8191 ;0
A 2.60955 -1.16043002 2.64163996 -1.18351004 2.63911063 -1.15317815 1 N 0 N;0
A 2.62978002 -1.15461998 2.66001998 -1.16328996 2.6502374 -1.14033868 1 N 0 N;0
A 2.66863996 -1.17375 2.66001998 -1.16328996 2.66100344 -1.17126132 1 N 0 N;0
A 2.6962 -1.17483996 2.71926004 -1.17483996 2.70773002 -1.17286427 1 N 0 N;0
L 2.69618996 -1.17483996 2.69618996 -1.06796998 1 N 0 ;0
A 2.83833002 -1.09275 2.82661998 -1.08201998 2.74555758 -1.18224094 1 N 0 N;0
A 2.82661998 -1.08198996 2.80036998 -1.07538996 2.80348839 -1.11848878 1 N 0 N;0
A 2.80036004 -1.07541998 2.76848996 -1.09933002 2.80700217 -1.1174685 1 N 0 N;0
A 2.76848996 -1.09931998 2.76446004 -1.12066004 2.82315728 -1.120694 1 N 0 N;0
A 2.74998002 -1.09273996 2.74528996 -1.11838996 2.8498563 -1.12425591 1 N 0 N;0
A 2.7954 -1.05776998 2.74998996 -1.09273996 2.80799961 -1.12109961 1 N 0 N;0
L 2.79541004 -1.05776998 2.80918996 -1.05776998 1 N 8191 ;0
A 2.85401998 -1.08106004 2.80918996 -1.05776998 2.80626024 -1.1181998 1 N 0 N;0
A 2.83833002 -1.09273996 2.85403002 -1.08106004 2.84418386 -1.08421683 1 N 0 N;0
L 2.76445 -1.12066004 2.76445 -1.12943002 1 N 8191 ;0
A 2.76446004 -1.12943002 2.76836998 -1.14305 2.80607844 -1.12485364 1 N 0 N;0
A 2.76836998 -1.14305 2.78891004 -1.16296998 2.80906152 -1.12164144 1 N 0 N;0
L 2.74528996 -1.13566004 2.74528996 -1.11838996 1 N 8191 ;0
A 2.55606004 -1.0862 2.56885 -1.07366998 2.56205354 -1.0795252 1 N 0 N;0
L 2.60953996 -1.07953996 2.59981998 -1.07953996 1 N 8191 ;0
A 2.5993 -1.05931998 2.59981004 -1.07955 2.6022813 -1.06936624 1 N 0 N;0
L 2.5993 -1.05931998 2.60953996 -1.05931998 1 N 8191 ;0
L 2.60953996 -1.05931998 2.60953996 -1.03491998 1 N 8191 ;0
A 2.62971998 -1.03418002 2.60953996 -1.03491004 2.61966791 -1.03559478 1 N 0 N;0
L 2.62971004 -1.03418996 2.62978002 -1.05931998 1 N 8191 ;0
L 2.62978002 -1.05931998 2.66008002 -1.05931998 1 N 8191 ;0
A 2.66003996 -1.07955 2.66008002 -1.05931998 2.65827421 -1.0694314 1 N 0 N;0
L 2.66003002 -1.07953996 2.62978002 -1.07953996 1 N 8191 ;0
A 2.71926004 -1.06796998 2.6962 -1.06796998 2.70773002 -1.0720561 1 N 0 N;0
A 2.71968996 -1.02341998 2.71968996 -1.02341998 2.70775 -1.02341998 1 N 0 N;0
A 2.57053996 -1.13728996 2.54306998 -1.11513002 2.53584449 -1.15219301 1 N 0 N;0
A 2.54891998 -1.15895 2.55001004 -1.14328002 2.54127923 -1.15054557 1 N 0 N;0
L 2.60953996 -1.16041004 2.60953996 -1.07953996 1 N 0 ;0
L 2.62978002 -1.07953996 2.62978002 -1.15463002 1 N 0 ;0
L 2.98495 -1.09393996 2.98495 -1.17625 1 N 0 ;0
A 2.96473996 -1.17626998 2.98493996 -1.17626998 2.97483996 -1.17442303 1 N 0 N;0
L 2.96473002 -1.17625 2.96473002 -1.17226004 1 N 8191 ;0
A 2.94165 -1.1835 2.96471004 -1.17226004 2.93076516 -1.1318935 1 N 0 N;0
L 2.94165 -1.1835 2.90701004 -1.1835 1 N 8191 ;0
A 2.90671004 -1.10841998 2.90703002 -1.18351004 2.9153065 -1.14592904 1 N 0 N;0
A 2.91853002 -1.12288996 2.91853002 -1.16618996 2.92048209 -1.14453996 1 N 0 N;0
L 2.91853002 -1.1662 2.94456004 -1.1662 1 N 8191 ;0
A 2.94456998 -1.16618996 2.94456998 -1.12288996 2.94406004 -1.14453996 1 N 0 N;0
A 2.96473002 -1.09686004 2.94741998 -1.07955 2.94874833 -1.09553169 1 N 0 N;0
L 2.9474 -1.07953996 2.90986998 -1.07953996 1 N 8191 ;0
A 2.90986998 -1.07953996 2.89821004 -1.0852 2.92433445 -1.12417766 1 N 0 N;0
A 2.89111998 -1.07086004 2.8982 -1.0852 2.8969689 -1.07688996 1 N 0 N;0
A 2.91561998 -1.05931998 2.89111998 -1.07085 2.92146033 -1.103525 1 N 0 N;0
L 2.91563002 -1.05931998 2.95031004 -1.05931998 1 N 8191 ;0
A 2.98496004 -1.09393996 2.95031004 -1.05933002 2.9453438 -1.09895197 1 N 0 N;0
A 2.92878996 -1.10535 2.9067 -1.10841998 2.93158484 -1.20646998 1 N 0 N;0
A 2.96471998 -1.10841004 2.92878002 -1.10536004 2.93215738 -1.27883829 1 N 0 N;0
L 2.96473002 -1.10841004 2.96473002 -1.09686004 1 N 8191 ;0
L 2.94456004 -1.12288002 2.91853002 -1.12288002 1 N 8191 ;0
L 3.04731004 -1.06001004 3.04191998 -1.07631998 1 N 8191 ;0
L 3.04191998 -1.07631998 3.03648002 -1.06001004 1 N 8191 ;0
L 3.03648002 -1.06001004 3.03243002 -1.06001004 1 N 8191 ;0
L 3.03243002 -1.06001004 3.02698002 -1.08543996 1 N 8191 ;0
L 3.02698002 -1.08543996 3.03226004 -1.08543996 1 N 8191 ;0
L 3.03226004 -1.08543996 3.03501004 -1.06886998 1 N 8191 ;0
L 3.03501004 -1.06886998 3.04086004 -1.08543996 1 N 8191 ;0
L 3.04086004 -1.08543996 3.04308996 -1.08543996 1 N 8191 ;0
L 3.04308996 -1.08543996 3.04888996 -1.06871004 1 N 8191 ;0
L 3.04888996 -1.06871004 3.05171004 -1.08543996 1 N 8191 ;0
L 3.05171004 -1.08543996 3.05713002 -1.08543996 1 N 8191 ;0
L 3.05713002 -1.08543996 3.05163996 -1.06001004 1 N 8191 ;0
L 3.05163996 -1.06001004 3.04731004 -1.06001004 1 N 8191 ;0
L 3.01066998 -1.06508002 3.00223002 -1.06508002 1 N 8191 ;0
L 3.00223002 -1.06508002 3.00223002 -1.06001004 1 N 8191 ;0
L 3.00223002 -1.06001004 3.02461004 -1.06001004 1 N 8191 ;0
L 3.02461004 -1.06001004 3.02461004 -1.06508002 1 N 8191 ;0
L 3.02461004 -1.06508002 3.01615 -1.06508002 1 N 8191 ;0
L 3.01615 -1.06508002 3.01615 -1.08533996 1 N 8191 ;0
L 3.01615 -1.08533996 3.01066998 -1.08533996 1 N 8191 ;0
L 3.01066998 -1.08533996 3.01066998 -1.06508002 1 N 8191 ;0
L 3.36933297 -0.955 3.36933297 -0.88 0 N 0 ;0
L 3.36933297 -0.88 3.39173337 -0.88 0 N 0 ;0
L 3.39173337 -0.88 3.3992001 -0.88375157 0 N 0 ;0
L 3.3992001 -0.88375157 3.40480059 -0.8924997 0 N 0 ;0
L 3.40480059 -0.8924997 3.40666693 -0.9024998 0 N 0 ;0
L 3.40666693 -0.9024998 3.40480059 -0.9125 0 N 0 ;0
L 3.40480059 -0.9125 3.40013327 -0.92000069 0 N 0 ;0
L 3.40013327 -0.92000069 3.39173337 -0.92375217 0 N 0 ;0
L 3.39173337 -0.92375217 3.36933297 -0.92375217 0 N 0 ;0
L 3.44619931 -0.95749941 3.47980059 -0.88 0 N 0 ;0
L 3.51653356 -0.955 3.51653356 -0.88 0 N 0 ;0
L 3.51653356 -0.88 3.55946634 -0.955 0 N 0 ;0
L 3.55946634 -0.955 3.55946634 -0.88 0 N 0 ;0
L 3.68799911 -0.95749941 3.68613287 -0.9562497 0 N 0 ;0
L 3.68613287 -0.9562497 3.68613287 -0.9537503 0 N 0 ;0
L 3.68613287 -0.9537503 3.68799911 -0.95250059 0 N 0 ;0
L 3.68799911 -0.95250059 3.68986703 -0.9537503 0 N 0 ;0
L 3.68986703 -0.9537503 3.68986703 -0.9562497 0 N 0 ;0
L 3.68986703 -0.9562497 3.68799911 -0.95749941 0 N 0 ;0
L 3.68799911 -0.92375217 3.68613287 -0.9225001 0 N 0 ;0
L 3.68613287 -0.9225001 3.68613287 -0.92000069 0 N 0 ;0
L 3.68613287 -0.92000069 3.68799911 -0.91875089 0 N 0 ;0
L 3.68799911 -0.91875089 3.68986703 -0.92000069 0 N 0 ;0
L 3.68986703 -0.92000069 3.68986703 -0.9225001 0 N 0 ;0
L 3.68986703 -0.9225001 3.68799911 -0.92375217 0 N 0 ;0
L 3.81933297 -0.955 3.81933297 -0.88 0 N 0 ;0
L 3.81933297 -0.88 3.84266644 -0.88 0 N 0 ;0
L 3.84266644 -0.88 3.85013327 -0.88375157 0 N 0 ;0
L 3.85013327 -0.88375157 3.85480059 -0.88875049 0 N 0 ;0
L 3.85480059 -0.88875049 3.85666693 -0.89875059 0 N 0 ;0
L 3.85666693 -0.89875059 3.85480059 -0.90875079 0 N 0 ;0
L 3.85480059 -0.90875079 3.8492001 -0.91499941 0 N 0 ;0
L 3.8492001 -0.91499941 3.84266644 -0.91875089 0 N 0 ;0
L 3.84266644 -0.91875089 3.81933297 -0.91875089 0 N 0 ;0
L 3.84266644 -0.91875089 3.85666693 -0.955 0 N 0 ;0
L 3.9242001 -0.955 3.9242001 -0.88 0 N 0 ;0
L 3.9242001 -0.88 3.88966565 -0.93375 0 N 0 ;0
L 3.88966565 -0.93375 3.93633425 -0.93375 0 N 0 ;0
L 3.98799911 -0.88 3.98053228 -0.88249951 0 N 0 ;0
L 3.98053228 -0.88249951 3.97493346 -0.88875049 0 N 0 ;0
L 3.97493346 -0.88875049 3.97119931 -0.89624882 0 N 0 ;0
L 3.97119931 -0.89624882 3.9683999 -0.90625128 0 N 0 ;0
L 3.9683999 -0.90625128 3.96746673 -0.91750118 0 N 0 ;0
L 3.96746673 -0.91750118 3.9683999 -0.92875108 0 N 0 ;0
L 3.9683999 -0.92875108 3.97119931 -0.93875128 0 N 0 ;0
L 3.97119931 -0.93875128 3.97493346 -0.94625187 0 N 0 ;0
L 3.97493346 -0.94625187 3.98053228 -0.95250059 0 N 0 ;0
L 3.98053228 -0.95250059 3.98799911 -0.955 0 N 0 ;0
L 3.98799911 -0.955 3.99546585 -0.95250059 0 N 0 ;0
L 3.99546585 -0.95250059 4.00106644 -0.94625187 0 N 0 ;0
L 4.00106644 -0.94625187 4.00480059 -0.93875128 0 N 0 ;0
L 4.00480059 -0.93875128 4.0076 -0.92875108 0 N 0 ;0
L 4.0076 -0.92875108 4.00853317 -0.91750118 0 N 0 ;0
L 4.00853317 -0.91750118 4.0076 -0.90625128 0 N 0 ;0
L 4.0076 -0.90625128 4.00480059 -0.89624882 0 N 0 ;0
L 4.00480059 -0.89624882 4.00106644 -0.88875049 0 N 0 ;0
L 4.00106644 -0.88875049 3.99546585 -0.88249951 0 N 0 ;0
L 3.99546585 -0.88249951 3.98799911 -0.88 0 N 0 ;0
L 4.06299911 -0.88 4.05553228 -0.88249951 0 N 0 ;0
L 4.05553228 -0.88249951 4.04993346 -0.88875049 0 N 0 ;0
L 4.04993346 -0.88875049 4.04619931 -0.89624882 0 N 0 ;0
L 4.04619931 -0.89624882 4.0433999 -0.90625128 0 N 0 ;0
L 4.0433999 -0.90625128 4.04246673 -0.91750118 0 N 0 ;0
L 4.04246673 -0.91750118 4.0433999 -0.92875108 0 N 0 ;0
L 4.0433999 -0.92875108 4.04619931 -0.93875128 0 N 0 ;0
L 4.04619931 -0.93875128 4.04993346 -0.94625187 0 N 0 ;0
L 4.04993346 -0.94625187 4.05553228 -0.95250059 0 N 0 ;0
L 4.05553228 -0.95250059 4.06299911 -0.955 0 N 0 ;0
L 4.06299911 -0.955 4.07046585 -0.95250059 0 N 0 ;0
L 4.07046585 -0.95250059 4.07606644 -0.94625187 0 N 0 ;0
L 4.07606644 -0.94625187 4.07980059 -0.93875128 0 N 0 ;0
L 4.07980059 -0.93875128 4.0826 -0.92875108 0 N 0 ;0
L 4.0826 -0.92875108 4.08353317 -0.91750118 0 N 0 ;0
L 4.08353317 -0.91750118 4.0826 -0.90625128 0 N 0 ;0
L 4.0826 -0.90625128 4.07980059 -0.89624882 0 N 0 ;0
L 4.07980059 -0.89624882 4.07606644 -0.88875049 0 N 0 ;0
L 4.07606644 -0.88875049 4.07046585 -0.88249951 0 N 0 ;0
L 4.07046585 -0.88249951 4.06299911 -0.88 0 N 0 ;0
L 4.12026614 -0.92375217 4.1267998 -0.91499941 0 N 0 ;0
L 4.1267998 -0.91499941 4.1324003 -0.91000049 0 N 0 ;0
L 4.1324003 -0.91000049 4.13986703 -0.90750108 0 N 0 ;0
L 4.13986703 -0.90750108 4.14640069 -0.91000049 0 N 0 ;0
L 4.14640069 -0.91000049 4.15106644 -0.91499941 0 N 0 ;0
L 4.15106644 -0.91499941 4.15480059 -0.9225001 0 N 0 ;0
L 4.15480059 -0.9225001 4.15573376 -0.93125059 0 N 0 ;0
L 4.15573376 -0.93125059 4.15480059 -0.93875128 0 N 0 ;0
L 4.15480059 -0.93875128 4.15106644 -0.94625187 0 N 0 ;0
L 4.15106644 -0.94625187 4.14546585 -0.95250059 0 N 0 ;0
L 4.14546585 -0.95250059 4.13893396 -0.955 0 N 0 ;0
L 4.13893396 -0.955 4.13146713 -0.95250059 0 N 0 ;0
L 4.13146713 -0.95250059 4.12493346 -0.94500217 0 N 0 ;0
L 4.12493346 -0.94500217 4.12119931 -0.93375 0 N 0 ;0
L 4.12119931 -0.93375 4.12026614 -0.92125039 0 N 0 ;0
L 4.12026614 -0.92125039 4.12213238 -0.90500157 0 N 0 ;0
L 4.12213238 -0.90500157 4.12493346 -0.89624882 0 N 0 ;0
L 4.12493346 -0.89624882 4.12959921 -0.88750069 0 N 0 ;0
L 4.12959921 -0.88750069 4.13613287 -0.8812498 0 N 0 ;0
L 4.13613287 -0.8812498 4.14266644 -0.88 0 N 0 ;0
L 4.14266644 -0.88 4.1492001 -0.88249951 0 N 0 ;0
L 4.1492001 -0.88249951 4.15386752 -0.88875049 0 N 0 ;0
L 4.20086663 -0.93000079 4.22513327 -0.93000079 0 N 0 ;0
L 4.29546585 -0.91499941 4.2992001 -0.9112502 0 N 0 ;0
L 4.2992001 -0.9112502 4.30199951 -0.90500157 0 N 0 ;0
L 4.30199951 -0.90500157 4.30386752 -0.89624882 0 N 0 ;0
L 4.30386752 -0.89624882 4.30199951 -0.88875049 0 N 0 ;0
L 4.30199951 -0.88875049 4.29826703 -0.88375157 0 N 0 ;0
L 4.29826703 -0.88375157 4.29173337 -0.88 0 N 0 ;0
L 4.29173337 -0.88 4.26653356 -0.88 0 N 0 ;0
L 4.26653356 -0.88 4.26653356 -0.955 0 N 0 ;0
L 4.26653356 -0.955 4.29733386 -0.955 0 N 0 ;0
L 4.29733386 -0.955 4.30386752 -0.95000108 0 N 0 ;0
L 4.30386752 -0.95000108 4.3076 -0.94250039 0 N 0 ;0
L 4.3076 -0.94250039 4.30946634 -0.93375 0 N 0 ;0
L 4.30946634 -0.93375 4.3076 -0.92500187 0 N 0 ;0
L 4.3076 -0.92500187 4.30199951 -0.91750118 0 N 0 ;0
L 4.30199951 -0.91750118 4.29546585 -0.91499941 0 N 0 ;0
L 4.29546585 -0.91499941 4.26653356 -0.91499941 0 N 0 ;0
L 4.36299911 -0.88 4.35553228 -0.88249951 0 N 0 ;0
L 4.35553228 -0.88249951 4.34993346 -0.88875049 0 N 0 ;0
L 4.34993346 -0.88875049 4.34619931 -0.89624882 0 N 0 ;0
L 4.34619931 -0.89624882 4.3433999 -0.90625128 0 N 0 ;0
L 4.3433999 -0.90625128 4.34246673 -0.91750118 0 N 0 ;0
L 4.34246673 -0.91750118 4.3433999 -0.92875108 0 N 0 ;0
L 4.3433999 -0.92875108 4.34619931 -0.93875128 0 N 0 ;0
L 4.34619931 -0.93875128 4.34993346 -0.94625187 0 N 0 ;0
L 4.34993346 -0.94625187 4.35553228 -0.95250059 0 N 0 ;0
L 4.35553228 -0.95250059 4.36299911 -0.955 0 N 0 ;0
L 4.36299911 -0.955 4.37046585 -0.95250059 0 N 0 ;0
L 4.37046585 -0.95250059 4.37606644 -0.94625187 0 N 0 ;0
L 4.37606644 -0.94625187 4.37980059 -0.93875128 0 N 0 ;0
L 4.37980059 -0.93875128 4.3826 -0.92875108 0 N 0 ;0
L 4.3826 -0.92875108 4.38353317 -0.91750118 0 N 0 ;0
L 4.38353317 -0.91750118 4.3826 -0.90625128 0 N 0 ;0
L 4.3826 -0.90625128 4.37980059 -0.89624882 0 N 0 ;0
L 4.37980059 -0.89624882 4.37606644 -0.88875049 0 N 0 ;0
L 4.37606644 -0.88875049 4.37046585 -0.88249951 0 N 0 ;0
L 4.37046585 -0.88249951 4.36299911 -0.88 0 N 0 ;0
L 4.43799911 -0.88 4.43053228 -0.88249951 0 N 0 ;0
L 4.43053228 -0.88249951 4.42493346 -0.88875049 0 N 0 ;0
L 4.42493346 -0.88875049 4.42119931 -0.89624882 0 N 0 ;0
L 4.42119931 -0.89624882 4.4183999 -0.90625128 0 N 0 ;0
L 4.4183999 -0.90625128 4.41746673 -0.91750118 0 N 0 ;0
L 4.41746673 -0.91750118 4.4183999 -0.92875108 0 N 0 ;0
L 4.4183999 -0.92875108 4.42119931 -0.93875128 0 N 0 ;0
L 4.42119931 -0.93875128 4.42493346 -0.94625187 0 N 0 ;0
L 4.42493346 -0.94625187 4.43053228 -0.95250059 0 N 0 ;0
L 4.43053228 -0.95250059 4.43799911 -0.955 0 N 0 ;0
L 4.43799911 -0.955 4.44546585 -0.95250059 0 N 0 ;0
L 4.44546585 -0.95250059 4.45106644 -0.94625187 0 N 0 ;0
L 4.45106644 -0.94625187 4.45480059 -0.93875128 0 N 0 ;0
L 4.45480059 -0.93875128 4.4576 -0.92875108 0 N 0 ;0
L 4.4576 -0.92875108 4.45853317 -0.91750118 0 N 0 ;0
L 4.45853317 -0.91750118 4.4576 -0.90625128 0 N 0 ;0
L 4.4576 -0.90625128 4.45480059 -0.89624882 0 N 0 ;0
L 4.45480059 -0.89624882 4.45106644 -0.88875049 0 N 0 ;0
L 4.45106644 -0.88875049 4.44546585 -0.88249951 0 N 0 ;0
L 4.44546585 -0.88249951 4.43799911 -0.88 0 N 0 ;0
L 4.51299911 -0.88 4.50553228 -0.88249951 0 N 0 ;0
L 4.50553228 -0.88249951 4.49993346 -0.88875049 0 N 0 ;0
L 4.49993346 -0.88875049 4.49619931 -0.89624882 0 N 0 ;0
L 4.49619931 -0.89624882 4.4933999 -0.90625128 0 N 0 ;0
L 4.4933999 -0.90625128 4.49246673 -0.91750118 0 N 0 ;0
L 4.49246673 -0.91750118 4.4933999 -0.92875108 0 N 0 ;0
L 4.4933999 -0.92875108 4.49619931 -0.93875128 0 N 0 ;0
L 4.49619931 -0.93875128 4.49993346 -0.94625187 0 N 0 ;0
L 4.49993346 -0.94625187 4.50553228 -0.95250059 0 N 0 ;0
L 4.50553228 -0.95250059 4.51299911 -0.955 0 N 0 ;0
L 4.51299911 -0.955 4.52046585 -0.95250059 0 N 0 ;0
L 4.52046585 -0.95250059 4.52606644 -0.94625187 0 N 0 ;0
L 4.52606644 -0.94625187 4.52980059 -0.93875128 0 N 0 ;0
L 4.52980059 -0.93875128 4.5326 -0.92875108 0 N 0 ;0
L 4.5326 -0.92875108 4.53353317 -0.91750118 0 N 0 ;0
L 4.53353317 -0.91750118 4.5326 -0.90625128 0 N 0 ;0
L 4.5326 -0.90625128 4.52980059 -0.89624882 0 N 0 ;0
L 4.52980059 -0.89624882 4.52606644 -0.88875049 0 N 0 ;0
L 4.52606644 -0.88875049 4.52046585 -0.88249951 0 N 0 ;0
L 4.52046585 -0.88249951 4.51299911 -0.88 0 N 0 ;0
L 4.58799911 -0.955 4.58799911 -0.88 0 N 0 ;0
L 4.58799911 -0.88 4.5767998 -0.89499911 0 N 0 ;0
L 4.5767998 -0.955 4.59919843 -0.955 0 N 0 ;0
L 4.65086663 -0.93000079 4.67513327 -0.93000079 0 N 0 ;0
L 4.73799911 -0.88 4.73053228 -0.88249951 0 N 0 ;0
L 4.73053228 -0.88249951 4.72493346 -0.88875049 0 N 0 ;0
L 4.72493346 -0.88875049 4.72119931 -0.89624882 0 N 0 ;0
L 4.72119931 -0.89624882 4.7183999 -0.90625128 0 N 0 ;0
L 4.7183999 -0.90625128 4.71746673 -0.91750118 0 N 0 ;0
L 4.71746673 -0.91750118 4.7183999 -0.92875108 0 N 0 ;0
L 4.7183999 -0.92875108 4.72119931 -0.93875128 0 N 0 ;0
L 4.72119931 -0.93875128 4.72493346 -0.94625187 0 N 0 ;0
L 4.72493346 -0.94625187 4.73053228 -0.95250059 0 N 0 ;0
L 4.73053228 -0.95250059 4.73799911 -0.955 0 N 0 ;0
L 4.73799911 -0.955 4.74546585 -0.95250059 0 N 0 ;0
L 4.74546585 -0.95250059 4.75106644 -0.94625187 0 N 0 ;0
L 4.75106644 -0.94625187 4.75480059 -0.93875128 0 N 0 ;0
L 4.75480059 -0.93875128 4.7576 -0.92875108 0 N 0 ;0
L 4.7576 -0.92875108 4.75853317 -0.91750118 0 N 0 ;0
L 4.75853317 -0.91750118 4.7576 -0.90625128 0 N 0 ;0
L 4.7576 -0.90625128 4.75480059 -0.89624882 0 N 0 ;0
L 4.75480059 -0.89624882 4.75106644 -0.88875049 0 N 0 ;0
L 4.75106644 -0.88875049 4.74546585 -0.88249951 0 N 0 ;0
L 4.74546585 -0.88249951 4.73799911 -0.88 0 N 0 ;0
L 4.79526614 -0.8924997 4.80086663 -0.88500128 0 N 0 ;0
L 4.80086663 -0.88500128 4.8074003 -0.8812498 0 N 0 ;0
L 4.8074003 -0.8812498 4.81486703 -0.88 0 N 0 ;0
L 4.81486703 -0.88 4.8242001 -0.88249951 0 N 0 ;0
L 4.8242001 -0.88249951 4.83073376 -0.88875049 0 N 0 ;0
L 4.83073376 -0.88875049 4.8326 -0.89624882 0 N 0 ;0
L 4.8326 -0.89624882 4.83166693 -0.90375187 0 N 0 ;0
L 4.83166693 -0.90375187 4.82793268 -0.91000049 0 N 0 ;0
L 4.82793268 -0.91000049 4.80926654 -0.9225001 0 N 0 ;0
L 4.80926654 -0.9225001 4.80086663 -0.93125059 0 N 0 ;0
L 4.80086663 -0.93125059 4.79526614 -0.94375246 0 N 0 ;0
L 4.79526614 -0.94375246 4.7933999 -0.955 0 N 0 ;0
L 4.7933999 -0.955 4.8326 -0.955 0 N 0 ;0
L 3.36746673 -1.205 3.36746673 -1.13 0 N 0 ;0
L 3.36746673 -1.13 3.38613287 -1.13 0 N 0 ;0
L 3.38613287 -1.13 3.39359961 -1.13375157 0 N 0 ;0
L 3.39359961 -1.13375157 3.3992001 -1.13875049 0 N 0 ;0
L 3.3992001 -1.13875049 3.40386752 -1.14624882 0 N 0 ;0
L 3.40386752 -1.14624882 3.4076 -1.15500157 0 N 0 ;0
L 3.4076 -1.15500157 3.40853317 -1.16750118 0 N 0 ;0
L 3.40853317 -1.16750118 3.4076 -1.18000079 0 N 0 ;0
L 3.4076 -1.18000079 3.40386752 -1.18875128 0 N 0 ;0
L 3.40386752 -1.18875128 3.3992001 -1.19625187 0 N 0 ;0
L 3.3992001 -1.19625187 3.39359961 -1.20125089 0 N 0 ;0
L 3.39359961 -1.20125089 3.38613287 -1.205 0 N 0 ;0
L 3.38613287 -1.205 3.36746673 -1.205 0 N 0 ;0
L 3.47980059 -1.205 3.47980059 -1.15500157 0 N 0 ;0
L 3.47980059 -1.1637497 3.47606644 -1.15875079 0 N 0 ;0
L 3.47606644 -1.15875079 3.47046585 -1.15625128 0 N 0 ;0
L 3.47046585 -1.15625128 3.46393396 -1.15500157 0 N 0 ;0
L 3.46393396 -1.15500157 3.4574003 -1.15750108 0 N 0 ;0
L 3.4574003 -1.15750108 3.4517998 -1.1625 0 N 0 ;0
L 3.4517998 -1.1625 3.44806555 -1.17000069 0 N 0 ;0
L 3.44806555 -1.17000069 3.44619931 -1.18000079 0 N 0 ;0
L 3.44619931 -1.18000079 3.44806555 -1.19000098 0 N 0 ;0
L 3.44806555 -1.19000098 3.4517998 -1.19750167 0 N 0 ;0
L 3.4517998 -1.19750167 3.4574003 -1.20250059 0 N 0 ;0
L 3.4574003 -1.20250059 3.46393396 -1.205 0 N 0 ;0
L 3.46393396 -1.205 3.47046585 -1.2037503 0 N 0 ;0
L 3.47046585 -1.2037503 3.47606644 -1.20000108 0 N 0 ;0
L 3.47606644 -1.20000108 3.47980059 -1.19500217 0 N 0 ;0
L 3.53799911 -1.13 3.53799911 -1.205 0 N 0 ;0
L 3.52493346 -1.15500157 3.55106644 -1.15500157 0 N 0 ;0
L 3.59900039 -1.17125039 3.62886752 -1.17125039 0 N 0 ;0
L 3.62886752 -1.17125039 3.62606644 -1.1625 0 N 0 ;0
L 3.62606644 -1.1625 3.62140069 -1.15750108 0 N 0 ;0
L 3.62140069 -1.15750108 3.61486703 -1.15500157 0 N 0 ;0
L 3.61486703 -1.15500157 3.60833346 -1.15625128 0 N 0 ;0
L 3.60833346 -1.15625128 3.60273287 -1.16000049 0 N 0 ;0
L 3.60273287 -1.16000049 3.59900039 -1.16875089 0 N 0 ;0
L 3.59900039 -1.16875089 3.59713238 -1.17625157 0 N 0 ;0
L 3.59713238 -1.17625157 3.59713238 -1.18375 0 N 0 ;0
L 3.59713238 -1.18375 3.59900039 -1.19125069 0 N 0 ;0
L 3.59900039 -1.19125069 3.60366604 -1.19875138 0 N 0 ;0
L 3.60366604 -1.19875138 3.60926654 -1.2037503 0 N 0 ;0
L 3.60926654 -1.2037503 3.6158002 -1.205 0 N 0 ;0
L 3.6158002 -1.205 3.62233386 -1.20250059 0 N 0 ;0
L 3.62233386 -1.20250059 3.62886752 -1.19500217 0 N 0 ;0
L 3.68799911 -1.20749941 3.68613287 -1.2062497 0 N 0 ;0
L 3.68613287 -1.2062497 3.68613287 -1.2037503 0 N 0 ;0
L 3.68613287 -1.2037503 3.68799911 -1.20250059 0 N 0 ;0
L 3.68799911 -1.20250059 3.68986703 -1.2037503 0 N 0 ;0
L 3.68986703 -1.2037503 3.68986703 -1.2062497 0 N 0 ;0
L 3.68986703 -1.2062497 3.68799911 -1.20749941 0 N 0 ;0
L 3.68799911 -1.17375217 3.68613287 -1.1725001 0 N 0 ;0
L 3.68613287 -1.1725001 3.68613287 -1.17000069 0 N 0 ;0
L 3.68613287 -1.17000069 3.68799911 -1.16875089 0 N 0 ;0
L 3.68799911 -1.16875089 3.68986703 -1.17000069 0 N 0 ;0
L 3.68986703 -1.17000069 3.68986703 -1.1725001 0 N 0 ;0
L 3.68986703 -1.1725001 3.68799911 -1.17375217 0 N 0 ;0
L 3.82026614 -1.1424997 3.82586663 -1.13500128 0 N 0 ;0
L 3.82586663 -1.13500128 3.8324003 -1.1312498 0 N 0 ;0
L 3.8324003 -1.1312498 3.83986703 -1.13 0 N 0 ;0
L 3.83986703 -1.13 3.8492001 -1.13249951 0 N 0 ;0
L 3.8492001 -1.13249951 3.85573376 -1.13875049 0 N 0 ;0
L 3.85573376 -1.13875049 3.8576 -1.14624882 0 N 0 ;0
L 3.8576 -1.14624882 3.85666693 -1.15375187 0 N 0 ;0
L 3.85666693 -1.15375187 3.85293268 -1.16000049 0 N 0 ;0
L 3.85293268 -1.16000049 3.83426654 -1.1725001 0 N 0 ;0
L 3.83426654 -1.1725001 3.82586663 -1.18125059 0 N 0 ;0
L 3.82586663 -1.18125059 3.82026614 -1.19375246 0 N 0 ;0
L 3.82026614 -1.19375246 3.8183999 -1.205 0 N 0 ;0
L 3.8183999 -1.205 3.8576 -1.205 0 N 0 ;0
L 3.91299911 -1.13 3.90553228 -1.13249951 0 N 0 ;0
L 3.90553228 -1.13249951 3.89993346 -1.13875049 0 N 0 ;0
L 3.89993346 -1.13875049 3.89619931 -1.14624882 0 N 0 ;0
L 3.89619931 -1.14624882 3.8933999 -1.15625128 0 N 0 ;0
L 3.8933999 -1.15625128 3.89246673 -1.16750118 0 N 0 ;0
L 3.89246673 -1.16750118 3.8933999 -1.17875108 0 N 0 ;0
L 3.8933999 -1.17875108 3.89619931 -1.18875128 0 N 0 ;0
L 3.89619931 -1.18875128 3.89993346 -1.19625187 0 N 0 ;0
L 3.89993346 -1.19625187 3.90553228 -1.20250059 0 N 0 ;0
L 3.90553228 -1.20250059 3.91299911 -1.205 0 N 0 ;0
L 3.91299911 -1.205 3.92046585 -1.20250059 0 N 0 ;0
L 3.92046585 -1.20250059 3.92606644 -1.19625187 0 N 0 ;0
L 3.92606644 -1.19625187 3.92980059 -1.18875128 0 N 0 ;0
L 3.92980059 -1.18875128 3.9326 -1.17875108 0 N 0 ;0
L 3.9326 -1.17875108 3.93353317 -1.16750118 0 N 0 ;0
L 3.93353317 -1.16750118 3.9326 -1.15625128 0 N 0 ;0
L 3.9326 -1.15625128 3.92980059 -1.14624882 0 N 0 ;0
L 3.92980059 -1.14624882 3.92606644 -1.13875049 0 N 0 ;0
L 3.92606644 -1.13875049 3.92046585 -1.13249951 0 N 0 ;0
L 3.92046585 -1.13249951 3.91299911 -1.13 0 N 0 ;0
L 3.97026614 -1.1424997 3.97586663 -1.13500128 0 N 0 ;0
L 3.97586663 -1.13500128 3.9824003 -1.1312498 0 N 0 ;0
L 3.9824003 -1.1312498 3.98986703 -1.13 0 N 0 ;0
L 3.98986703 -1.13 3.9992001 -1.13249951 0 N 0 ;0
L 3.9992001 -1.13249951 4.00573376 -1.13875049 0 N 0 ;0
L 4.00573376 -1.13875049 4.0076 -1.14624882 0 N 0 ;0
L 4.0076 -1.14624882 4.00666693 -1.15375187 0 N 0 ;0
L 4.00666693 -1.15375187 4.00293268 -1.16000049 0 N 0 ;0
L 4.00293268 -1.16000049 3.98426654 -1.1725001 0 N 0 ;0
L 3.98426654 -1.1725001 3.97586663 -1.18125059 0 N 0 ;0
L 3.97586663 -1.18125059 3.97026614 -1.19375246 0 N 0 ;0
L 3.97026614 -1.19375246 3.9683999 -1.205 0 N 0 ;0
L 3.9683999 -1.205 4.0076 -1.205 0 N 0 ;0
L 4.04526614 -1.1424997 4.05086663 -1.13500128 0 N 0 ;0
L 4.05086663 -1.13500128 4.0574003 -1.1312498 0 N 0 ;0
L 4.0574003 -1.1312498 4.06486703 -1.13 0 N 0 ;0
L 4.06486703 -1.13 4.0742001 -1.13249951 0 N 0 ;0
L 4.0742001 -1.13249951 4.08073376 -1.13875049 0 N 0 ;0
L 4.08073376 -1.13875049 4.0826 -1.14624882 0 N 0 ;0
L 4.0826 -1.14624882 4.08166693 -1.15375187 0 N 0 ;0
L 4.08166693 -1.15375187 4.07793268 -1.16000049 0 N 0 ;0
L 4.07793268 -1.16000049 4.05926654 -1.1725001 0 N 0 ;0
L 4.05926654 -1.1725001 4.05086663 -1.18125059 0 N 0 ;0
L 4.05086663 -1.18125059 4.04526614 -1.19375246 0 N 0 ;0
L 4.04526614 -1.19375246 4.0433999 -1.205 0 N 0 ;0
L 4.0433999 -1.205 4.0826 -1.205 0 N 0 ;0
L 4.12586663 -1.18000079 4.15013327 -1.18000079 0 N 0 ;0
L 4.21299911 -1.13 4.20553228 -1.13249951 0 N 0 ;0
L 4.20553228 -1.13249951 4.19993346 -1.13875049 0 N 0 ;0
L 4.19993346 -1.13875049 4.19619931 -1.14624882 0 N 0 ;0
L 4.19619931 -1.14624882 4.1933999 -1.15625128 0 N 0 ;0
L 4.1933999 -1.15625128 4.19246673 -1.16750118 0 N 0 ;0
L 4.19246673 -1.16750118 4.1933999 -1.17875108 0 N 0 ;0
L 4.1933999 -1.17875108 4.19619931 -1.18875128 0 N 0 ;0
L 4.19619931 -1.18875128 4.19993346 -1.19625187 0 N 0 ;0
L 4.19993346 -1.19625187 4.20553228 -1.20250059 0 N 0 ;0
L 4.20553228 -1.20250059 4.21299911 -1.205 0 N 0 ;0
L 4.21299911 -1.205 4.22046585 -1.20250059 0 N 0 ;0
L 4.22046585 -1.20250059 4.22606644 -1.19625187 0 N 0 ;0
L 4.22606644 -1.19625187 4.22980059 -1.18875128 0 N 0 ;0
L 4.22980059 -1.18875128 4.2326 -1.17875108 0 N 0 ;0
L 4.2326 -1.17875108 4.23353317 -1.16750118 0 N 0 ;0
L 4.23353317 -1.16750118 4.2326 -1.15625128 0 N 0 ;0
L 4.2326 -1.15625128 4.22980059 -1.14624882 0 N 0 ;0
L 4.22980059 -1.14624882 4.22606644 -1.13875049 0 N 0 ;0
L 4.22606644 -1.13875049 4.22046585 -1.13249951 0 N 0 ;0
L 4.22046585 -1.13249951 4.21299911 -1.13 0 N 0 ;0
L 4.27026614 -1.1424997 4.27586663 -1.13500128 0 N 0 ;0
L 4.27586663 -1.13500128 4.2824003 -1.1312498 0 N 0 ;0
L 4.2824003 -1.1312498 4.28986703 -1.13 0 N 0 ;0
L 4.28986703 -1.13 4.2992001 -1.13249951 0 N 0 ;0
L 4.2992001 -1.13249951 4.30573376 -1.13875049 0 N 0 ;0
L 4.30573376 -1.13875049 4.3076 -1.14624882 0 N 0 ;0
L 4.3076 -1.14624882 4.30666693 -1.15375187 0 N 0 ;0
L 4.30666693 -1.15375187 4.30293268 -1.16000049 0 N 0 ;0
L 4.30293268 -1.16000049 4.28426654 -1.1725001 0 N 0 ;0
L 4.28426654 -1.1725001 4.27586663 -1.18125059 0 N 0 ;0
L 4.27586663 -1.18125059 4.27026614 -1.19375246 0 N 0 ;0
L 4.27026614 -1.19375246 4.2683999 -1.205 0 N 0 ;0
L 4.2683999 -1.205 4.3076 -1.205 0 N 0 ;0
L 4.35086663 -1.18000079 4.37513327 -1.18000079 0 N 0 ;0
L 4.42026614 -1.1424997 4.42586663 -1.13500128 0 N 0 ;0
L 4.42586663 -1.13500128 4.4324003 -1.1312498 0 N 0 ;0
L 4.4324003 -1.1312498 4.43986703 -1.13 0 N 0 ;0
L 4.43986703 -1.13 4.4492001 -1.13249951 0 N 0 ;0
L 4.4492001 -1.13249951 4.45573376 -1.13875049 0 N 0 ;0
L 4.45573376 -1.13875049 4.4576 -1.14624882 0 N 0 ;0
L 4.4576 -1.14624882 4.45666693 -1.15375187 0 N 0 ;0
L 4.45666693 -1.15375187 4.45293268 -1.16000049 0 N 0 ;0
L 4.45293268 -1.16000049 4.43426654 -1.1725001 0 N 0 ;0
L 4.43426654 -1.1725001 4.42586663 -1.18125059 0 N 0 ;0
L 4.42586663 -1.18125059 4.42026614 -1.19375246 0 N 0 ;0
L 4.42026614 -1.19375246 4.4183999 -1.205 0 N 0 ;0
L 4.4183999 -1.205 4.4576 -1.205 0 N 0 ;0
L 4.49246673 -1.19375246 4.49806555 -1.20000108 0 N 0 ;0
L 4.49806555 -1.20000108 4.50459921 -1.2037503 0 N 0 ;0
L 4.50459921 -1.2037503 4.51299911 -1.205 0 N 0 ;0
L 4.51299911 -1.205 4.52140069 -1.20250059 0 N 0 ;0
L 4.52140069 -1.20250059 4.52793268 -1.19750167 0 N 0 ;0
L 4.52793268 -1.19750167 4.5326 -1.18875128 0 N 0 ;0
L 4.5326 -1.18875128 4.53353317 -1.17875108 0 N 0 ;0
L 4.53353317 -1.17875108 4.53166693 -1.16875089 0 N 0 ;0
L 4.53166693 -1.16875089 4.52699951 -1.1625 0 N 0 ;0
L 4.52699951 -1.1625 4.52046585 -1.15750108 0 N 0 ;0
L 4.52046585 -1.15750108 4.51393396 -1.15625128 0 N 0 ;0
L 4.51393396 -1.15625128 4.5074003 -1.15750108 0 N 0 ;0
L 4.5074003 -1.15750108 4.49900039 -1.1625 0 N 0 ;0
L 4.49900039 -1.1625 4.5017998 -1.13 0 N 0 ;0
L 4.5017998 -1.13 4.52699951 -1.13 0 N 0 ;0
L 3.29433297 -1.255 3.29433297 -1.33 0 N 0 ;0
L 3.29433297 -1.33 3.33166693 -1.33 0 N 0 ;0
L 3.40480059 -1.33 3.40480059 -1.28000157 0 N 0 ;0
L 3.40480059 -1.2887497 3.40106644 -1.28375079 0 N 0 ;0
L 3.40106644 -1.28375079 3.39546585 -1.28125128 0 N 0 ;0
L 3.39546585 -1.28125128 3.38893396 -1.28000157 0 N 0 ;0
L 3.38893396 -1.28000157 3.3824003 -1.28250108 0 N 0 ;0
L 3.3824003 -1.28250108 3.3767998 -1.2875 0 N 0 ;0
L 3.3767998 -1.2875 3.37306555 -1.29500069 0 N 0 ;0
L 3.37306555 -1.29500069 3.37119931 -1.30500079 0 N 0 ;0
L 3.37119931 -1.30500079 3.37306555 -1.31500098 0 N 0 ;0
L 3.37306555 -1.31500098 3.3767998 -1.32250167 0 N 0 ;0
L 3.3767998 -1.32250167 3.3824003 -1.32750059 0 N 0 ;0
L 3.3824003 -1.32750059 3.38893396 -1.33 0 N 0 ;0
L 3.38893396 -1.33 3.39546585 -1.3287503 0 N 0 ;0
L 3.39546585 -1.3287503 3.40106644 -1.32500108 0 N 0 ;0
L 3.40106644 -1.32500108 3.40480059 -1.32000217 0 N 0 ;0
L 3.4433999 -1.3524997 3.44900039 -1.35499921 0 N 0 ;0
L 3.44900039 -1.35499921 3.45646713 -1.3524997 0 N 0 ;0
L 3.45646713 -1.3524997 3.46113287 -1.34750079 0 N 0 ;0
L 3.46113287 -1.34750079 3.46486703 -1.3412498 0 N 0 ;0
L 3.46486703 -1.3412498 3.47046585 -1.32125187 0 N 0 ;0
L 3.47046585 -1.32125187 3.4826 -1.28000157 0 N 0 ;0
L 3.45273287 -1.28000157 3.47046585 -1.32125187 0 N 0 ;0
L 3.52400039 -1.29625039 3.55386752 -1.29625039 0 N 0 ;0
L 3.55386752 -1.29625039 3.55106644 -1.2875 0 N 0 ;0
L 3.55106644 -1.2875 3.54640069 -1.28250108 0 N 0 ;0
L 3.54640069 -1.28250108 3.53986703 -1.28000157 0 N 0 ;0
L 3.53986703 -1.28000157 3.53333346 -1.28125128 0 N 0 ;0
L 3.53333346 -1.28125128 3.52773287 -1.28500049 0 N 0 ;0
L 3.52773287 -1.28500049 3.52400039 -1.29375089 0 N 0 ;0
L 3.52400039 -1.29375089 3.52213238 -1.30125157 0 N 0 ;0
L 3.52213238 -1.30125157 3.52213238 -1.30875 0 N 0 ;0
L 3.52213238 -1.30875 3.52400039 -1.31625069 0 N 0 ;0
L 3.52400039 -1.31625069 3.52866604 -1.32375138 0 N 0 ;0
L 3.52866604 -1.32375138 3.53426654 -1.3287503 0 N 0 ;0
L 3.53426654 -1.3287503 3.5408002 -1.33 0 N 0 ;0
L 3.5408002 -1.33 3.54733386 -1.32750059 0 N 0 ;0
L 3.54733386 -1.32750059 3.55386752 -1.32000217 0 N 0 ;0
L 3.59993346 -1.33 3.59993346 -1.28000157 0 N 0 ;0
L 3.59993346 -1.28999941 3.60459921 -1.28500049 0 N 0 ;0
L 3.60459921 -1.28500049 3.60926654 -1.28125128 0 N 0 ;0
L 3.60926654 -1.28125128 3.6158002 -1.28000157 0 N 0 ;0
L 3.6158002 -1.28000157 3.62046585 -1.28125128 0 N 0 ;0
L 3.62046585 -1.28125128 3.62606644 -1.28500049 0 N 0 ;0
L 3.68799911 -1.33249941 3.68613287 -1.3312497 0 N 0 ;0
L 3.68613287 -1.3312497 3.68613287 -1.3287503 0 N 0 ;0
L 3.68613287 -1.3287503 3.68799911 -1.32750059 0 N 0 ;0
L 3.68799911 -1.32750059 3.68986703 -1.3287503 0 N 0 ;0
L 3.68986703 -1.3287503 3.68986703 -1.3312497 0 N 0 ;0
L 3.68986703 -1.3312497 3.68799911 -1.33249941 0 N 0 ;0
L 3.68799911 -1.29875217 3.68613287 -1.2975001 0 N 0 ;0
L 3.68613287 -1.2975001 3.68613287 -1.29500069 0 N 0 ;0
L 3.68613287 -1.29500069 3.68799911 -1.29375089 0 N 0 ;0
L 3.68799911 -1.29375089 3.68986703 -1.29500069 0 N 0 ;0
L 3.68986703 -1.29500069 3.68986703 -1.2975001 0 N 0 ;0
L 3.68986703 -1.2975001 3.68799911 -1.29875217 0 N 0 ;0
L 3.36933297 -1.08 3.36933297 -1.005 0 N 0 ;0
L 3.36933297 -1.005 3.39266644 -1.005 0 N 0 ;0
L 3.39266644 -1.005 3.40013327 -1.00875157 0 N 0 ;0
L 3.40013327 -1.00875157 3.40480059 -1.01375049 0 N 0 ;0
L 3.40480059 -1.01375049 3.40666693 -1.02375059 0 N 0 ;0
L 3.40666693 -1.02375059 3.40480059 -1.03375079 0 N 0 ;0
L 3.40480059 -1.03375079 3.3992001 -1.03999941 0 N 0 ;0
L 3.3992001 -1.03999941 3.39266644 -1.04375089 0 N 0 ;0
L 3.39266644 -1.04375089 3.36933297 -1.04375089 0 N 0 ;0
L 3.39266644 -1.04375089 3.40666693 -1.08 0 N 0 ;0
L 3.44900039 -1.04625039 3.47886752 -1.04625039 0 N 0 ;0
L 3.47886752 -1.04625039 3.47606644 -1.0375 0 N 0 ;0
L 3.47606644 -1.0375 3.47140069 -1.03250108 0 N 0 ;0
L 3.47140069 -1.03250108 3.46486703 -1.03000157 0 N 0 ;0
L 3.46486703 -1.03000157 3.45833346 -1.03125128 0 N 0 ;0
L 3.45833346 -1.03125128 3.45273287 -1.03500049 0 N 0 ;0
L 3.45273287 -1.03500049 3.44900039 -1.04375089 0 N 0 ;0
L 3.44900039 -1.04375089 3.44713238 -1.05125157 0 N 0 ;0
L 3.44713238 -1.05125157 3.44713238 -1.05875 0 N 0 ;0
L 3.44713238 -1.05875 3.44900039 -1.06625069 0 N 0 ;0
L 3.44900039 -1.06625069 3.45366604 -1.07375138 0 N 0 ;0
L 3.45366604 -1.07375138 3.45926654 -1.0787503 0 N 0 ;0
L 3.45926654 -1.0787503 3.4658002 -1.08 0 N 0 ;0
L 3.4658002 -1.08 3.47233386 -1.07750059 0 N 0 ;0
L 3.47233386 -1.07750059 3.47886752 -1.07000217 0 N 0 ;0
L 3.52119931 -1.03000157 3.53799911 -1.08 0 N 0 ;0
L 3.53799911 -1.08 3.55480059 -1.03000157 0 N 0 ;0
L 3.68799911 -1.08249941 3.68613287 -1.0812497 0 N 0 ;0
L 3.68613287 -1.0812497 3.68613287 -1.0787503 0 N 0 ;0
L 3.68613287 -1.0787503 3.68799911 -1.07750059 0 N 0 ;0
L 3.68799911 -1.07750059 3.68986703 -1.0787503 0 N 0 ;0
L 3.68986703 -1.0787503 3.68986703 -1.0812497 0 N 0 ;0
L 3.68986703 -1.0812497 3.68799911 -1.08249941 0 N 0 ;0
L 3.68799911 -1.04875217 3.68613287 -1.0475001 0 N 0 ;0
L 3.68613287 -1.0475001 3.68613287 -1.04500069 0 N 0 ;0
L 3.68613287 -1.04500069 3.68799911 -1.04375089 0 N 0 ;0
L 3.68799911 -1.04375089 3.68986703 -1.04500069 0 N 0 ;0
L 3.68986703 -1.04500069 3.68986703 -1.0475001 0 N 0 ;0
L 3.68986703 -1.0475001 3.68799911 -1.04875217 0 N 0 ;0
L 3.83799911 -1.005 3.83053228 -1.00749951 0 N 0 ;0
L 3.83053228 -1.00749951 3.82493346 -1.01375049 0 N 0 ;0
L 3.82493346 -1.01375049 3.82119931 -1.02124882 0 N 0 ;0
L 3.82119931 -1.02124882 3.8183999 -1.03125128 0 N 0 ;0
L 3.8183999 -1.03125128 3.81746673 -1.04250118 0 N 0 ;0
L 3.81746673 -1.04250118 3.8183999 -1.05375108 0 N 0 ;0
L 3.8183999 -1.05375108 3.82119931 -1.06375128 0 N 0 ;0
L 3.82119931 -1.06375128 3.82493346 -1.07125187 0 N 0 ;0
L 3.82493346 -1.07125187 3.83053228 -1.07750059 0 N 0 ;0
L 3.83053228 -1.07750059 3.83799911 -1.08 0 N 0 ;0
L 3.83799911 -1.08 3.84546585 -1.07750059 0 N 0 ;0
L 3.84546585 -1.07750059 3.85106644 -1.07125187 0 N 0 ;0
L 3.85106644 -1.07125187 3.85480059 -1.06375128 0 N 0 ;0
L 3.85480059 -1.06375128 3.8576 -1.05375108 0 N 0 ;0
L 3.8576 -1.05375108 3.85853317 -1.04250118 0 N 0 ;0
L 3.85853317 -1.04250118 3.8576 -1.03125128 0 N 0 ;0
L 3.8576 -1.03125128 3.85480059 -1.02124882 0 N 0 ;0
L 3.85480059 -1.02124882 3.85106644 -1.01375049 0 N 0 ;0
L 3.85106644 -1.01375049 3.84546585 -1.00749951 0 N 0 ;0
L 3.84546585 -1.00749951 3.83799911 -1.005 0 N 0 ;0
L 3.91299911 -1.08 3.91299911 -1.005 0 N 0 ;0
L 3.91299911 -1.005 3.9017998 -1.01999911 0 N 0 ;0
L 3.9017998 -1.08 3.92419843 -1.08 0 N 0 ;0

### steps/pcb/layers/l07_gnd3/features
#
#Num Features
#
F 2394

#
#Units
#
U INCH

#
#Feature symbol names
#
$0 r5
$1 r6
$2 r10
$3 r26
$4 r28
$5 r30
$6 r32
$7 r39
$8 r82
$9 r99
$10 r102
$11 r125
$12 r143
$13 r150
$14 024x051ob071x075p_l
$15 024x051ob071x075p_r
$16 024x063ob035x075p
$17 ths102x92.01x45x4x14 I
$18 ths105x95x45x4x14 I
$19 ths191.99x182x45x4x27 I
$20 ths42.01x31.99x45x4x10 I
$21 ths58.99x49x45x4x10 I
$22 ths89x79x45x4x11.99 I

#
#Feature attribute names
#
@0 .nomenclature
@1 .geometry
@2 .sip

#
#Feature attribute text strings
#
&0 V010C020P_TP030B
&1 V008C018P-ANTI28-NSM
&2 V010C020P
&3 TPV010CT020B030
&4 V008C018P_ANTI026_TP030B
&5 V008C018P_NATI28_TP030B_NSMT
&6 016C024P
&7 V008C018P_TP030B
&8 V008C018P
&9 V008C018P_ANTI28
&10 059C086P
&11 V008C018P_ANTI026_NSM
&12 076S104P
&13 076C104P
&14 079C100P
&15 V010C020P_SM014-NTH
&16 024X063OB035X075P
&17 166CT244CB198P
&18 024X051OB071X075P_R
&19 024X051OB071X075P_L
&20 033C057P
&21 063C090P
&22 MTH100C090N
&23 MTH125C115N
&24 MTH118C108N

#
#Layer features
#
S P 0;0,2=1
OB -24.76435 -17.98935 I
OS -24.76435 16.38535
OS 21.05735 16.38535
OS 21.05735 -17.98935
OS -24.76435 -17.98935
OE
OB -0.00110019685 0.21653976378 H
OC 0.039369783465 0.176069783465 0.039369783465 0.21653976378 N
OS 0.551194094488 0.176069980315
OC 0.59165 0.216525885827 0.551180019685 0.21653996063 N
OS 0.59165019685 0.46260019685
OC 0.629906200787 0.500870177165 0.629920177165 0.46260019685 Y
OS 1.273619980315 0.500869980315
OC 1.31188996063 0.462613779528 1.273619980315 0.4626 Y
OS 1.31188976378 0.21653976378
OC 1.35235984252 0.176069783465 1.352359744094 0.21653976378 N
OS 1.588594094488 0.176069980315
OC 1.62905 0.216525885827 1.588580019685 0.21653996063 N
OS 1.62905019685 0.430120177165
OC 1.77055019685 0.430134055118 1.69980019685 0.430120177165 Y
OS 1.770550098425 0.019702952756
OC 1.770872244094 0.018912204724 1.77165 0.019690059055 N
OS 1.790547933071 -0.000763484252
OC 1.791339862205 -0.001100098425 1.79133996063 -0.000000098425 N
OS 2.192896850394 -0.001100098425
OC 2.193511712598 -0.000920767717 2.192909645669 -0.00000019685 N
OC 2.193677066929 -0.000788484252 2.192910728346 -0.000000098425 N
OS 2.213388188976 0.018922637795
OC 2.213699901575 0.019689862205 2.212599901575 0.019689862205 N
OS 2.2137 0.29331003937
OC 2.2863 0.29331003937 2.25 0.29331003937 Y
OS 2.286300098425 0.019690059055
OC 2.286636712598 0.018898129921 2.287400098425 0.01969015748 N
OS 2.306298129921 -0.000763287402
OC 2.307090059055 -0.001099901575 2.30709015748 0.000000098425 N
OS 3.102347047244 -0.001099901575
OC 3.102961909449 -0.000920570866 3.10235984252 0 N
OC 3.10312726378 -0.000788287402 3.102360925197 0.000000098425 N
OS 3.122837893701 0.01892234252
OC 3.122970570866 0.019087992126 3.122049901575 0.019689468504 N
OC 3.123149901575 0.019702952756 3.12205 0.019690059055 N
OS 3.12314980315 0.462613779528
OC 3.161419783465 0.500869783465 3.161419783465 0.46259980315 Y
OS 6.561034055118 0.500869980315
OC 6.60148996063 0.541325885827 6.561019980315 0.54133996063 N
OS 6.60149015748 2.374999901575
OC 6.580710531496 2.39579015748 6.580705216535 2.375005216535 N
OS 6.572096555118 2.39578996063
OC 6.553530019685 2.414369980315 6.57211003937 2.414369980315 Y
OS 6.553529822835 2.826783759843
OC 6.572110137795 2.84535984252 6.57211476378 2.826774901575 Y
OS 6.572111122047 2.84535984252
OS 6.580724409449 2.84536003937
OC 6.60148996063 2.866125590551 6.58071003937 2.86613996063 N
OS 6.60149015748 4.33661023622
OC 6.561020177165 4.377080216535 6.561020177165 4.33661023622 N
OS 0.039355905512 4.377080019685
OC -0.0011 4.336624114173 0.039369980315 4.33661003937 N
OS -0.00110019685 0.21653976378
OE
SE
S P 0
OB -0.00110019685 0.21653976378 I
OS -0.0011 4.336624114173
OC 0.039355905512 4.377080019685 0.039369980315 4.33661003937 Y
OS 6.561020177165 4.377080216535
OC 6.60149015748 4.33661023622 6.561020177165 4.33661023622 Y
OS 6.60148996063 2.866125590551
OC 6.580724409449 2.84536003937 6.58071003937 2.86613996063 Y
OS 6.580725 2.84536003937
OS 6.580710629921 2.845359940945
OS 6.572123917323 2.845359940945
OS 6.572111122047 2.84535984252
OS 6.572110137795 2.84535984252
OC 6.553529822835 2.826783759843 6.57211476378 2.826774901575 N
OS 6.553530019685 2.414369980315
OC 6.572096555118 2.39578996063 6.57211003937 2.414369980315 N
OS 6.580710531496 2.39579015748
OC 6.60149015748 2.374999901575 6.580705216535 2.375005216535 Y
OS 6.60148996063 0.541325885827
OC 6.561034055118 0.500869980315 6.561019980315 0.54133996063 Y
OS 6.561034744094 0.500869980315
OS 6.561020570866 0.50086988189
OS 3.161433858268 0.50086988189
OS 3.161419783465 0.500869783465
OC 3.12314980315 0.462613779528 3.161419783465 0.46259980315 N
OS 3.123149901575 0.019702952756
OC 3.122970570866 0.019087992126 3.12205 0.019690059055 Y
OC 3.122837893701 0.01892234252 3.122049901575 0.019689468504 Y
OS 3.10312726378 -0.000788287402
OC 3.102961909449 -0.000920570866 3.102360925197 0.000000098425 Y
OC 3.102347047244 -0.001099901575 3.10235984252 0 Y
OS 2.307090059055 -0.001099901575
OC 2.306298129921 -0.000763287402 2.30709015748 0.000000098425 Y
OS 2.286636712598 0.018898129921
OC 2.286300098425 0.019690059055 2.287400098425 0.01969015748 Y
OS 2.2863 0.29331003937
OC 2.2137 0.29331003937 2.25 0.29331003937 N
OS 2.213699901575 0.019689862205
OC 2.213388188976 0.018922637795 2.212599901575 0.019689862205 Y
OS 2.193677066929 -0.000788484252
OC 2.193511712598 -0.000920767717 2.192910728346 -0.000000098425 Y
OC 2.192896850394 -0.001100098425 2.192909645669 -0.00000019685 Y
OS 1.791339862205 -0.001100098425
OC 1.790547933071 -0.000763484252 1.79133996063 -0.000000098425 Y
OS 1.770872244094 0.018912204724
OC 1.770550098425 0.019702952756 1.77165 0.019690059055 Y
OS 1.77055019685 0.430134055118
OC 1.62905019685 0.430120177165 1.69980019685 0.430120177165 N
OS 1.62905 0.216525885827
OC 1.588594094488 0.176069980315 1.588580019685 0.21653996063 Y
OS 1.588594783465 0.176069980315
OS 1.588580610236 0.17606988189
OS 1.352373917323 0.17606988189
OS 1.35235984252 0.176069783465
OC 1.31188976378 0.21653976378 1.352359744094 0.21653976378 Y
OS 1.31188996063 0.462613779528
OC 1.273619980315 0.500869980315 1.273619980315 0.4626 N
OS 0.629906200787 0.500870177165
OC 0.59165019685 0.46260019685 0.629920177165 0.46260019685 N
OS 0.59165 0.216525885827
OC 0.551194094488 0.176069980315 0.551180019685 0.21653996063 Y
OS 0.551194783465 0.176069980315
OS 0.551180610236 0.17606988189
OS 0.039383858268 0.17606988189
OS 0.039369783465 0.176069783465
OC -0.00110019685 0.21653976378 0.039369783465 0.21653976378 Y
OE
OB 0.03003996063 0.21653996063 H
OC 0.039369980315 0.20721003937 0.03936988189 0.21653996063 N
OS 0.551180019685 0.20721003937
OC 0.56051003937 0.21653996063 0.55118011811 0.21653996063 N
OS 0.56051003937 0.4626
OC 0.629919980315 0.53201003937 0.629919980315 0.462600098425 Y
OS 1.273619980315 0.53201003937
OC 1.343030019685 0.4626 1.273619980315 0.4626 Y
OS 1.343030019685 0.21653996063
OC 1.35236003937 0.20721003937 1.352359940945 0.21653996063 N
OS 1.588580019685 0.20721003937
OC 1.59791003937 0.21653996063 1.58858011811 0.21653996063 N
OS 1.59791003937 0.430119980315
OC 1.80168996063 0.430119980315 1.6998 0.430119980315 Y
OS 1.80168996063 0.262
OS 2.18256003937 0.262
OS 2.18256003937 0.29331003937
OC 2.31743996063 0.29331003937 2.25 0.29331003937 Y
OS 2.31743996063 0.262
OS 3.09201003937 0.262
OS 3.09201003937 0.4626
OC 3.161419980315 0.53201003937 3.161419980315 0.462600098425 Y
OS 6.561019980315 0.53201003937
OC 6.57035 0.54133996063 6.56102007874 0.54133996063 N
OS 6.57035 2.364680019685
OC 6.52238996063 2.414369980315 6.572111220472 2.41437007874 Y
OS 6.52238996063 2.826780019685
OC 6.57035 2.876469980315 6.572115452756 2.826775885827 Y
OS 6.57035 4.33661003937
OC 6.561019980315 4.34593996063 6.56102007874 4.33661003937 N
OS 0.039369980315 4.34593996063
OC 0.03003996063 4.33661003937 0.03936988189 4.33661003937 N
OS 0.03003996063 0.21653996063
OE
OB 0.36981003937 0.36811003937 I
OC 0.36981003937 0.36811003937 0.295280019685 0.36811003937 Y
OE
OB 0.36981003937 3.73031003937 I
OC 0.36981003937 3.73031003937 0.295280019685 3.73031003937 Y
OE
OB 0.688980019685 3.560980019685 I
OS 0.688980019685 3.589019980315
OS 0.749019980315 3.589019980315
OS 0.749019980315 3.560980019685
OS 0.688980019685 3.560980019685
OE
OB 1.058980019685 3.810980019685 I
OS 1.058980019685 3.839019980315
OS 1.119019980315 3.839019980315
OS 1.119019980315 3.810980019685
OS 1.058980019685 3.810980019685
OE
OB 1.4977 1.060430019685 I
OC 1.4977 1.060430019685 1.435669980315 1.060430019685 Y
OE
OB 1.5227 2.680430019685 I
OC 1.5227 2.680430019685 1.460669980315 2.680430019685 Y
OE
OB 2.39006003937 0.679980019685 I
OS 2.39006003937 0.750019980315
OS 2.4201 0.750019980315
OS 2.4201 0.679980019685
OS 2.39006003937 0.679980019685
OE
OB 2.4562 0.748980019685 I
OS 2.4562 0.777019980315
OS 2.51623996063 0.777019980315
OS 2.51623996063 0.748980019685
OS 2.4562 0.748980019685
OE
OB 2.7477 1.121430019685 I
OC 2.7477 1.121430019685 2.685669980315 1.121430019685 Y
OE
OB 2.7477 2.559430019685 I
OC 2.7477 2.559430019685 2.685669980315 2.559430019685 Y
OE
OB 2.629380019685 0.338980019685 I
OS 2.629380019685 0.399019980315
OS 2.6574 0.399019980315
OS 2.6574 0.338980019685
OS 2.629380019685 0.338980019685
OE
OB 2.65306003937 0.748980019685 I
OS 2.65306003937 0.777019980315
OS 2.713080019685 0.777019980315
OS 2.713080019685 0.748980019685
OS 2.65306003937 0.748980019685
OE
OB 2.783 1.971980019685 I
OS 2.783 2.002019980315
OS 2.853019980315 2.002019980315
OS 2.853019980315 1.971980019685
OS 2.783 1.971980019685
OE
OB 2.78686003937 0.338980019685 I
OS 2.78686003937 0.399019980315
OS 2.814880019685 0.399019980315
OS 2.814880019685 0.338980019685
OS 2.78686003937 0.338980019685
OE
OB 2.80453996063 0.748980019685 I
OS 2.80453996063 0.777019980315
OS 2.86456003937 0.777019980315
OS 2.86456003937 0.748980019685
OS 2.80453996063 0.748980019685
OE
OB 2.829980019685 1.823980019685 I
OS 2.829980019685 1.894019980315
OS 2.860019980315 1.894019980315
OS 2.860019980315 1.823980019685
OS 2.829980019685 1.823980019685
OE
OB 2.94433996063 0.338980019685 I
OS 2.94433996063 0.399019980315
OS 2.97236003937 0.399019980315
OS 2.97236003937 0.338980019685
OS 2.94433996063 0.338980019685
OE
OB 2.94433996063 0.434980019685 I
OS 2.94433996063 0.495019980315
OS 2.97236003937 0.495019980315
OS 2.97236003937 0.434980019685
OS 2.94433996063 0.434980019685
OE
OB 3.10516003937 0.875 I
OS 3.125 0.89483996063
OS 3.167469980315 0.852369980315
OS 3.147630019685 0.832530019685
OS 3.10516003937 0.875
OE
OB 3.213080019685 1.888980019685 I
OS 3.213080019685 1.917
OS 3.273119980315 1.917
OS 3.273119980315 1.888980019685
OS 3.213080019685 1.888980019685
OE
OB 3.359980019685 1.142980019685 I
OS 3.359980019685 1.213019980315
OS 3.390019980315 1.213019980315
OS 3.390019980315 1.142980019685
OS 3.359980019685 1.142980019685
OE
OB 3.398980019685 1.069980019685 I
OS 3.398980019685 1.100019980315
OS 3.469019980315 1.100019980315
OS 3.469019980315 1.069980019685
OS 3.398980019685 1.069980019685
OE
OB 3.439 1.884980019685 I
OS 3.439 1.945
OS 3.467019980315 1.945
OS 3.467019980315 1.884980019685
OS 3.439 1.884980019685
OE
OB 3.49563996063 1.03206003937 I
OS 3.49563996063 1.062080019685
OS 3.56566003937 1.062080019685
OS 3.56566003937 1.03206003937
OS 3.49563996063 1.03206003937
OE
OB 3.610980019685 0.905980019685 I
OS 3.610980019685 0.934019980315
OS 3.671019980315 0.934019980315
OS 3.671019980315 0.905980019685
OS 3.610980019685 0.905980019685
OE
OB 3.637 1.869580019685 I
OS 3.637 1.9296
OS 3.665019980315 1.9296
OS 3.665019980315 1.869580019685
OS 3.637 1.869580019685
OE
OB 3.871930019685 1.417019980315 I
OC 3.871930019685 1.443080019685 3.871930019685 1.43005 Y
OS 3.9113 1.443080019685
OC 3.9113 1.417019980315 3.9113 1.43005 Y
OS 3.871930019685 1.417019980315
OE
OB 3.871930019685 1.49576003937 I
OC 3.871930019685 1.521819980315 3.871930019685 1.508790059055 Y
OS 3.9113 1.521819980315
OC 3.9113 1.49576003937 3.9113 1.508790059055 Y
OS 3.871930019685 1.49576003937
OE
OB 3.871930019685 1.5745 I
OC 3.871930019685 1.60056003937 3.871930019685 1.587530019685 Y
OS 3.9113 1.60056003937
OC 3.9113 1.5745 3.9113 1.587530019685 Y
OS 3.871930019685 1.5745
OE
OB 3.871930019685 1.65323996063 I
OC 3.871930019685 1.6793 3.871930019685 1.666269980315 Y
OS 3.9113 1.6793
OC 3.9113 1.65323996063 3.9113 1.666269980315 Y
OS 3.871930019685 1.65323996063
OE
OB 3.950669980315 1.53513996063 I
OC 3.950669980315 1.561180019685 3.950669980315 1.54816003937 Y
OS 3.99003996063 1.561180019685
OC 3.99003996063 1.53513996063 3.99003996063 1.54816003937 Y
OS 3.950669980315 1.53513996063
OE
OB 3.950669980315 1.692619980315 I
OC 3.950669980315 1.71866003937 3.950669980315 1.705640059055 Y
OS 3.99003996063 1.71866003937
OC 3.99003996063 1.692619980315 3.99003996063 1.705640059055 Y
OS 3.950669980315 1.692619980315
OE
OB 3.950669980315 1.4564 I
OC 3.950669980315 1.48243996063 3.950669980315 1.469419980315 Y
OS 3.99003996063 1.48243996063
OC 3.99003996063 1.4564 3.99003996063 1.469419980315 Y
OS 3.950669980315 1.4564
OE
OB 3.950669980315 1.613880019685 I
OC 3.950669980315 1.639919980315 3.950669980315 1.6269 Y
OS 3.99003996063 1.639919980315
OC 3.99003996063 1.613880019685 3.99003996063 1.6269 Y
OS 3.950669980315 1.613880019685
OE
OB 3.997480019685 1.145980019685 I
OS 3.997480019685 1.176
OS 4.067519980315 1.176
OS 4.067519980315 1.145980019685
OS 3.997480019685 1.145980019685
OE
OB 4.029419980315 1.49576003937 I
OC 4.029419980315 1.521819980315 4.029419980315 1.508790059055 Y
OS 4.06878996063 1.521819980315
OC 4.06878996063 1.49576003937 4.06878996063 1.508790059055 Y
OS 4.029419980315 1.49576003937
OE
OB 4.029419980315 1.65323996063 I
OC 4.029419980315 1.6793 4.029419980315 1.666269980315 Y
OS 4.06878996063 1.6793
OC 4.06878996063 1.65323996063 4.06878996063 1.666269980315 Y
OS 4.029419980315 1.65323996063
OE
OB 4.3575 1.150980019685 I
OS 4.3575 1.181
OS 4.427519980315 1.181
OS 4.427519980315 1.150980019685
OS 4.3575 1.150980019685
OE
OB 4.42311003937 1.850080019685 I
OC 4.42311003937 1.87613996063 4.42311003937 1.86311003937 Y
OS 4.462480019685 1.87613996063
OC 4.462480019685 1.850080019685 4.462480019685 1.86311003937 Y
OS 4.42311003937 1.850080019685
OE
OB 4.462480019685 1.417019980315 I
OC 4.462480019685 1.443080019685 4.462480019685 1.43005 Y
OS 4.50185 1.443080019685
OC 4.50185 1.417019980315 4.50185 1.43005 Y
OS 4.462480019685 1.417019980315
OE
OB 4.5223 1.20666003937 I
OS 4.5223 1.236680019685
OS 4.592319980315 1.236680019685
OS 4.592319980315 1.20666003937
OS 4.5223 1.20666003937
OE
OB 4.61996003937 1.2989 I
OC 4.61996003937 1.32496003937 4.61996003937 1.311930019685 Y
OS 4.659330019685 1.32496003937
OC 4.659330019685 1.2989 4.659330019685 1.311930019685 Y
OS 4.61996003937 1.2989
OE
OB 4.6987 1.4564 I
OC 4.6987 1.48243996063 4.6987 1.469419980315 Y
OS 4.738069980315 1.48243996063
OC 4.738069980315 1.4564 4.738069980315 1.469419980315 Y
OS 4.6987 1.4564
OE
OB 4.72503996063 1.3513 I
OS 4.72503996063 1.390669980315
OC 4.7511 1.390669980315 4.738069980315 1.390669980315 Y
OS 4.7511 1.3513
OC 4.72503996063 1.3513 4.738069980315 1.3513 Y
OE
OB 6.190030019685 2.094 I
OC 6.190030019685 2.094 5.99 2.094 Y
OE
OB 5.974969980315 1.045 I
OC 5.984369980315 1.1056 6.174999507874 1.045001377953 Y
OC 5.97846003937 1.12348996063 6.008502165354 1.123493208661 Y
OS 5.97846003937 1.1235
OC 6.00696003937 1.1535 6.008499507874 1.1235 Y
OC 6.175 1.245030019685 6.175000098425 1.045012598425 Y
OC 6.375030019685 1.045 6.175 1.045 Y
OC 6.362830019685 0.97621003937 6.174992913386 1.045 Y
OC 6.365 0.96501003937 6.334998523622 0.965007480315 Y
OS 6.365 0.965
OC 6.342730019685 0.93601003937 6.334996161417 0.965 Y
OC 6.175 0.844969980315 6.174999901575 1.045000984252 Y
OC 5.974969980315 1.045 6.175 1.045 Y
OE
OB 6.1856 2.230719980315 I
OS 6.1856 2.29076003937
OS 6.213619980315 2.29076003937
OS 6.213619980315 2.230719980315
OS 6.1856 2.230719980315
OE
OB 6.424580019685 3.34448996063 I
OC 6.424580019685 3.34448996063 6.34055 3.34448996063 Y
OE
OB 6.424580019685 3.67518996063 I
OC 6.424580019685 3.67518996063 6.34055 3.67518996063 Y
OE
OB 6.474919980315 0.65353996063 I
OC 6.474919980315 0.65353996063 6.40038996063 0.65353996063 Y
OE
OB 6.474919980315 4.17835 I
OC 6.474919980315 4.17835 6.40038996063 4.17835 Y
OE
SE
P 4.31 4.065 6 P 0 8 0;1=0
P 4.31 4.115 6 P 0 8 0;1=0
P 4.61 2.3 6 P 0 8 0;1=0
P 4.50185 2.05996004 4 P 0 8 0;1=1
P 4.49 2.275 6 P 0 8 0;1=0
P 4.435 2.315 6 P 0 8 0;1=0
P 4.49 2.325 6 P 0 8 0;1=0
P 4.435 2.365 6 P 0 8 0;1=0
P 3.655 2.465 6 P 0 8 0;1=0
P 3.125 1.605 6 P 0 8 0;1=0
P 3.65 2.68 6 P 0 8 0;1=2
P 3.12 2.645 6 P 0 8 0;1=2
P 4.1869 2.09933002 4 P 0 8 0;1=1
P 3.765 2.69 6 P 0 8 0;1=0
P 4.50185 1.50878996 4 P 0 8 0;1=1
P 4.3 3.865 4 P 0 8 0;1=3
P 3.36525 3.305 3 P 0 8 0;1=4
P 3.37 3.44 4 P 0 8 0;1=3
P 4.795 0.925 4 P 0 8 0;1=3
P 4.08 3.27 4 P 0 8 0;1=3
P 3.95 3.82 4 P 0 8 0;1=3
P 3.746 1.782 4 P 0 8 0;1=3
P 4.06878996 1.58753002 4 P 0 8 0;1=1
P 4.205 0.82 4 P 0 8 0;1=3
P 3.82286004 0.86213996 6 P 0 8 0;1=0
P 3.705 0.84 4 P 0 8 0;1=3
P 0.496 2.13455 6 P 0 8 0;1=0
P 0.528 2.72 6 P 0 8 0;1=0
P 0.575 1.015 6 P 0 8 0;1=0
P 0.48956998 1.53618996 6 P 0 8 0;1=0
P 4.65933002 1.98121998 4 P 0 8 0;1=1
P 4.06878996 1.90248002 4 P 0 8 0;1=1
P 4.50185 1.39066998 4 P 0 8 0;1=1
P 4.06878996 2.1387 4 P 0 8 0;1=1
P 4.22626998 2.05996004 4 P 0 8 0;1=1
P 3.95066998 2.05996004 4 P 0 8 0;1=1
P 4.22626998 2.02058996 4 P 0 8 0;1=1
P 4.26563996 2.09933002 4 P 0 8 0;1=1
P 4.26563996 2.05996004 4 P 0 8 0;1=1
P 4.50185 1.90248002 4 P 0 8 0;1=1
P 4.73806998 2.09933002 4 P 0 8 0;1=1
P 4.02941998 2.02058996 4 P 0 8 0;1=1
P 4.50185 1.86311004 4 P 0 8 0;1=1
P 4.6987 2.05996004 4 P 0 8 0;1=1
P 4.61996004 1.94185 4 P 0 8 0;1=1
P 4.61996004 1.98121998 4 P 0 8 0;1=1
P 4.26563996 2.02058996 4 P 0 8 0;1=1
P 4.61996004 1.90248002 4 P 0 8 0;1=1
P 4.58058996 1.98121998 4 P 0 8 0;1=1
P 4.54121998 2.02058996 4 P 0 8 0;1=1
P 4.34436998 2.09933002 4 P 0 8 0;1=1
P 4.06878996 2.09933002 4 P 0 8 0;1=5
P 4.6987 1.50878996 4 P 0 8 0;1=1
P 4.54121998 1.98121998 4 P 0 8 0;1=1
P 4.06878996 2.05996004 4 P 0 8 0;1=1
P 4.65933002 1.50878996 4 P 0 8 0;1=1
P 3.95066998 2.09933002 4 P 0 8 0;1=1
P 4.61996004 1.54816004 4 P 0 8 0;1=1
P 3.99005 2.09933002 4 P 0 8 0;1=5
P 4.58058996 1.54816004 4 P 0 8 0;1=1
P 4.6987 1.94185 4 P 0 8 0;1=1
P 4.50185 2.02058996 4 P 0 8 0;1=1
P 4.46248002 2.02058996 4 P 0 8 0;1=1
P 4.42311004 1.98121998 4 P 0 8 0;1=1
P 4.46248002 1.94185 4 P 0 8 0;1=1
P 4.38373996 1.86311004 4 P 0 8 0;1=1
P 4.38373996 1.82373996 4 P 0 8 0;1=1
P 4.46248002 1.98121998 4 P 0 8 0;1=1
P 4.10816004 1.94185 4 P 0 8 0;1=1
P 4.02941998 1.98121998 4 P 0 8 0;1=1
P 4.58058996 2.17806998 4 P 0 8 0;1=1
P 4.73806998 1.90248002 4 P 0 8 0;1=1
P 4.54121998 2.1387 4 P 0 8 0;1=1
P 4.10816004 2.02058996 4 P 0 8 0;1=1
P 4.50185 2.1387 4 P 0 8 0;1=1
P 3.99005 1.94185 4 P 0 8 0;1=1
P 4.02941998 1.94185 4 P 0 8 0;1=1
P 4.50185 2.09933002 4 P 0 8 0;1=1
P 4.14753002 2.02058996 4 P 0 8 0;1=1
P 4.61996004 2.17806998 4 P 0 8 0;1=1
P 4.02941998 1.86311004 4 P 0 8 0;1=1
P 4.06878996 1.43005 4 P 0 8 0;1=1
P 4.54121998 1.54816004 4 P 0 8 0;1=1
P 4.26563996 1.50878996 4 P 0 8 0;1=1
P 4.1869 1.94185 4 P 0 8 0;1=1
P 4.14753002 1.46941998 4 P 0 8 0;1=1
P 4.1869 1.46941998 4 P 0 8 0;1=1
P 4.1869 2.1387 4 P 0 8 0;1=1
P 4.6987 1.43005 4 P 0 8 0;1=1
P 4.10816004 1.39066998 4 P 0 8 0;1=1
P 4.65933002 1.43005 4 P 0 8 0;1=1
P 4.14753002 1.39066998 4 P 0 8 0;1=1
P 4.61996004 1.43005 4 P 0 8 0;1=1
P 4.10816004 1.43005 4 P 0 8 0;1=1
P 4.58058996 1.43005 4 P 0 8 0;1=1
P 4.14753002 1.43005 4 P 0 8 0;1=1
P 4.1869 1.43005 4 P 0 8 0;1=1
P 4.22626998 1.43005 4 P 0 8 0;1=1
P 4.54121998 1.46941998 4 P 0 8 0;1=1
P 4.22626998 1.39066998 4 P 0 8 0;1=1
P 4.50185 1.46941998 4 P 0 8 0;1=1
P 4.26563996 1.39066998 4 P 0 8 0;1=1
P 4.61996004 1.46941998 4 P 0 8 0;1=1
P 4.26563996 1.31193002 4 P 0 8 0;1=1
P 4.61996004 1.50878996 4 P 0 8 0;1=1
P 4.34436998 1.31193002 4 P 0 8 0;1=1
P 4.58058996 1.46941998 4 P 0 8 0;1=1
P 4.34436998 1.3513 4 P 0 8 0;1=1
P 4.54121998 1.50878996 4 P 0 8 0;1=1
P 4.34436998 1.39066998 4 P 0 8 0;1=1
P 4.1869 1.50878996 4 P 0 8 0;1=1
P 4.46248002 1.50878996 4 P 0 8 0;1=1
P 4.22626998 1.50878996 4 P 0 8 0;1=1
P 4.26563996 1.43005 4 P 0 8 0;1=5
P 4.26563996 1.46941998 4 P 0 8 0;1=1
P 4.38373996 1.39066998 4 P 0 8 0;1=1
P 4.38373996 1.43005 4 P 0 8 0;1=1
P 4.54121998 1.31193002 4 P 0 8 0;1=1
P 4.49876004 1.31501998 4 P 0 8 0;1=1
P 4.34436998 1.98121998 4 P 0 8 0;1=1
P 4.57843996 1.35345 4 P 0 8 0;1=1
P 3.9113 1.3513 4 P 0 8 0;1=1
P 4.54121998 1.3513 4 P 0 8 0;1=1
P 3.95066998 1.3513 4 P 0 8 0;1=1
P 4.45938996 1.35438996 4 P 0 8 0;1=1
P 3.99 1.31188002 4 P 0 8 0;1=1
P 4.46248002 1.39066998 4 P 0 8 0;1=1
P 4.65933002 1.3513 4 P 0 8 0;1=1
P 3.99 1.35125 4 P 0 8 0;1=1
P 4.61996004 1.3513 4 P 0 8 0;1=1
P 4.6987 1.86311004 4 P 0 8 0;1=1
P 4.46248002 2.05996004 4 P 0 8 0;1=1
P 4.06873996 1.31188002 4 P 0 8 0;1=1
P 4.65933002 1.82373996 4 P 0 8 0;1=1
P 4.42311004 2.05996004 4 P 0 8 0;1=1
P 4.10811004 1.31188002 4 P 0 8 0;1=1
P 4.58058996 1.39066998 4 P 0 8 0;1=1
P 4.02941998 1.39066998 4 P 0 8 0;1=1
P 4.54121998 1.39066998 4 P 0 8 0;1=1
P 4.06878996 1.39066998 4 P 0 8 0;1=1
P 4.73806998 1.78436998 4 P 0 8 0;1=1
P 4.73806998 1.31193002 4 P 0 8 0;1=1
P 4.1869 1.31193002 4 P 0 8 0;1=1
P 4.73806998 1.70563996 4 P 0 8 0;1=1
P 4.6987 1.31193002 4 P 0 8 0;1=1
P 4.22626998 1.31193002 4 P 0 8 0;1=1
P 4.10816004 1.3513 4 P 0 8 0;1=1
P 4.14753002 1.3513 4 P 0 8 0;1=1
P 4.6987 1.39066998 4 P 0 8 0;1=1
P 4.1869 1.3513 4 P 0 8 0;1=1
P 4.65933002 1.39066998 4 P 0 8 0;1=1
P 4.22626998 1.3513 4 P 0 8 0;1=1
P 4.73806998 2.17806998 4 P 0 8 0;1=1
P 4.73806998 2.1387 4 P 0 8 0;1=1
P 4.58058996 2.09933002 4 P 0 8 0;1=1
P 4.54121998 2.09933002 4 P 0 8 0;1=1
P 4.58058996 1.86311004 4 P 0 8 0;1=1
P 4.65933002 2.05996004 4 P 0 8 0;1=1
P 4.58058996 2.05996004 4 P 0 8 0;1=1
P 4.54121998 1.90248002 4 P 0 8 0;1=1
P 4.58058996 2.02058996 4 P 0 8 0;1=1
P 4.22626998 1.98121998 4 P 0 8 0;1=1
P 4.26563996 1.94185 4 P 0 8 0;1=1
P 4.10816004 1.98121998 4 P 0 8 0;1=1
P 4.14753002 1.98121998 4 P 0 8 0;1=1
P 4.61996004 2.1387 4 P 0 8 0;1=1
P 4.6987 1.70563996 4 P 0 8 0;1=1
P 4.6987 1.66626998 4 P 0 8 0;1=1
P 1.45 3.59 6 P 0 8 0;1=0
P 1.56 3.165 6 P 0 8 0;1=2
P 1.56 3.205 6 P 0 8 0;1=0
P 0.72 3.463 6 P 0 8 0;1=2
P 0.42326004 3.4315 7 P 0 8 0;1=6
P 0.40553996 3.4008 7 P 0 8 0;1=6
P 0.2815 3.4315 7 P 0 8 0;1=6
P 0.26378002 3.4008 7 P 0 8 0;1=6
P 0.71 3.305 4 P 0 8 0;1=3
P 1.14 3.52 6 P 0 8 0;1=0
P 1.245 3.52 6 P 0 8 0;1=0
P 4.705 3.95 3 P 0 8 0;1=4
P 4.705 3.91 6 P 0 8 0;1=2
P 1.566 2.95 6 P 0 8 0;1=0
P 1.045 3.77 6 P 0 8 0;1=2
P 1.515 3.58 6 P 0 8 0;1=2
P 6.145 4.035 6 P 0 8 0;1=0
P 1.37 3.64 6 P 0 8 0;1=2
P 1.667 3.438 6 P 0 8 0;1=2
P 1.591 3.546 6 P 0 8 0;1=2
P 1.13 3.445 6 P 0 8 0;1=2
P 0.95 3.445 6 P 0 8 0;1=2
P 2.19 3.488 6 P 0 8 0;1=2
P 2.192 3.388 6 P 0 8 0;1=2
P 1.41916004 3.33916004 6 P 0 8 0;1=2
P 1.407 3.2 6 P 0 8 0;1=2
P 1.495 3.11033996 6 P 0 8 0;1=2
P 1.535 3.105 4 P 0 8 0;1=3
P 1.15253002 3.06246998 6 P 0 8 0;1=2
P 0.95 3.215 6 P 0 8 0;1=2
P 0.945 3.125 6 P 0 8 0;1=2
P 1.175 2.9 6 P 0 8 0;1=2
P 1.025 3.02 6 P 0 8 0;1=2
P 5.275 3.891 6 P 0 8 0;1=0
P 5.275 3.931 6 P 0 8 0;1=2
P 5.275 3.971 6 P 0 8 0;1=0
P 5.321 3.99 6 P 0 8 0;1=2
P 5.762 3.425 5 P 0 8 0;1=7
P 5.567 3.203 6 P 0 8 0;1=2
P 5.617 3.203 6 P 0 8 0;1=0
P 5.62 3.316 6 P 0 8 0;1=2
P 5.625 3.261 6 P 0 8 0;1=0
P 5.625 3.361 6 P 0 8 0;1=2
P 5.6 3.421 6 P 0 8 0;1=0
P 5.552 3.71141004 5 P 0 8 0;1=8
P 5.552 3.74683996 5 P 0 8 0;1=8
P 5.552 3.78226998 5 P 0 8 0;1=8
P 5.552 3.67596998 5 P 0 8 0;1=8
P 5.52 3.78226998 5 P 0 8 0;1=8
P 5.52 3.74683996 5 P 0 8 0;1=8
P 5.52 3.71141004 5 P 0 8 0;1=8
P 5.52 3.67596998 5 P 0 8 0;1=8
P 0.978 3.918 4 P 0 8 0;1=3
P 0.928 3.961 6 P 0 8 0;1=2
P 0.968 3.961 6 P 0 8 0;1=2
P 0.968 4.021 6 P 0 8 0;1=2
P 0.928 4.021 6 P 0 8 0;1=0
P 0.928 4.081 6 P 0 8 0;1=2
P 0.968 4.081 6 P 0 8 0;1=0
P 0.928 4.141 6 P 0 8 0;1=0
P 0.968 4.141 6 P 0 8 0;1=2
P 0.603 3.951 6 P 0 8 0;1=0
P 0.643 3.956 6 P 0 8 0;1=2
P 0.603 4.011 6 P 0 8 0;1=2
P 0.643 4.016 6 P 0 8 0;1=0
P 0.603 4.071 6 P 0 8 0;1=0
P 0.643 4.076 6 P 0 8 0;1=2
P 0.603 4.131 6 P 0 8 0;1=2
P 0.643 4.136 6 P 0 8 0;1=0
P 0.854 3.942 6 P 0 8 0;1=2
P 0.807 3.942 6 P 0 8 0;1=2
P 0.76 3.942 6 P 0 8 0;1=2
P 0.713 3.942 6 P 0 8 0;1=2
P 0.76 4.042 6 P 0 8 0;1=2
P 0.76 3.992 6 P 0 8 0;1=2
P 0.713 3.992 6 P 0 8 0;1=2
P 0.713 4.042 6 P 0 8 0;1=2
P 0.713 4.092 6 P 0 8 0;1=2
P 0.76 4.092 6 P 0 8 0;1=2
P 0.807 4.092 6 P 0 8 0;1=2
P 0.807 4.042 6 P 0 8 0;1=2
P 0.807 3.992 6 P 0 8 0;1=2
P 0.854 3.992 6 P 0 8 0;1=2
P 0.854 4.042 6 P 0 8 0;1=2
P 0.854 4.092 6 P 0 8 0;1=2
P 0.74 1.005 6 P 0 8 0;1=0
P 0.79 1.005 6 P 0 8 0;1=0
P 0.84 1.005 6 P 0 8 0;1=0
P 1.568 3.011 6 P 0 8 0;1=0
P 1.738 3.241 6 P 0 8 0;1=0
P 1.765 2.9 6 P 0 8 0;1=0
P 1.78 3.095 6 P 0 8 0;1=0
P 1.795 2.946 6 P 0 8 0;1=0
P 5.2 0.87 6 P 0 8 0;1=0
P 4.47 3.21998002 6 P 0 8 0;1=0
P 4.385 3.645 6 P 0 8 0;1=0
P 0.78 3.305 4 P 0 8 0;1=3
P 1.03 3.515 6 P 0 8 0;1=0
P 1.19 3.52 6 P 0 8 0;1=0
P 0.95 2.915 4 P 0 8 0;1=3
P 0.945 2.99 4 P 0 8 0;1=3
P 0.885 3.03 4 P 0 8 0;1=3
P 0.875 2.955 4 P 0 8 0;1=3
P 0.795 3.085 4 P 0 8 0;1=3
P 0.55 3.36 6 P 0 8 0;1=0
P 0.3701 3.4008 7 P 0 8 0;1=6
P 0.55 3.554 6 P 0 8 0;1=0
P 0.31693996 3.4315 7 P 0 8 0;1=6
P 5.92 1.57063002 6 P 0 8 0;1=0
P 6.22 1.57 6 P 0 8 0;1=0
P 5.92 1.46 6 P 0 8 0;1=0
P 6.22 1.465 6 P 0 8 0;1=0
P 5.92 1.68 6 P 0 8 0;1=0
P 6.22035 1.67063002 6 P 0 8 0;1=0
P 5.92 1.78 6 P 0 8 0;1=0
P 6.22 1.755 6 P 0 8 0;1=0
P 6.09423996 4.13778996 6 P 0 8 0;1=0
P 3.51 3.08 6 P 0 8 0;1=0
P 1.025 2.9 6 P 0 8 0;1=2
P 4.42311004 1.94185 4 P 0 8 0;1=1
P 3.46 3.065 6 P 0 8 0;1=0
P 1.125 2.9 6 P 0 8 0;1=2
P 4.42311004 1.90248002 4 P 0 8 0;1=1
P 3.035 1.64 6 P 0 8 0;1=2
P 3.445 2.65 4 P 0 8 0;1=3
P 1.1288 0.7302 5 P 0 8 0;1=7
P 3.075 1.605 6 P 0 8 0;1=2
P 3.365 2.95 3 P 0 8 0;1=4
P 0.755 0.62 4 P 0 8 0;1=3
P 0.715 0.77 6 P 0 8 0;1=0
P 0.83 3.445 6 P 0 8 0;1=0
P 0.795 3.485 6 P 0 8 0;1=0
P 0.83 3.525 6 P 0 8 0;1=0
P 0.951 3.519 6 P 0 8 0;1=0
P 0.82951004 3.2794 6 P 0 8 0;1=0
P 0.79 3.155 6 P 0 8 0;1=0
P 0.78635 3.24491998 6 P 0 8 0;1=0
P 1.26 3.18 6 P 0 8 0;1=0
P 1.295 3.28 6 P 0 8 0;1=0
P 1.075 3.02 6 P 0 8 0;1=0
P 1.125 3.02 6 P 0 8 0;1=0
P 1.073 3.825 4 P 0 8 0;1=9
P 0.703 3.575 4 P 0 8 0;1=9
P 0.35238002 3.4315 7 P 0 8 0;1=6
P 0.33466004 3.4008 7 P 0 8 0;1=6
P 0.735 3.575 4 P 0 8 0;1=9
P 1.105 3.825 4 P 0 8 0;1=9
P 0.38781998 3.4315 7 P 0 8 0;1=6
P 0.29921998 3.4008 7 P 0 8 0;1=6
P 0.995 3.7 4 P 0 8 0;1=3
P 4.285 3.46 6 P 0 8 0;1=2
P 2.15 3.438 6 P 0 8 0;1=0
P 2.05 3.538 6 P 0 8 0;1=0
P 2.05 3.488 6 P 0 8 0;1=0
P 1.29 3.215 6 P 0 8 0;1=2
P 1.0541 3.185 6 P 0 8 0;1=0
P 1.3 3.49663996 6 P 0 8 0;1=2
P 1.04018996 3.47425 6 P 0 8 0;1=2
P 4.205 3.66 6 P 0 8 0;1=0
P 0.975 3.41 6 P 0 8 0;1=2
P 4.225 3.545 6 P 0 8 0;1=0
P 1.015 3.41 6 P 0 8 0;1=2
P 3.95 3.6 6 P 0 8 0;1=0
P 0.835 3.6 6 P 0 8 0;1=2
P 3.95 3.7 6 P 0 8 0;1=0
P 0.915 3.595 6 P 0 8 0;1=2
P 4.1184 3.5362 6 P 0 8 0;1=2
P 4.085 3.11 6 P 0 8 0;1=0
P 4.51 3.065 6 P 0 8 0;1=2
P 4.33381998 3.60466004 6 P 0 8 0;1=0
P 4.34 3.28 6 P 0 8 0;1=2
P 4.335 3.665 6 P 0 8 0;1=0
P 4.09 3.71338996 6 P 0 8 0;1=0
P 3.38 1.025 6 P 0 8 0;1=2
P 4.585 0.865 6 P 0 8 0;1=0
P 0.62 3.235 6 P 0 8 0;1=2
P 3.925 3.239 6 P 0 8 0;1=0
P 0.825 3.39 6 P 0 8 0;1=2
P 0.795 3.4179 6 P 0 8 0;1=2
P 3.795 3.758 6 P 0 8 0;1=0
P 3.62 1.28 6 P 0 8 0;1=2
P 5.195 0.755 6 P 0 8 0;1=0
P 4.96 0.85 6 P 0 8 0;1=2
P 0.66 3.185 6 P 0 8 0;1=2
P 3.62 1.235 6 P 0 8 0;1=2
P 5.195 0.815 6 P 0 8 0;1=0
P 4.937 0.79161004 6 P 0 8 0;1=2
P 0.66 3.235 6 P 0 8 0;1=2
P 4.205 3.81 6 P 0 8 0;1=2
P 5.814 2.821 5 P 0 8 0;1=7
P 4.19 3.735 6 P 0 8 0;1=2
P 5.814 2.721 5 P 0 8 0;1=7
P 3.895 3.7 6 P 0 8 0;1=2
P 5.815 3.021 5 P 0 8 0;1=7
P 4.135 3.735 6 P 0 8 0;1=2
P 5.814 2.621 5 P 0 8 0;1=7
P 2.3 3.475 6 P 0 8 0;1=2
P 5.045 3.405 6 P 0 8 0;1=2
P 6.33 2.67 5 P 0 8 0;1=7
P 1.35 3.12 6 P 0 8 0;1=2
P 2.255 3.475 6 P 0 8 0;1=2
P 5.09 3.405 6 P 0 8 0;1=2
P 6.33 2.865 6 P 0 8 0;1=0
P 1.46 3.34 6 P 0 8 0;1=2
P 4.575 2.235 6 P 0 8 0;1=2
P 4.50185 1.94185 4 P 0 8 0;1=1
P 4.705 0.825 6 P 0 8 0;1=0
P 4.575 2.275 6 P 0 8 0;1=2
P 4.38373996 1.98121998 4 P 0 8 0;1=1
P 4.755 0.825 6 P 0 8 0;1=0
P 1.26 0.72 6 P 0 8 0;1=0
P 4.6987 1.82373996 4 P 0 8 0;1=1
P 0.842 0.75 6 P 0 8 0;1=0
P 4.73806998 1.82373996 4 P 0 8 0;1=1
P 4.10816004 1.90248002 4 P 0 8 0;1=5
P 3.73648996 1.85735 6 P 0 8 0;1=2
P 4.10816004 1.82373996 4 P 0 8 0;1=1
P 4.345 3.02 6 P 0 8 0;1=2
P 4.075 3.005 6 P 0 8 0;1=2
P 3.925 3.291 6 P 0 8 0;1=0
P 4.14753002 1.82373996 4 P 0 8 0;1=1
P 4.39 3.02 6 P 0 8 0;1=2
P 4.13 3.005 6 P 0 8 0;1=2
P 3.795 3.81 6 P 0 8 0;1=0
P 4.615 3.11 6 P 0 8 0;1=2
P 4.6987 1.90248002 4 P 0 8 0;1=1
P 4.4 3.325 6 P 0 8 0;1=0
P 4.615 2.68408996 6 P 0 8 0;1=2
P 4.15 2.468 6 P 0 8 0;1=2
P 6.22 1.415 6 P 0 8 0;1=0
P 4.685 2.7 6 P 0 8 0;1=2
P 4.209 2.468 6 P 0 8 0;1=2
P 4.34436998 2.1387 4 P 0 8 0;1=1
P 6.22 1.516 6 P 0 8 0;1=0
P 4.975 2.26 6 P 0 8 0;1=2
P 4.093 2.468 6 P 0 8 0;1=2
P 6.22 1.62 6 P 0 8 0;1=0
P 4.925 2.26 6 P 0 8 0;1=0
P 4.037 2.468 6 P 0 8 0;1=2
P 6.22 1.815 6 P 0 8 0;1=0
P 5.92 1.41 6 P 0 8 0;1=0
P 5.09 2.155 6 P 0 8 0;1=2
P 3.801 2.468 6 P 0 8 0;1=2
P 4.10816004 2.09933002 4 P 0 8 0;1=1
P 5.92 1.515 6 P 0 8 0;1=0
P 5.135 2.155 6 P 0 8 0;1=2
P 3.86 2.468 6 P 0 8 0;1=2
P 4.14753002 2.09933002 4 P 0 8 0;1=1
P 5.92 1.63 6 P 0 8 0;1=0
P 5.115 2.065 6 P 0 8 0;1=2
P 3.919 2.468 6 P 0 8 0;1=2
P 5.92 1.73 6 P 0 8 0;1=0
P 5.13 2.105 6 P 0 8 0;1=2
P 3.978 2.468 6 P 0 8 0;1=2
P 4.685 2.645 6 P 0 8 0;1=2
P 4.1 3.38 6 P 0 8 0;1=0
P 4.53 2.5 6 P 0 8 0;1=2
P 3.9 3.385 6 P 0 8 0;1=0
P 4.485 3.115 6 P 0 8 0;1=0
P 4.575 2.374 6 P 0 8 0;1=2
P 4.485 2.5 6 P 0 8 0;1=2
P 4.29441998 3.10075 6 P 0 8 0;1=0
P 4.61 2.345 6 P 0 8 0;1=2
P 4.54 3.125 6 P 0 8 0;1=0
P 4.085 3.21998002 6 P 0 8 0;1=0
P 4.35 2.505 6 P 0 8 0;1=2
P 5.365 0.79 6 P 0 8 0;1=0
P 5.365 0.845 6 P 0 8 0;1=0
P 4.0661 3.5341 6 P 0 8 0;1=0
P 3.83 3.466 5 P 0 8 0;1=7
P 4.35143002 3.06643002 6 P 0 8 0;1=2
P 3.7 3.325 6 P 0 8 0;1=0
P 3.5825 3.4005 3 P 0 8 0;1=4
P 4.33 3.1432 6 P 0 8 0;1=2
P 3.83 3.235 6 P 0 8 0;1=0
P 4.085 3.165 6 P 0 8 0;1=2
P 3.415 3.335 3 P 0 8 0;1=4
P 0.74 1.3 6 P 0 8 0;1=2
P 1.26 0.62 5 P 0 8 0;1=7
P 0.785 0.8225 6 P 0 8 0;1=2
P 0.695 1.3 6 P 0 8 0;1=2
P 1.26 0.67 5 P 0 8 0;1=7
P 0.76321004 0.783 6 P 0 8 0;1=2
P 3.32 3.015 4 P 0 8 0;1=3
P 3.24 3.01 4 P 0 8 0;1=3
P 0.606 1.57 6 P 0 8 0;1=0
P 0.835 1.73 6 P 0 8 0;1=0
P 0.355 3.27 6 P 0 8 0;1=0
P 0.28 3.27 6 P 0 8 0;1=0
P 0.13 3.187 6 P 0 8 0;1=0
P 0.69023002 1.98523996 6 P 0 8 0;1=2
P 0.125 2.195 6 P 0 8 0;1=0
P 0.69 1.93 6 P 0 8 0;1=2
P 0.125 2.145 6 P 0 8 0;1=0
P 0.69 1.875 6 P 0 8 0;1=2
P 0.125 2.045 6 P 0 8 0;1=0
P 0.13 2.73326998 6 P 0 8 0;1=0
P 0.287 2.743 6 P 0 8 0;1=0
P 0.125 2.615 6 P 0 8 0;1=0
P 0.735 1.19 6 P 0 8 0;1=2
P 0.125 1.06 6 P 0 8 0;1=0
P 0.68 1.19 6 P 0 8 0;1=2
P 0.125 1.01 6 P 0 8 0;1=0
P 0.675 1.145 6 P 0 8 0;1=2
P 0.125 0.91 6 P 0 8 0;1=0
P 0.125 1.62 6 P 0 8 0;1=0
P 0.13 1.57 6 P 0 8 0;1=0
P 0.1362 1.4872 6 P 0 8 0;1=0
P 2.937 3.173 6 P 0 8 0;1=0
P 3.01 3.17 6 P 0 8 0;1=2
P 0.896 2.489 3 P 0 8 0;1=4
P 4.31168996 4.01168996 3 P 0 8 0;1=4
P 4.319 3.922 3 P 0 8 0;1=4
P 4.5 4.115 6 P 0 8 0;1=0
P 1.315 2.905 5 P 0 8 0;1=8
P 2.932 3.295 5 P 0 8 0;1=8
P 0.915 1.4 6 P 0 8 0;1=2
P 1.42 0.69535 5 P 0 8 0;1=7
P 4.5 4.165 6 P 0 8 0;1=0
P 1.36 2.905 5 P 0 8 0;1=8
P 2.896 3.301 5 P 0 8 0;1=8
P 0.965 1.4 6 P 0 8 0;1=2
P 1.4207 0.779 5 P 0 8 0;1=7
P 4.65933002 2.02058996 4 P 0 8 0;1=5
P 4.33 3.535 6 P 0 8 0;1=2
P 4.44 4.065 3 P 0 8 0;1=4
P 4.61996004 2.05996004 4 P 0 8 0;1=1
P 4.395 3.415 5 P 0 8 0;1=8
P 4.44 4.115 3 P 0 8 0;1=4
P 4.61996004 2.09933002 4 P 0 8 0;1=1
P 4.425 3.36088996 5 P 0 8 0;1=8
P 0.638 2.74 5 P 0 8 0;1=8
P 0.825 2.305 3 P 0 8 0;1=4
P 0.755 2.825 5 P 0 8 0;1=8
P 0.795 2.345 3 P 0 8 0;1=4
P 5.97613002 4.13778996 6 P 0 8 0;1=0
P 5.90748002 4.18725 6 P 0 8 0;1=0
P 4.06878996 2.02058996 4 P 0 8 0;1=1
P 0.905 1.935 6 P 0 8 0;1=0
P 3.99005 2.05996004 4 P 0 8 0;1=1
P 0.945 1.97 6 P 0 8 0;1=0
P 4.02941998 2.05996004 4 P 0 8 0;1=1
P 0.905 1.885 6 P 0 8 0;1=0
P 0.63 2.15 6 P 0 8 0;1=2
P 3.95066998 2.02058996 4 P 0 8 0;1=1
P 0.985 2.185 6 P 0 8 0;1=0
P 0.287 2.62508002 6 P 0 8 0;1=2
P 0.43 2.555 6 P 0 8 0;1=0
P 3.95066998 1.98121998 4 P 0 8 0;1=1
P 0.63 2.105 6 P 0 8 0;1=2
P 0.99 2.015 6 P 0 8 0;1=2
P 0.242 2.62508002 6 P 0 8 0;1=0
P 3.99005 1.98121998 4 P 0 8 0;1=1
P 0.63 2.06 6 P 0 8 0;1=2
P 0.99 1.975 6 P 0 8 0;1=2
P 4.02941998 1.82373996 4 P 0 8 0;1=1
P 0.935 1.3 6 P 0 8 0;1=0
P 3.95066998 1.90248002 4 P 0 8 0;1=1
P 0.87 1.255 6 P 0 8 0;1=0
P 3.95066998 1.86311004 4 P 0 8 0;1=1
P 0.935 1.25 6 P 0 8 0;1=0
P 4.06878996 1.94185 4 P 0 8 0;1=1
P 0.92 1.73 6 P 0 8 0;1=0
P 0.281 1.48798002 6 P 0 8 0;1=2
P 4.06878996 1.86311004 4 P 0 8 0;1=1
P 0.985 1.655 6 P 0 8 0;1=0
P 0.371 1.48798002 6 P 0 8 0;1=2
P 4.06878996 1.82373996 4 P 0 8 0;1=1
P 0.985 1.59 6 P 0 8 0;1=0
P 0.236 1.48798002 6 P 0 8 0;1=2
P 0.345 3.09 6 P 0 8 0;1=2
P 3.84091004 2.00091004 6 P 0 8 0;1=0
P 0.99 1.885 6 P 0 8 0;1=2
P 0.395 3.09 6 P 0 8 0;1=2
P 3.87193002 2.09933002 4 P 0 8 0;1=5
P 0.99 2.065 6 P 0 8 0;1=2
P 0.445 3.09 6 P 0 8 0;1=0
P 3.9113 2.09933002 4 P 0 8 0;1=1
P 0.975 2.14 6 P 0 8 0;1=2
P 0.53 2.005 6 P 0 8 0;1=0
P 0.552 2.535 6 P 0 8 0;1=0
P 0.455 1.825 6 P 0 8 0;1=0
P 0.16038996 1.85433002 8 P 0 8 0;1=10
P 0.46 2.195 6 P 0 8 0;1=0
P 0.16038996 2.4252 8 P 0 8 0;1=10
P 0.445 0.735 6 P 0 8 0;1=0
P 0.16038996 0.7126 8 P 0 8 0;1=10
P 0.455 1.0439 6 P 0 8 0;1=0
P 0.16038996 1.28346004 8 P 0 8 0;1=10
P 0.535 1.835 6 P 0 8 0;1=0
P 0.532 2.40186998 6 P 0 8 0;1=0
P 0.505 0.60228002 6 P 0 8 0;1=0
P 0.5374 1.26 6 P 0 8 0;1=0
P 0.48 2.005 6 P 0 8 0;1=0
P 0.485 2.525 6 P 0 8 0;1=0
P 0.515 0.835 6 P 0 8 0;1=0
P 0.475 1.405 6 P 0 8 0;1=0
P 6.335 0.965 6 P 0 8 0;1=0
P 6.335 1.02 6 P 0 8 0;1=0
P 6.335 1.08 6 P 0 8 0;1=0
P 2.085 3.017 5 P 0 8 0;1=7
P 2.135 3.017 5 P 0 8 0;1=7
P 2.185 3.017 5 P 0 8 0;1=7
P 6.0085 1.1235 6 P 0 8 0;1=0
P 2.22 3.3 5 P 0 8 0;1=7
P 5.8 1.048 4 P 0 8 0;1=3
P 4.34436998 2.02058996 4 P 0 8 0;1=1
P 5.285 2.99 5 P 0 8 0;1=8
P 3.125 3.075 6 P 0 8 0;1=2
P 4.34436998 2.17806998 4 P 0 8 0;1=1
P 2.017 3.279 4 P 0 8 0;1=3
P 0.636 2.915 4 P 0 8 0;1=3
P 4.38373996 2.17806998 4 P 0 8 0;1=1
P 2.97 3.105 6 P 0 8 0;1=0
P 5.91 2.785 6 P 0 8 0;1=0
P 5.91 2.615 5 P 0 8 0;1=7
P 5.91 2.915 6 P 0 8 0;1=0
P 5.91 2.715 6 P 0 8 0;1=0
P 0.54 2.135 6 P 0 8 0;1=2
P 0.67 1.09 6 P 0 8 0;1=0
P 4.61996004 1.66626998 4 P 0 8 0;1=1
P 0.45 2.13 6 P 0 8 0;1=2
P 4.6987 2.09933002 4 P 0 8 0;1=1
P 0.965 2.355 6 P 0 8 0;1=0
P 4.5806 1.70563996 4 P 0 8 0;1=1
P 0.735 1.125 6 P 0 8 0;1=0
P 0.48231998 2.6453 6 P 0 8 0;1=2
P 3.755 3.505 5 P 0 8 0;1=8
P 4.6987 2.1387 4 P 0 8 0;1=1
P 0.525 2.78 6 P 0 8 0;1=2
P 4.6 0.76 6 P 0 8 0;1=2
P 4.61996004 1.78436998 4 P 0 8 0;1=1
P 0.905 1.05 6 P 0 8 0;1=2
P 4.175 0.75 6 P 0 8 0;1=2
P 0.51765 0.966 3 P 0 8 0;1=4
P 2.078 0.8301 6 P 0 8 0;1=2
P 0.46 0.82 3 P 0 8 0;1=4
P 4.65933002 1.78436998 4 P 0 8 0;1=1
P 0.5413 1.525 6 P 0 8 0;1=0
P 4.61996004 1.70563996 4 P 0 8 0;1=1
P 0.625 1.005 6 P 0 8 0;1=2
P 4.65933002 1.70563996 4 P 0 8 0;1=1
P 0.935 1.105 6 P 0 8 0;1=0
P 0.4839 1.28311998 6 P 0 8 0;1=2
P 1.128 0.666 3 P 0 8 0;1=4
P 5.97613002 4.27558002 6 P 0 8 0;1=0
P 4.14753002 1.86311004 4 P 0 8 0;1=1
P 0.945 1.63 6 P 0 8 0;1=2
P 0.635 0.845 4 P 0 8 0;1=3
P 4.1869 1.86311004 4 P 0 8 0;1=1
P 0.975 1.72 6 P 0 8 0;1=2
P 0.644 0.7 4 P 0 8 0;1=3
P 0.555 0.59 6 P 0 8 0;1=0
P 3.935 3.91 5 P 0 8 0;1=7
P 0.835 1.885 6 P 0 8 0;1=2
P 3.885 3.91 5 P 0 8 0;1=7
P 0.835 1.93 6 P 0 8 0;1=2
P 3.985 3.91 5 P 0 8 0;1=7
P 0.835 1.78 6 P 0 8 0;1=2
P 0.645 1.295 4 P 0 8 0;1=3
P 4.1869 1.90248002 4 P 0 8 0;1=1
P 0.955 1.92 6 P 0 8 0;1=2
P 0.565 1.13 4 P 0 8 0;1=3
P 4.14753002 1.90248002 4 P 0 8 0;1=1
P 0.885 1.49 6 P 0 8 0;1=0
P 0.99 1.755 6 P 0 8 0;1=2
P 3.935 4 5 P 0 8 0;1=8
P 0.332 2.62508002 6 P 0 8 0;1=0
P 3.885 4 5 P 0 8 0;1=8
P 0.405 2.62 6 P 0 8 0;1=0
P 3.985 4 5 P 0 8 0;1=8
P 0.19 2.625 6 P 0 8 0;1=0
P 0.62 1.995 4 P 0 8 0;1=3
P 4.34436998 1.82373996 4 P 0 8 0;1=1
P 0.75 1.417 6 P 0 8 0;1=2
P 4.26563996 1.82373996 4 P 0 8 0;1=1
P 0.952 1.51 6 P 0 8 0;1=0
P 0.545 1.71 4 P 0 8 0;1=3
P 0.415 1.275 6 P 0 8 0;1=2
P 0.87 1.2 6 P 0 8 0;1=2
P 0.7558 4.19003996 5 P 0 8 0;1=7
P 3.98 4.185 5 P 0 8 0;1=8
P 0.465 1.33 6 P 0 8 0;1=2
P 0.87 1.3 6 P 0 8 0;1=2
P 0.705 4.19 5 P 0 8 0;1=7
P 4.03 4.185 5 P 0 8 0;1=8
P 0.41408996 1.32591004 6 P 0 8 0;1=2
P 0.89 1.105 6 P 0 8 0;1=2
P 0.805 4.205 6 P 0 8 0;1=0
P 3.93 4.185 5 P 0 8 0;1=8
P 0.647 2.517 4 P 0 8 0;1=3
P 4.22626998 1.82373996 4 P 0 8 0;1=1
P 0.939 1.552 6 P 0 8 0;1=2
P 0.575 2.265 4 P 0 8 0;1=3
P 4.22626998 1.86311004 4 P 0 8 0;1=1
P 0.957 2.275 6 P 0 8 0;1=0
P 4.168 4.24 5 P 0 8 0;1=8
P 0.855 4.205 5 P 0 8 0;1=8
P 0.15 2.79 6 P 0 8 0;1=0
P 0.326 1.487 6 P 0 8 0;1=2
P 0.09 2.86 6 P 0 8 0;1=0
P 0.9 4.205 5 P 0 8 0;1=8
P 4.22336998 4.24 5 P 0 8 0;1=8
P 0.416 1.48798002 6 P 0 8 0;1=2
P 0.09 2.79 6 P 0 8 0;1=0
P 0.98 4.2 5 P 0 8 0;1=8
P 4.14 4.19 5 P 0 8 0;1=8
P 0.191 1.48798002 6 P 0 8 0;1=2
P 4.10463002 3.83 5 P 0 8 0;1=7
P 0.33 3.145 6 P 0 8 0;1=2
P 4.05463002 3.83 5 P 0 8 0;1=7
P 0.43 3.145 6 P 0 8 0;1=2
P 4.15463002 3.83 5 P 0 8 0;1=7
P 0.18 3.145 6 P 0 8 0;1=2
P 0.869 2.672 6 P 0 8 0;1=2
P 0.871 2.713 3 P 0 8 0;1=4
P 0.686 2.74 5 P 0 8 0;1=8
P 0.64248002 2.58 6 P 0 8 0;1=2
P 0.736 2.525 5 P 0 8 0;1=8
P 0.714 2.329 6 P 0 8 0;1=2
P 3.429 2.468 3 P 0 8 0;1=4
P 3.51 2.33243002 6 P 0 8 0;1=2
P 3.278 2.468 3 P 0 8 0;1=4
P 3.243 2.547 3 P 0 8 0;1=4
P 3.385 2.135 4 P 0 8 0;1=3
P 3.24 2.36 3 P 0 8 0;1=4
P 3.285 2.38645 3 P 0 8 0;1=4
P 0.832 2.603 6 P 0 8 0;1=0
P 0.77963996 2.601 3 P 0 8 0;1=4
P 0.695 2.578 6 P 0 8 0;1=0
P 0.72 2.714 3 P 0 8 0;1=4
P 0.825 2.732 3 P 0 8 0;1=4
P 6.01953002 2.18853002 6 P 0 8 0;1=0
P 4.415 2.975 3 P 0 8 0;1=4
P 6.09423996 4.27558002 6 P 0 8 0;1=0
P 0.959 2.789 6 P 0 8 0;1=2
P 0.845 2.18 6 P 0 8 0;1=0
P 5.955 2.39 4 P 0 8 0;1=3
P 5.94153002 2.205 5 P 0 8 0;1=7
P 6.01901998 2.001 5 P 0 8 0;1=7
P 5.87 1.84 4 P 0 8 0;1=3
P 3.4593 2.17 5 P 0 8 0;1=7
P 3.44 2.12 6 P 0 8 0;1=0
P 4.34436998 1.94185 4 P 0 8 0;1=1
P 3.18 2.685 3 P 0 8 0;1=4
P 3.523 1.75 5 P 0 8 0;1=8
P 4.712 1.157 4 P 0 8 0;1=3
P 4.42311004 1.50878996 4 P 0 8 0;1=1
P 4.61996004 1.6269 4 P 0 8 0;1=3
P 4.29 1.235 4 P 0 8 0;1=3
P 4.38373996 1.46941998 4 P 0 8 0;1=1
P 4.15 1.235 4 P 0 8 0;1=3
P 4.34436998 1.50878996 4 P 0 8 0;1=1
P 5.035 1.49 4 P 0 8 0;1=3
P 4.65933002 1.58753002 4 P 0 8 0;1=1
P 4.185 1.17 4 P 0 8 0;1=3
P 4.34436998 1.46941998 4 P 0 8 0;1=1
P 4.816 1.258 4 P 0 8 0;1=3
P 4.665 1.104 4 P 0 8 0;1=3
P 4.38373996 1.3513 4 P 0 8 0;1=1
P 4.91 1.54 4 P 0 8 0;1=3
P 4.768 1.207 4 P 0 8 0;1=3
P 4.42311004 1.46941998 4 P 0 8 0;1=1
P 5.03 1.55 4 P 0 8 0;1=3
P 4.58058996 1.6269 4 P 0 8 0;1=1
P 4.828 1.103 4 P 0 8 0;1=3
P 4.42311004 1.43005 4 P 0 8 0;1=1
P 4.83 1.33 4 P 0 8 0;1=3
P 4.22 1.235 4 P 0 8 0;1=3
P 3.83128002 1.78371998 5 P 0 8 0;1=8
P 6.02558996 4.175 6 P 0 8 0;1=0
P 6.1437 4.175 6 P 0 8 0;1=0
P 3.87193002 1.86311004 4 P 0 8 0;1=1
P 4.14753002 2.05996004 4 P 0 8 0;1=1
P 5.83 2.97 6 P 0 8 0;1=2
P 5.89953002 2.366 5 P 0 8 0;1=7
P 3.61123996 3.49876004 3 P 0 8 0;1=4
P 4.54121998 1.94185 4 P 0 8 0;1=1
P 4.22626998 1.94185 4 P 0 8 0;1=1
P 1.96496998 0.76501998 5 P 0 8 0;1=7
P 4.1869 1.98121998 4 P 0 8 0;1=1
P 3.12 2.565 6 P 0 8 0;1=2
P 3.119 2.299 6 P 0 8 0;1=0
P 4.26563996 1.90248002 4 P 0 8 0;1=1
P 3.385 2.59 6 P 0 8 0;1=0
P 5.155 2.01 6 P 0 8 0;1=2
P 6.025 1.83 6 P 0 8 0;1=0
P 4.1869 2.05996004 4 P 0 8 0;1=1
P 4.34436998 1.90248002 4 P 0 8 0;1=1
P 2.554 2.901 6 P 0 8 0;1=0
P 4.75 1.63 4 P 0 8 0;1=5
P 3.205 1.7 6 P 0 8 0;1=0
P 4.775 1.705 6 P 0 8 0;1=2
P 4.84 1.855 6 P 0 8 0;1=0
P 4.58058996 1.82373996 4 P 0 8 0;1=1
P 4.65933002 1.86311004 4 P 0 8 0;1=1
P 4.815 1.93 6 P 0 8 0;1=0
P 4.885 3.46 6 P 0 8 0;1=2
P 4.61996004 1.86311004 4 P 0 8 0;1=1
P 4.83501004 3.46 6 P 0 8 0;1=0
P 3.125 2.254 6 P 0 8 0;1=2
P 4.26563996 1.86311004 4 P 0 8 0;1=5
P 3.12 2.69 6 P 0 8 0;1=2
P 4.565 3.055 6 P 0 8 0;1=2
P 4.3 3.81 6 P 0 8 0;1=0
P 1.3825 3.7225 5 P 0 8 0;1=8
P 5.905 3.015 5 P 0 8 0;1=7
P 5.41 0.96 4 P 0 8 0;1=3
P 4.85033002 1.74933996 6 P 0 8 0;1=2
P 4.54121998 1.78436998 4 P 0 8 0;1=1
P 5.26 2.955 6 P 0 8 0;1=2
P 3.625 0.92 4 P 0 8 0;1=9
P 6.19961004 2.27673996 4 P 0 8 0;1=9
P 3.657 0.92 4 P 0 8 0;1=9
P 6.19961004 2.24473996 4 P 0 8 0;1=9
P 3.3255 2.1355 6 P 0 8 0;1=0
P 3.35153002 2.17875 6 P 0 8 0;1=2
P 3.44 2.95 3 P 0 8 0;1=4
P 3.27923002 2.21576998 6 P 0 8 0;1=2
P 3.3435 2.82 3 P 0 8 0;1=4
P 4.46 2.94 6 P 0 8 0;1=0
P 4.47 2.83 6 P 0 8 0;1=0
P 5.995 1.165 6 P 0 8 0;1=2
P 3.106 3.26 6 P 0 8 0;1=2
P 3.222 3.385 5 P 0 8 0;1=8
P 3.106 3.35 5 P 0 8 0;1=8
P 1.959 3.325 6 P 0 8 0;1=2
P 3.222 3.205 5 P 0 8 0;1=8
P 3.49 2.955 6 P 0 8 0;1=2
P 3.98 3.365 6 P 0 8 0;1=2
P 3.7 3.37 6 P 0 8 0;1=2
P 3.55 3.37 6 P 0 8 0;1=2
P 4.175 3.37 6 P 0 8 0;1=2
P 3.71 3.26 6 P 0 8 0;1=2
P 3.55 3.28 5 P 0 8 0;1=8
P 3.414 3.235 6 P 0 8 0;1=2
P 3.41 3.04 6 P 0 8 0;1=2
P 3.548 2.856 5 P 0 8 0;1=8
P 3.5768 2.7178 6 P 0 8 0;1=2
P 3.395 2.82 6 P 0 8 0;1=2
P 3.58 2.615 4 P 0 8 0;1=3
P 3.485 2.6 6 P 0 8 0;1=2
P 3.525 2.6 6 P 0 8 0;1=2
P 3.335 2.589 6 P 0 8 0;1=2
P 3.24 2.2075 6 P 0 8 0;1=2
P 4.905 2.1675 6 P 0 8 0;1=2
P 4.85 2.02738996 6 P 0 8 0;1=2
P 4.965 1.975 6 P 0 8 0;1=2
P 3.49128002 1.86628002 6 P 0 8 0;1=2
P 4.65933002 1.66626998 4 P 0 8 0;1=1
P 3.795 2.375 6 P 0 8 0;1=2
P 3.99005 2.02058996 4 P 0 8 0;1=1
P 4.34436998 1.86311004 4 P 0 8 0;1=1
P 4.02941998 1.90248002 4 P 0 8 0;1=1
P 3.855 1.96153996 4 P 0 8 0;1=1
P 3.9113 1.86311004 4 P 0 8 0;1=1
P 4.06878996 1.78436998 4 P 0 8 0;1=1
P 4.1869 1.82373996 4 P 0 8 0;1=1
P 3.86 2.5925 6 P 0 8 0;1=2
P 3.758 2.552 6 P 0 8 0;1=2
P 4.209 2.59 6 P 0 8 0;1=2
P 4.65933002 2.09933002 4 P 0 8 0;1=1
P 4.54121998 2.05996004 4 P 0 8 0;1=1
P 4.50185 2.17806998 4 P 0 8 0;1=1
P 4.46248002 1.90248002 4 P 0 8 0;1=1
P 4.42311004 2.02058996 4 P 0 8 0;1=1
P 4.38373996 2.1387 4 P 0 8 0;1=1
P 4.26563996 1.98121998 4 P 0 8 0;1=1
P 4.22626998 2.09933002 4 P 0 8 0;1=1
P 4.14753002 1.94185 4 P 0 8 0;1=1
P 4.10816004 2.05996004 4 P 0 8 0;1=1
P 4.06878996 2.17806998 4 P 0 8 0;1=1
P 3.95066998 2.1387 4 P 0 8 0;1=1
P 4.6987 1.98121998 4 P 0 8 0;1=1
P 4.58058996 1.94185 4 P 0 8 0;1=1
P 4.73806998 1.86311004 4 P 0 8 0;1=1
P 4.61996004 1.82373996 4 P 0 8 0;1=1
P 4.50185 1.78436998 4 P 0 8 0;1=1
P 4.249 2.929 6 P 0 8 0;1=0
P 4.239 2.785 6 P 0 8 0;1=0
P 4.249 2.843 6 P 0 8 0;1=0
P 4.575 2.5 6 P 0 8 0;1=2
P 4.395 2.5 6 P 0 8 0;1=2
P 4.77 2.39 6 P 0 8 0;1=2
P 4.71 2.39 6 P 0 8 0;1=2
P 4.075 2.25 6 P 0 8 0;1=2
P 3.735 2.47 6 P 0 8 0;1=2
P 5.0395 1.335 6 P 0 8 0;1=2
P 4.97 1.75 6 P 0 8 0;1=0
P 4.96 1.63 6 P 0 8 0;1=2
P 6.22 1.27063002 6 P 0 8 0;1=2
P 3.839 3.846 6 P 0 8 0;1=2
P 4.384 3.824 6 P 0 8 0;1=2
P 4.95 3.46 6 P 0 8 0;1=2
P 5.94003002 1.87 6 P 0 8 0;1=2
P 6.379 1.169 6 P 0 8 0;1=2
P 6.105 1.905 6 P 0 8 0;1=2
P 5.92 1.27063002 6 P 0 8 0;1=2
P 5.88 0.965 6 P 0 8 0;1=2
P 6.47 1.08 6 P 0 8 0;1=2
P 5.19 3.075 6 P 0 8 0;1=2
P 5.375 3.04 6 P 0 8 0;1=2
P 5.41 2.815 6 P 0 8 0;1=2
P 5.544 2.675 6 P 0 8 0;1=2
P 6.1865 2.493 6 P 0 8 0;1=2
P 6.141 2.364 6 P 0 8 0;1=2
P 5.85 2.265 6 P 0 8 0;1=2
P 5.62 2.5487 6 P 0 8 0;1=2
P 5.42 2.9645 6 P 0 8 0;1=2
P 4.645 2.985 6 P 0 8 0;1=2
P 4.61 3.025 6 P 0 8 0;1=2
P 4.43 3.865 5 P 0 8 0;1=8
P 5.221 4.165 6 P 0 8 0;1=2
P 4.32 3.965 5 P 0 8 0;1=8
P 4.535 3.815 6 P 0 8 0;1=2
P 4.509 3.309 6 P 0 8 0;1=2
P 4.235 4.155 6 P 0 8 0;1=2
P 4.505 3.685 6 P 0 8 0;1=2
P 5.975 4.219 6 P 0 8 0;1=2
P 5.84 4.219 6 P 0 8 0;1=2
P 6.145 3.98 6 P 0 8 0;1=2
P 4.655 0.785 6 P 0 8 0;1=2
P 4.635 0.92 6 P 0 8 0;1=2
P 5.249 0.99 6 P 0 8 0;1=2
P 5.53 1.085 6 P 0 8 0;1=2
P 5.33 0.82 6 P 0 8 0;1=2
P 5.265 0.675 6 P 0 8 0;1=2
P 2.964 0.702 6 P 0 8 0;1=2
P 5.515 0.59596998 6 P 0 8 0;1=2
P 2.0477 0.6778 6 P 0 8 0;1=2
P 2.285 0.79 6 P 0 8 0;1=2
P 2.285 0.755 6 P 0 8 0;1=2
P 3.09 1.645 6 P 0 8 0;1=2
P 1.605 0.715 6 P 0 8 0;1=2
P 1.605 0.755 6 P 0 8 0;1=2
P 1.826 2.895 6 P 0 8 0;1=2
P 1.401 3.069 6 P 0 8 0;1=2
P 3.119 2.434 6 P 0 8 0;1=2
P 2.245 3.02 5 P 0 8 0;1=8
P 2.49 2.903 6 P 0 8 0;1=2
P 2.128 2.895 5 P 0 8 0;1=8
P 0.11976004 3.23523996 6 P 0 8 0;1=2
P 0.78 2.915 6 P 0 8 0;1=2
P 0.241 3.109 6 P 0 8 0;1=2
P 0.16 2.975 6 P 0 8 0;1=2
P 0.374 2.829 6 P 0 8 0;1=2
P 0.5459 2.6687 6 P 0 8 0;1=2
P 0.674 2.271 6 P 0 8 0;1=2
P 0.857 2.365 6 P 0 8 0;1=2
P 0.677 2.402 6 P 0 8 0;1=2
P 0.11963002 2.66436998 6 P 0 8 0;1=2
P 0.51451998 2.199 6 P 0 8 0;1=2
P 0.58 2.135 6 P 0 8 0;1=2
P 0.125 2.095 6 P 0 8 0;1=2
P 0.64445 1.68945 6 P 0 8 0;1=2
P 0.884 1.549 6 P 0 8 0;1=2
P 0.883 1.639 5 P 0 8 0;1=8
P 0.514 1.616 6 P 0 8 0;1=2
P 0.605 1.52 6 P 0 8 0;1=2
P 0.11263996 1.52263996 6 P 0 8 0;1=2
P 0.625 1.17 6 P 0 8 0;1=2
P 0.59 0.965 6 P 0 8 0;1=0
P 0.505 1.048 6 P 0 8 0;1=2
P 0.125 0.96 6 P 0 8 0;1=2
P 0.821 0.793 6 P 0 8 0;1=2
P 0.764 0.872 6 P 0 8 0;1=2
P 1.25 0.765 6 P 0 8 0;1=2
P 1.1133 0.5981 6 P 0 8 0;1=2
P 0.86 0.631 6 P 0 8 0;1=2
P 0.601 0.73 6 P 0 8 0;1=2
P 0.596 0.602 6 P 0 8 0;1=2
P 1.5327 0.584 6 P 0 8 0;1=2
P 4.6987 1.54816004 4 P 0 8 0;1=1
P 4.58058996 1.50878996 4 P 0 8 0;1=1
P 4.14753002 1.50878996 4 P 0 8 0;1=1
P 4.73806998 1.43005 4 P 0 8 0;1=1
P 4.61996004 1.39066998 4 P 0 8 0;1=1
P 4.50185 1.3513 4 P 0 8 0;1=1
P 4.46248002 1.46941998 4 P 0 8 0;1=1
P 4.38373996 1.31193002 4 P 0 8 0;1=1
P 4.34436998 1.43005 4 P 0 8 0;1=1
P 4.1869 1.39066998 4 P 0 8 0;1=1
P 4.06878996 1.3513 4 P 0 8 0;1=1
P 3.95066998 1.31193002 4 P 0 8 0;1=1
P 5.039 1.2869 6 P 0 8 0;1=2
P 5.0386 1.2415 6 P 0 8 0;1=2
P 4.625 1.17 6 P 0 8 0;1=2
P 4.485 1.005 6 P 0 8 0;1=2
P 3.69171998 1.02828002 6 P 0 8 0;1=2
P 3.6931 1.095 6 P 0 8 0;1=2
P 6.04 3.98 6 P 0 8 0;1=2
P 5.445 0.795 4 P 0 8 0;1=3
P 5.494 0.816 6 P 0 8 0;1=2
P 5.443 0.871 6 P 0 8 0;1=2
P 5.49 0.78223002 6 P 0 8 0;1=2
P 3.795 4.175 6 P 0 8 0;1=2
P 3.66 3.5085 6 P 0 8 0;1=2
P 3.105 3.21 6 P 0 8 0;1=2
P 5.55 4.02 6 P 0 8 0;1=2
P 5.01 2.635 6 P 0 8 0;1=0
P 5 2.78798996 5 P 0 8 0;1=7
P 5.226 2.762 5 P 0 8 0;1=7
P 3.775 2.235 6 P 0 8 0;1=2
P 3.775 2.265 6 P 0 8 0;1=0
P 3.775 2.21 6 P 0 8 0;1=2
P 3.775 2.185 6 P 0 8 0;1=2
P 4.42311004 1.78436998 4 P 0 8 0;1=1
P 4.46248002 1.70563996 4 P 0 8 0;1=1
P 4.34436998 1.78436998 4 P 0 8 0;1=1
P 4.22626998 1.78436998 4 P 0 8 0;1=1
P 4.22626998 1.66626998 4 P 0 8 0;1=1
P 4.14753002 1.78436998 4 P 0 8 0;1=1
P 4.02941998 1.78436998 4 P 0 8 0;1=1
P 5.765 0.98 4 P 0 8 0;1=3
P 1.385 3.875 5 P 0 8 0;1=7
P 5.31 2.855 6 P 0 8 0;1=2
P 4.608 2.942 6 P 0 8 0;1=2
P 4.25 3.81 6 P 0 8 0;1=2
P 0.99 2.60025 6 P 0 8 0;1=2
P 0.985 2.56661004 6 P 0 8 0;1=2
P 3.555 2.23 6 P 0 8 0;1=2
P 3.555 2.255 6 P 0 8 0;1=2
P 3.555 2.205 6 P 0 8 0;1=2
P 3.555 2.18 6 P 0 8 0;1=2
P 5.345 2.536 4 P 0 8 0;1=3
P 5.22 2.47 6 P 0 8 0;1=2
P 5.254 2.47 6 P 0 8 0;1=2
P 5.239 2.571 6 P 0 8 0;1=2
P 5.243 2.617 6 P 0 8 0;1=2
P 5.224 2.707 5 P 0 8 0;1=7
P 5.005 2.711 5 P 0 8 0;1=7
P 3.793 3.05 3 P 0 8 0;1=4
P 3.96981004 3.04481998 6 P 0 8 0;1=0
P 3.948 2.813 6 P 0 8 0;1=0
P 4.831 2.728 4 P 0 8 0;1=3
P 3.55 1.415 6 P 0 8 0;1=2
P 3.525 1.415 6 P 0 8 0;1=2
P 3.5 1.415 6 P 0 8 0;1=2
P 3.475 1.415 6 P 0 8 0;1=2
P 3.655 2.795 4 P 0 8 0;1=3
P 3.745 2.76 6 P 0 8 0;1=2
P 3.7 2.76 6 P 0 8 0;1=2
P 3.822 2.81 6 P 0 8 0;1=2
P 3.78 2.81 6 P 0 8 0;1=2
P 3.894 2.811 6 P 0 8 0;1=0
P 3.916 3.048 3 P 0 8 0;1=4
P 5.589 2.025 6 P 0 8 0;1=0
P 5.546 2.024 6 P 0 8 0;1=2
P 5.69943002 2.233 6 P 0 8 0;1=0
P 5.48158002 2.28033002 5 P 0 8 0;1=7
P 4.50185 1.66626998 4 P 0 8 0;1=1
P 4.42311004 1.66626998 4 P 0 8 0;1=1
P 4.38373996 1.70563996 4 P 0 8 0;1=1
P 4.26563996 1.70563996 4 P 0 8 0;1=1
P 4.14753002 1.66626998 4 P 0 8 0;1=1
P 4.1869 1.70563996 4 P 0 8 0;1=1
P 4.50185 1.58753002 4 P 0 8 0;1=1
P 4.46248002 1.6269 4 P 0 8 0;1=1
P 4.46248002 1.54816004 4 P 0 8 0;1=1
P 4.38373996 1.54816004 4 P 0 8 0;1=1
P 4.42311004 1.58753002 4 P 0 8 0;1=1
P 4.34436998 1.58753002 4 P 0 8 0;1=1
P 4.26563996 1.54816004 4 P 0 8 0;1=1
P 4.22626998 1.58753002 4 P 0 8 0;1=1
P 4.14753002 1.58753002 4 P 0 8 0;1=1
P 4.1869 1.6269 4 P 0 8 0;1=1
P 4.1869 1.54816004 4 P 0 8 0;1=1
P 5.145 1.57 6 P 0 8 0;1=2
P 5.145 1.54 6 P 0 8 0;1=2
P 5.145 1.44 6 P 0 8 0;1=0
P 5.145 1.48 6 P 0 8 0;1=2
P 5.145 1.51 6 P 0 8 0;1=2
P 5.76 2.465 4 P 0 8 0;1=3
P 4.2136 3.5997 3 P 0 8 0;1=4
P 3.755 3.092 6 P 0 8 0;1=2
P 3.99005 1.66626998 4 P 0 8 0;1=1
P 4.06878996 1.54816004 4 P 0 8 0;1=1
P 4.06878996 1.6269 4 P 0 8 0;1=1
P 4.02941998 1.58753002 4 P 0 8 0;1=1
P 3.99005 1.50878996 4 P 0 8 0;1=1
P 3.679 1.54228002 6 P 0 8 0;1=2
P 3.714 1.543 6 P 0 8 0;1=2
P 3.784 1.543 6 P 0 8 0;1=2
P 3.749 1.54228002 6 P 0 8 0;1=2
P 3.605 1.545 6 P 0 8 0;1=2
P 3.50085 1.543 6 P 0 8 0;1=2
P 3.53481998 1.54156998 6 P 0 8 0;1=2
P 3.57 1.542 6 P 0 8 0;1=2
P 5.4227 1.724 6 P 0 8 0;1=2
P 5.3977 1.724 6 P 0 8 0;1=2
P 5.58 1.615 4 P 0 8 0;1=3
P 5.3977 1.699 6 P 0 8 0;1=2
P 5.3977 1.749 6 P 0 8 0;1=2
P 5.4227 1.699 6 P 0 8 0;1=2
P 5.4352 1.7497 6 P 0 8 0;1=2
P 5.654 2.447 6 P 0 8 0;1=2
P 5.667 2.275 5 P 0 8 0;1=7
P 5.595 2.28 5 P 0 8 0;1=7
P 5.483 2.226 6 P 0 8 0;1=0
P 5.6695 2.2 6 P 0 8 0;1=2
P 5.771 2.279 5 P 0 8 0;1=7
P 5.789 2.366 6 P 0 8 0;1=2
P 5.6 2.4 6 P 0 8 0;1=2
P 5.6 4.01 4 P 0 8 0;1=3
P 5.55568996 3.88051004 3 P 0 8 0;1=4
P 5.765 2.197 6 P 0 8 0;1=0
P 5.71 2.179 6 P 0 8 0;1=2
P 5.41 2.164 6 P 0 8 0;1=0
P 5.458 2.165 6 P 0 8 0;1=2
P 5.465 2.405 6 P 0 8 0;1=2
P 5.53121998 2.27978996 5 P 0 8 0;1=7
P 3.817 0.924 5 P 0 8 0;1=7
P 4.25 0.877 6 P 0 8 0;1=0
P 5.495 0.694 5 P 0 8 0;1=7
P 5.49 0.635 6 P 0 8 0;1=0
P 5.725 0.60301004 5 P 0 8 0;1=7
P 5.686 0.76 5 P 0 8 0;1=7
P 5.7287 0.6757 5 P 0 8 0;1=7
P 5.38558002 4.13778996 6 P 0 8 0;1=0
P 5.485 4.11 6 P 0 8 0;1=0
P 5.725 4.135 6 P 0 8 0;1=0
P 5.6218 4.13778996 6 P 0 8 0;1=0
P 5.323 4.257 5 P 0 8 0;1=7
P 3.83 3.335 3 P 0 8 0;1=4
P 3.415 3.285 3 P 0 8 0;1=4
P 3.83 3.285 3 P 0 8 0;1=4
P 3.415 3.385 3 P 0 8 0;1=4
P 4.83871004 1.98241004 6 P 0 8 0;1=0
P 4.80288002 2.03788002 6 P 0 8 0;1=0
P 4.97 3.41 6 P 0 8 0;1=0
P 4.38373996 1.90248002 4 P 0 8 0;1=1
P 4.81 3.41 6 P 0 8 0;1=2
P 4.42311004 2.09933002 4 P 0 8 0;1=5
P 3.48863002 4.105 6 P 0 8 0;1=0
P 2.987 3.235 5 P 0 8 0;1=8
P 0.7595 1.642 5 P 0 8 0;1=7
P 2.987 3.27 5 P 0 8 0;1=8
P 0.761 1.544 5 P 0 8 0;1=7
P 4.54121998 1.82373996 4 P 0 8 0;1=1
P 4.79246004 1.78463996 6 P 0 8 0;1=0
P 4.54121998 2.17806998 4 P 0 8 0;1=5
P 0.955 1.455 6 P 0 8 0;1=0
P 1.512 0.75191004 6 P 0 8 0;1=2
P 1.8091 0.6339 5 P 0 8 0;1=7
P 1.459 0.752 5 P 0 8 0;1=8
P 0.905 1.445 6 P 0 8 0;1=2
P 2.40508002 0.731 5 P 0 8 0;1=8
P 4.06878996 1.66626998 3 P 0 8 0;1=11
P 2.40508002 0.699 5 P 0 8 0;1=8
P 4.02941998 1.66626998 3 P 0 8 0;1=11
P 4.4085 1.16598996 5 P 0 8 0;1=8
P 4.46248002 1.43005 3 P 0 8 0;1=11
P 4.3765 1.16598996 5 P 0 8 0;1=8
P 4.50185 1.43005 3 P 0 8 0;1=11
P 4.0485 1.16098996 5 P 0 8 0;1=8
P 4.06878996 1.50878996 3 P 0 8 0;1=11
P 4.0165 1.16098996 5 P 0 8 0;1=8
P 4.02941998 1.50878996 3 P 0 8 0;1=11
P 4.82 2.125 4 P 0 8 0;1=3
P 4.38373996 1.78436998 4 P 0 8 0;1=1
P 3.54663996 1.04706998 5 P 0 8 0;1=8
P 4.6987 1.46941998 3 P 0 8 0;1=11
P 3.51463996 1.04706998 5 P 0 8 0;1=8
P 4.73806998 1.46941998 3 P 0 8 0;1=11
P 3.44998996 1.085 5 P 0 8 0;1=8
P 4.73806998 1.39066998 3 P 0 8 0;1=11
P 3.41798996 1.085 5 P 0 8 0;1=8
P 4.73806998 1.3513 3 P 0 8 0;1=11
P 3.445 1.815 6 P 0 8 0;1=2
P 4.58058996 1.90248002 4 P 0 8 0;1=1
P 4.65933002 1.94185 4 P 0 8 0;1=1
P 4.785 3.46 6 P 0 8 0;1=0
P 3.9113 1.70563996 4 P 0 8 0;1=1
P 3.674 1.744 6 P 0 8 0;1=2
P 3.95066998 1.58753002 4 P 0 8 0;1=1
P 3.9113 1.54816004 4 P 0 8 0;1=1
P 3.9113 1.6269 4 P 0 8 0;1=1
P 3.95066998 1.43005 4 P 0 8 0;1=1
P 3.9113 1.46941998 4 P 0 8 0;1=1
P 3.82 1.42 6 P 0 8 0;1=0
P 3.79 1.41 6 P 0 8 0;1=2
P 3.74 1.41 6 P 0 8 0;1=2
P 3.765 1.41 6 P 0 8 0;1=2
P 4.54121998 1.6269 4 P 0 8 0;1=1
P 4.9097 1.385 5 P 0 8 0;1=7
P 4.54121998 1.66626998 4 P 0 8 0;1=1
P 4.84 1.66 6 P 0 8 0;1=0
P 4.81 1.725 6 P 0 8 0;1=0
P 3.375 1.194 5 P 0 8 0;1=8
P 4.5413 1.22166998 5 P 0 8 0;1=8
P 4.61996004 1.31193002 3 P 0 8 0;1=11
P 3.375 1.162 5 P 0 8 0;1=8
P 4.5733 1.22166998 5 P 0 8 0;1=8
P 4.65933002 1.31193002 3 P 0 8 0;1=11
P 5.3 4.065 4 P 0 8 0;1=3
P 4.10816004 1.70563996 4 P 0 8 0;1=1
P 4.365 2.33 6 P 0 8 0;1=2
P 4.38373996 2.02058996 4 P 0 8 0;1=5
P 4.38373996 2.05996004 4 P 0 8 0;1=1
P 4.485 2.375 6 P 0 8 0;1=0
P 4.38373996 2.09933002 4 P 0 8 0;1=1
P 4.54121998 1.58753002 4 P 0 8 0;1=1
P 4.9097 1.335 5 P 0 8 0;1=7
P 4.26563996 1.78436998 4 P 0 8 0;1=1
P 4.365 2.375 6 P 0 8 0;1=0
P 3.465 1.74 6 P 0 8 0;1=2
P 3.44 1.03 6 P 0 8 0;1=0
P 6.285 1.895 6 P 0 8 0;1=2
P 6.258 2.15873996 5 P 0 8 0;1=8
P 6.275 2.05373996 6 P 0 8 0;1=2
P 6.335 2.05906004 5 P 0 8 0;1=7
P 1.77 3.98 6 P 0 8 0;1=0
P 1.75 3.945 6 P 0 8 0;1=2
P 1.5315 3.9459 5 P 0 8 0;1=7
P 1.517 4.113 6 P 0 8 0;1=0
P 1.511 3.863 5 P 0 8 0;1=7
P 1.5153 4.063 5 P 0 8 0;1=7
P 1.521 3.993 5 P 0 8 0;1=7
P 1.579 3.874 6 P 0 8 0;1=0
P 1.585 4.052 6 P 0 8 0;1=2
P 1.435 4.18 6 P 0 8 0;1=2
P 1.522 4.163 5 P 0 8 0;1=7
P 1.4 4.01 6 P 0 8 0;1=2
P 5.14 3.74 6 P 0 8 0;1=2
P 5.175 3.74 6 P 0 8 0;1=2
P 5.18 3.825 6 P 0 8 0;1=2
P 5.675 4.03 6 P 0 8 0;1=2
P 1.56 3.29 6 P 0 8 0;1=2
P 1.56 3.25 6 P 0 8 0;1=2
P 3.245 2.955 6 P 0 8 0;1=2
P 3.21 2.955 6 P 0 8 0;1=2
P 3.175 2.955 6 P 0 8 0;1=2
P 2.59 3.445 6 P 0 8 0;1=2
P 2.55 3.445 6 P 0 8 0;1=2
P 2.51 3.445 6 P 0 8 0;1=2
P 2.47 3.445 6 P 0 8 0;1=2
P 2.2 3.96 6 P 0 8 0;1=2
P 2.25 3.96 4 P 0 8 0;1=3
P 1.351 4.126 6 P 0 8 0;1=2
P 2.165 3.96 6 P 0 8 0;1=2
P 2.155 3.925 6 P 0 8 0;1=2
P 2.19 3.925 6 P 0 8 0;1=2
P 3.23 4.015 6 P 0 8 0;1=0
P 3.2 3.985 6 P 0 8 0;1=2
P 5.9065 2.4568 6 P 0 8 0;1=2
P 3.745 4.185 4 P 0 8 0;1=3
P 3.47 3.912 6 P 0 8 0;1=0
P 3.69 4.135 4 P 0 8 0;1=3
P 3.48278996 4.05678002 6 P 0 8 0;1=2
P 3.476 3.988 6 P 0 8 0;1=0
P 3.437 4.099 6 P 0 8 0;1=0
P 3.598 3.977 6 P 0 8 0;1=2
P 3.477 3.816 6 P 0 8 0;1=0
P 3.405 3.916 6 P 0 8 0;1=2
P 5.68326004 3.712 6 P 0 8 0;1=0
P 5.686 3.807 6 P 0 8 0;1=0
P 5.50643002 4.009 3 P 0 8 0;1=4
P 5.686 3.76 6 P 0 8 0;1=0
P 5.675 3.865 6 P 0 8 0;1=0
P 5.718 3.965 4 P 0 8 0;1=3
P 6.05315 3.67518996 9 P 0 8 0;1=12
P 6.05315 3.50983996 9 P 0 8 0;1=13
P 6.05315 3.34448996 9 P 0 8 0;1=13
P 0.865 3.645 6 P 0 8 0;1=2
P 0.905 3.645 6 P 0 8 0;1=2
P 0.945 3.645 6 P 0 8 0;1=2
P 0.945 3.69 6 P 0 8 0;1=2
P 0.945 3.73 6 P 0 8 0;1=2
P 0.945 3.765 6 P 0 8 0;1=2
P 0.865 3.845 6 P 0 8 0;1=2
P 0.905 3.845 6 P 0 8 0;1=2
P 0.94 3.845 6 P 0 8 0;1=2
P 0.945 3.805 6 P 0 8 0;1=0
P 0.828 3.846 6 P 0 8 0;1=2
P 0.828 3.646 6 P 0 8 0;1=2
P 5.66 3.47 4 P 0 8 0;1=3
P 5.68 3.567 3 P 0 8 0;1=4
P 5.406 3.863 6 P 0 8 0;1=0
P 3.46 4.16 6 P 0 8 0;1=2
P 3.495 4.15 6 P 0 8 0;1=2
P 3.5 4.195 6 P 0 8 0;1=2
P 3.53 4.165 6 P 0 8 0;1=2
P 5.769 4.031 6 P 0 8 0;1=2
P 5.644 3.967 6 P 0 8 0;1=0
P 5.803 3.907 6 P 0 8 0;1=2
P 1.45 3.78 6 P 0 8 0;1=2
P 1.485 3.76 5 P 0 8 0;1=7
P 1.485 3.8 6 P 0 8 0;1=2
P 5.406 2.346 4 P 0 8 0;1=3
P 5.375 2.32 6 P 0 8 0;1=2
P 5.34 2.315 6 P 0 8 0;1=2
P 5.43 3.6 6 P 0 8 0;1=0
P 5.433 3.651 6 P 0 8 0;1=2
P 5.43 3.7 6 P 0 8 0;1=2
P 5.39 3.6 6 P 0 8 0;1=2
P 5.393 3.651 6 P 0 8 0;1=2
P 5.39 3.7 6 P 0 8 0;1=2
P 1.6055 4.134 6 P 0 8 0;1=2
P 1.60581998 4.1 6 P 0 8 0;1=2
P 1.606 4.174 5 P 0 8 0;1=7
P 1.636 3.786 6 P 0 8 0;1=2
P 1.591 3.826 6 P 0 8 0;1=2
P 1.633 3.829 5 P 0 8 0;1=7
P 3.408 4.152 6 P 0 8 0;1=2
P 3.363 4.192 6 P 0 8 0;1=2
P 3.363 4.152 6 P 0 8 0;1=2
P 3.363 4.232 6 P 0 8 0;1=0
P 3.393 3.877 6 P 0 8 0;1=2
P 3.393 3.84 6 P 0 8 0;1=2
P 3.392 3.803 6 P 0 8 0;1=2
P 3.607 4.062 6 P 0 8 0;1=2
P 1.352 4.084 6 P 0 8 0;1=0
P 1.95 0.5455 5 P 0 8 0;1=7
P 5.681 3.617 6 P 0 8 0;1=0
P 5.681 3.664 6 P 0 8 0;1=0
P 5.40318002 2.70436004 5 P 0 8 0;1=7
P 0.55921998 1.40543002 6 P 0 8 0;1=0
P 0.57 0.835 6 P 0 8 0;1=0
P 3.584 1.827 5 P 0 8 0;1=7
P 1.535 3.905 5 P 0 8 0;1=8
P 1.98135 0.365 5 P 0 8 0;1=8
P 1.7317 0.7084 6 P 0 8 0;1=0
P 1.91535 0.412 5 P 0 8 0;1=8
P 1.8039 0.7072 5 P 0 8 0;1=7
P 3.2271 1.90298996 4 P 0 8 0;1=9
P 3.45301004 1.89898996 4 P 0 8 0;1=9
P 3.2591 1.90298996 4 P 0 8 0;1=9
P 3.45301004 1.93098996 4 P 0 8 0;1=9
P 1.26066998 2.64043002 10 P 0 8 0;1=14
P 5.035 3.945 6 P 0 8 0;1=0
P 5.075 3.945 6 P 0 8 0;1=2
P 2.97771998 1.88693996 6 P 0 8 0;1=2
P 3.00995 1.87611004 6 P 0 8 0;1=2
P 2.86066998 2.64043002 10 P 0 8 0;1=14
P 2.105 0.305 5 P 0 8 0;1=8
P 2.235 0.5825 6 P 0 8 0;1=2
P 3.405 0.635 6 P 0 8 0;1=2
P 5.295 0.605 6 P 0 8 0;1=0
P 5.91 4.04 6 P 0 8 0;1=0
P 2.135 0.54 6 P 0 8 0;1=2
P 5.215 0.6 6 P 0 8 0;1=0
P 6.025 4.04 6 P 0 8 0;1=0
P 3.36 0.6106 6 P 0 8 0;1=2
P 0.96 2.41 6 P 0 8 0;1=2
P 0.68 2.355 6 P 0 8 0;1=2
P 2.38 3.45 6 P 0 8 0;1=2
P 1.41 3.795 6 P 0 8 0;1=2
P 3.445 3.613 6 P 0 8 0;1=2
P 3.365 3.613 6 P 0 8 0;1=0
P 3.25 3.63 6 P 0 8 0;1=2
P 3.325 3.613 6 P 0 8 0;1=2
P 3.405 3.613 6 P 0 8 0;1=2
P 3.48418002 3.613 6 P 0 8 0;1=2
P 3.645 4.135 6 P 0 8 0;1=2
P 3.655 3.059 6 P 0 8 0;1=2
P 3.614 3.099 6 P 0 8 0;1=2
P 3.614 3.058 6 P 0 8 0;1=2
P 3.614 3.015 6 P 0 8 0;1=2
P 5.236 2.811 6 P 0 8 0;1=2
P 4.3305 2.914 6 P 0 8 0;1=15
P 4.3815 2.838 6 P 0 8 0;1=15
P 4.29 2.74 4 P 0 8 0;1=3
P 4.456 2.783 6 P 0 8 0;1=2
P 4.355 2.745 6 P 0 8 0;1=2
P 4.346 2.783 6 P 0 8 0;1=2
P 4.4 2.785 6 P 0 8 0;1=2
P 4 2.655 6 P 0 8 0;1=2
P 5.022 2.407 6 P 0 8 0;1=2
P 4.923 2.408 6 P 0 8 0;1=2
P 4.972 2.406 6 P 0 8 0;1=2
P 4.971 2.447 6 P 0 8 0;1=2
P 5.2871 2.275 6 P 0 8 0;1=2
P 5.62533002 1.02001004 6 P 0 8 0;1=2
P 5.65933002 1.02 6 P 0 8 0;1=2
P 3.804 0.816 5 P 0 8 0;1=8
P 4.23 0.7295 6 P 0 8 0;1=2
P 2.31 0.715 6 P 0 8 0;1=2
P 2.31 0.68 6 P 0 8 0;1=2
P 2.595 0.547 6 P 0 8 0;1=2
P 1.87598002 0.289 5 P 0 8 0;1=8
P 1.86 0.33 5 P 0 8 0;1=8
P 1.895 0.33 5 P 0 8 0;1=8
P 1.87598002 0.369 5 P 0 8 0;1=8
P 0.705 3.82 6 P 0 8 0;1=2
P 0.665 3.82 6 P 0 8 0;1=2
P 0.625 3.82 6 P 0 8 0;1=2
P 0.625 3.78 6 P 0 8 0;1=0
P 0.625 3.73 6 P 0 8 0;1=0
P 0.66 3.65 6 P 0 8 0;1=2
P 0.695 3.65 6 P 0 8 0;1=2
P 0.73 3.65 6 P 0 8 0;1=2
P 0.625 3.69 6 P 0 8 0;1=2
P 0.625 3.65 6 P 0 8 0;1=2
P 3.51 2.37 6 P 0 8 0;1=2
P 0.29 2.915 6 P 0 8 0;1=0
P 0.28 2.965 6 P 0 8 0;1=0
P 0.285 3.02 6 P 0 8 0;1=0
P 2.977 3.351 3 P 0 8 0;1=4
P 3.36525 3.255 3 P 0 8 0;1=4
P 3.36525 3.205 3 P 0 8 0;1=4
P 1.8062 0.7789 5 P 0 8 0;1=7
P 3.073 0.613 5 P 0 8 0;1=7
P 2.54526998 0.339 5 P 0 8 0;1=8
P 2.527 0.44 3 P 0 8 0;1=4
P 5.73991004 4.27558002 6 P 0 8 0;1=0
P 5.38558002 4.27558002 6 P 0 8 0;1=0
P 5.50368996 4.27558002 6 P 0 8 0;1=0
P 5.6218 4.27558002 6 P 0 8 0;1=0
P 5.875 1.9 6 P 0 8 0;1=0
P 3.865 3.65 6 P 0 8 0;1=2
P 6.06901998 1.86 6 P 0 8 0;1=0
P 3.81 3.65 6 P 0 8 0;1=2
P 5.97 1.999 5 P 0 8 0;1=7
P 2.86066998 1.04042992 18 P 0 8 0;1=14
P 5.9645 2.1035 6 P 0 8 0;1=15
P 6.0155 2.0845 6 P 0 8 0;1=15
P 0.43705 3.51576004 16 P 0 8 0;1=16
P 0.43705 3.31655 16 P 0 8 0;1=16
P 0.24806998 3.47245 16 P 0 8 0;1=16
P 0.24806998 3.35985 16 P 0 8 0;1=16
P 0.24605994 3.4315 20 P 0 8 0;1=6
P 0.4587 3.4315 20 P 0 8 0;1=6
P 0.44097992 3.4008 20 P 0 8 0;1=6
P 0.22833996 3.4008 20 P 0 8 0;1=6
P 4.94093996 4.12008002 19 P 0 8 0;1=17
P 4.94093996 3.09646004 19 P 0 8 0;1=17
P 2.55906004 4.12008002 19 P 0 8 0;1=17
P 2.55906004 3.09646004 19 P 0 8 0;1=17
P 5.88778996 3.34448996 17 P 0 8 0;1=13
P 5.88778996 3.50983996 17 P 0 8 0;1=13
P 5.88778996 3.67518996 17 P 0 8 0;1=13
P 6.51581998 2.24803996 15 P 0 8 0;1=18
P 6.51581998 1.97243996 14 P 0 8 0;1=19
P 6.40951998 2.20866998 21 P 0 8 0;1=20
P 6.40951998 2.01180994 21 P 0 8 0;1=20
P 0.06038996 1.38345994 22 P 0 8 0;1=21
P 0.26038996 1.38345994 22 P 0 8 0;1=21
P 0.06038996 1.18345994 22 P 0 8 0;1=21
P 0.26038996 1.18345994 22 P 0 8 0;1=21
P 0.06038996 0.8126 22 P 0 8 0;1=21
P 0.26038996 0.8126 22 P 0 8 0;1=21
P 0.06038996 0.6126 22 P 0 8 0;1=21
P 0.26038996 0.6126 22 P 0 8 0;1=21
P 0.06038996 2.5252 22 P 0 8 0;1=21
P 0.26038996 2.5252 22 P 0 8 0;1=21
P 0.06038996 2.3252 22 P 0 8 0;1=21
P 0.26038996 2.3252 22 P 0 8 0;1=21
P 0.06038996 1.95433002 22 P 0 8 0;1=21
P 0.26038996 1.95433002 22 P 0 8 0;1=21
P 0.06038996 1.75433002 22 P 0 8 0;1=21
P 0.26038996 1.75433002 22 P 0 8 0;1=21
P 1.26066998 1.84042992 18 P 0 8 0;1=14
P 5.91901998 2.003 5 P 0 8 0;1=7
P 6.06901998 2.004 5 P 0 8 0;1=7
P 3.49 0.825 5 P 0 8 0;1=7
P 2.65966998 0.93443002 10 P 0 8 0;1=14
P 6.095 2.545 6 P 0 8 0;1=0
P 5.07 1.885 6 P 0 8 0;1=2
P 5.33 0.995 5 P 0 8 0;1=8
P 3.54 0.825 6 P 0 8 0;1=2
P 6.04 2.545 6 P 0 8 0;1=0
P 5.07 1.925 6 P 0 8 0;1=2
P 5.33 0.95 5 P 0 8 0;1=8
P 2.53966998 0.93443002 10 P 0 8 0;1=14
P 2.802 1.987 5 P 0 8 0;1=8
P 2.834 1.987 5 P 0 8 0;1=8
P 2.845 1.875 5 P 0 8 0;1=8
P 2.845 1.843 5 P 0 8 0;1=8
P 2.77866998 0.93443002 10 P 0 8 0;1=14
P 4.97 1.54 4 P 0 8 0;1=3
P 4.9806 1.855 6 P 0 8 0;1=0
P 1.26066998 1.04043002 10 P 0 8 0;1=14
P 0.724 2.646 6 P 0 8 0;1=0
P 0.758 2.743 3 P 0 8 0;1=4
P 3.235 2.63 4 P 0 8 0;1=3
P 3.275 2.32 3 P 0 8 0;1=4
P 3.24 2.275 6 P 0 8 0;1=0
P 3.305 2.65 4 P 0 8 0;1=3
P 3.375 2.65 4 P 0 8 0;1=3
P 3.326 2.466 3 P 0 8 0;1=4
P 2.1481 0.7881 5 P 0 8 0;1=7
P 5.08 1.105 6 P 0 8 0;1=2
P 5.225 1.145 6 P 0 8 0;1=2
P 5.132 0.66 6 P 0 8 0;1=2
P 2.0816 0.7399 6 P 0 8 0;1=2
P 2.03 0.75 5 P 0 8 0;1=7
P 5.08 1.155 6 P 0 8 0;1=2
P 5.08 1.055 6 P 0 8 0;1=2
P 2.0788 0.7874 5 P 0 8 0;1=7
P 2.29581998 0.48918002 4 P 0 8 0;1=3
P 2.633 0.522 5 P 0 8 0;1=8
P 3.455 0.87 6 P 0 8 0;1=2
P 0.9225 0.9775 6 P 0 8 0;1=2
P 4.82 0.835 6 P 0 8 0;1=0
P 0.8825 1.7725 6 P 0 8 0;1=2
P 3.405 0.87 6 P 0 8 0;1=2
P 0.965 0.98 6 P 0 8 0;1=2
P 0.91 1.815 6 P 0 8 0;1=0
P 4.78 0.78 6 P 0 8 0;1=2
P 4.42311004 1.86311004 3 P 0 8 0;1=11
P 3.65101004 1.88358996 4 P 0 8 0;1=9
P 4.46248002 1.86311004 3 P 0 8 0;1=11
P 3.65101004 1.91558996 4 P 0 8 0;1=9
P 3.065 1.695 4 P 0 8 0;1=3
P 2.98283996 1.75183996 6 P 0 8 0;1=2
P 2.225 3.245 6 P 0 8 0;1=2
P 4.595 2.62 6 P 0 8 0;1=2
P 4.025 3.08 6 P 0 8 0;1=2
P 0.62 3.07 6 P 0 8 0;1=2
P 5.865 1.125 6 P 0 8 0;1=0
P 5.865 1.07 6 P 0 8 0;1=0
P 2.265 3.34 6 P 0 8 0;1=2
P 4.57 2.585 6 P 0 8 0;1=2
P 4.02 3.03 6 P 0 8 0;1=2
P 0.645 2.9675 6 P 0 8 0;1=2
P 5.48828996 4.16328996 6 P 0 8 0;1=0
P 3.99005 1.90248002 4 P 0 8 0;1=1
P 5.55315 4.175 6 P 0 8 0;1=0
P 3.99005 1.86311004 4 P 0 8 0;1=1
P 5.67126004 4.175 6 P 0 8 0;1=0
P 3.95066998 1.82373996 4 P 0 8 0;1=1
P 5.78936998 4.175 6 P 0 8 0;1=0
P 3.9113 1.82373996 4 P 0 8 0;1=1
P 4.205 2.295 4 P 0 8 0;1=3
P 4.65933002 1.6269 4 P 0 8 0;1=3
P 4.254 2.296 4 P 0 8 0;1=3
P 4.23 2.354 4 P 0 8 0;1=3
P 4.915 1.485 4 P 0 8 0;1=3
P 4.65933002 1.54816004 4 P 0 8 0;1=1
P 3.94 2.235 4 P 0 8 0;1=3
P 4.85 1.54 4 P 0 8 0;1=3
P 4.149 2.298 4 P 0 8 0;1=3
P 4.161 2.354 4 P 0 8 0;1=3
P 3.75 2.1 4 P 0 8 0;1=3
P 4.975 1.485 4 P 0 8 0;1=3
P 4.58058996 1.58753002 4 P 0 8 0;1=1
P 3.8 2.1 4 P 0 8 0;1=3
P 4.73806998 1.54816004 4 P 0 8 0;1=3
P 3.9 2.325 4 P 0 8 0;1=3
P 4.73806998 1.50878996 4 P 0 8 0;1=3
P 3.83 2.325 4 P 0 8 0;1=3
P 0.846 2.489 3 P 0 8 0;1=4
P 3.28 3.065 6 P 0 8 0;1=2
P 0.796 2.489 3 P 0 8 0;1=4
P 3.325 3.065 6 P 0 8 0;1=2
P 5.03 3.546 3 P 0 8 0;1=4
P 4.935 3.59 3 P 0 8 0;1=4
P 4.67 3.555 4 P 0 8 0;1=3
P 4.885 3.59 5 P 0 8 0;1=7
P 4.70461998 3.69461998 3 P 0 8 0;1=4
P 4.50185 1.82373996 4 P 0 8 0;1=1
P 5.395 2.92 6 P 0 8 0;1=0
P 5.015 1.925 6 P 0 8 0;1=2
P 5.39976998 2.75123996 5 P 0 8 0;1=7
P 4.46248002 1.82373996 4 P 0 8 0;1=1
P 5.375 2.96606998 5 P 0 8 0;1=7
P 4.58058996 1.78436998 4 P 0 8 0;1=1
P 5.4525 2.563 5 P 0 8 0;1=7
P 3.545 0.6092 6 P 0 8 0;1=2
P 1.395 0.625 5 P 0 8 0;1=7
P 5.085 0.645 6 P 0 8 0;1=2
P 3.495 0.61 6 P 0 8 0;1=2
P 5.04 0.645 6 P 0 8 0;1=2
P 1.485 0.625 5 P 0 8 0;1=7
P 3.99005 1.6269 3 P 0 8 0;1=11
P 2.95835 0.385 4 P 0 8 0;1=9
P 3.95066998 1.6269 3 P 0 8 0;1=11
P 2.95835 0.353 4 P 0 8 0;1=9
P 3.9113 1.66626998 3 P 0 8 0;1=11
P 2.80086998 0.385 4 P 0 8 0;1=9
P 3.87193002 1.66626998 3 P 0 8 0;1=11
P 2.80086998 0.353 4 P 0 8 0;1=9
P 3.99005 1.70563996 3 P 0 8 0;1=11
P 2.64338996 0.385 4 P 0 8 0;1=9
P 3.95066998 1.70563996 3 P 0 8 0;1=11
P 2.64338996 0.353 4 P 0 8 0;1=9
P 3.9113 1.58753002 3 P 0 8 0;1=11
P 2.95835 0.481 4 P 0 8 0;1=9
P 2.95835 0.449 4 P 0 8 0;1=9
P 3.87193002 1.58753002 3 P 0 8 0;1=11
P 3.125 0.875 4 P 0 8 0;1=9
P 3.99005 1.54816004 3 P 0 8 0;1=11
P 3.14763002 0.85236998 4 P 0 8 0;1=9
P 3.95066998 1.54816004 3 P 0 8 0;1=11
P 2.81855 0.763 4 P 0 8 0;1=9
P 3.9113 1.50878996 3 P 0 8 0;1=11
P 2.85055 0.763 4 P 0 8 0;1=9
P 3.87193002 1.50878996 3 P 0 8 0;1=11
P 2.66706998 0.763 4 P 0 8 0;1=9
P 3.99005 1.46941998 3 P 0 8 0;1=11
P 2.69906998 0.763 4 P 0 8 0;1=9
P 3.95066998 1.46941998 3 P 0 8 0;1=11
P 2.47021998 0.763 4 P 0 8 0;1=9
P 3.9113 1.43005 3 P 0 8 0;1=11
P 2.50221998 0.763 4 P 0 8 0;1=9
P 3.87193002 1.43005 3 P 0 8 0;1=11
P 1.889 0.5496 6 P 0 8 0;1=2
P 2.435 0.4865 3 P 0 8 0;1=4
P 3.56 3.023 6 P 0 8 0;1=0
P 3.57 2.955 6 P 0 8 0;1=0
P 4.975 2.14 6 P 0 8 0;1=2
P 5.03005 0.99493996 6 P 0 8 0;1=0
P 5.638 3.907 6 P 0 8 0;1=0
P 1.8317 0.5639 5 P 0 8 0;1=7
P 2.68566998 1.12143002 11 P 0 8 0;1=22
P 2.68566998 2.55943002 11 P 0 8 0;1=22
P 1.46066998 2.68043002 11 P 0 8 0;1=22
P 1.43566998 1.06043002 11 P 0 8 0;1=22
P 6.40038996 0.65353996 13 P 0 8 0;1=23
P 0.29528002 3.73031004 13 P 0 8 0;1=23
P 0.29528002 0.36811004 13 P 0 8 0;1=23
P 6.40038996 4.17835 13 P 0 8 0;1=23
P 6.34055 3.34448996 12 P 0 8 0;1=24
P 6.34055 3.67518996 12 P 0 8 0;1=24
L 3.80999961 -1.25 3.80999961 -1.33 1 N 0 ;0
L 3.80999961 -1.33 3.8500003 -1.33 1 N 0 ;0
L 3.90999902 -1.25 3.90199892 -1.25266614 1 N 0 ;0
L 3.90199892 -1.25266614 3.8960002 -1.25933386 1 N 0 ;0
L 3.8960002 -1.25933386 3.89199921 -1.26733209 1 N 0 ;0
L 3.89199921 -1.26733209 3.8889999 -1.27800138 1 N 0 ;0
L 3.8889999 -1.27800138 3.8880001 -1.29000128 1 N 0 ;0
L 3.8880001 -1.29000128 3.8889999 -1.30200118 1 N 0 ;0
L 3.8889999 -1.30200118 3.89199921 -1.31266801 1 N 0 ;0
L 3.89199921 -1.31266801 3.8960002 -1.3206687 1 N 0 ;0
L 3.8960002 -1.3206687 3.90199892 -1.32733396 1 N 0 ;0
L 3.90199892 -1.32733396 3.90999902 -1.33 1 N 0 ;0
L 3.90999902 -1.33 3.91799911 -1.32733396 1 N 0 ;0
L 3.91799911 -1.32733396 3.9239997 -1.3206687 1 N 0 ;0
L 3.9239997 -1.3206687 3.92800069 -1.31266801 1 N 0 ;0
L 3.92800069 -1.31266801 3.931 -1.30200118 1 N 0 ;0
L 3.931 -1.30200118 3.9319998 -1.29000128 1 N 0 ;0
L 3.9319998 -1.29000128 3.931 -1.27800138 1 N 0 ;0
L 3.931 -1.27800138 3.92800069 -1.26733209 1 N 0 ;0
L 3.92800069 -1.26733209 3.9239997 -1.25933386 1 N 0 ;0
L 3.9239997 -1.25933386 3.91799911 -1.25266614 1 N 0 ;0
L 3.91799911 -1.25266614 3.90999902 -1.25 1 N 0 ;0
L 3.98799951 -1.33 3.98999902 -1.31266801 1 N 0 ;0
L 3.98999902 -1.31266801 3.9930002 -1.29800197 1 N 0 ;0
L 3.9930002 -1.29800197 3.99699941 -1.28466663 1 N 0 ;0
L 3.99699941 -1.28466663 4.0020001 -1.27000069 1 N 0 ;0
L 4.0020001 -1.27000069 4.0100003 -1.25 1 N 0 ;0
L 4.0100003 -1.25 3.96999961 -1.25 1 N 0 ;0
L 4.04 -1.35666585 4.1 -1.35666585 1 N 0 ;0
L 4.15599961 -1.29000128 4.17600079 -1.29000128 1 N 0 ;0
L 4.17600079 -1.29000128 4.17600079 -1.31400098 1 N 0 ;0
L 4.17600079 -1.31400098 4.1700003 -1.32200177 1 N 0 ;0
L 4.1700003 -1.32200177 4.1629999 -1.32733396 1 N 0 ;0
L 4.1629999 -1.32733396 4.1530002 -1.33 1 N 0 ;0
L 4.1530002 -1.33 4.14300049 -1.32733396 1 N 0 ;0
L 4.14300049 -1.32733396 4.1360002 -1.32200177 1 N 0 ;0
L 4.1360002 -1.32200177 4.12999961 -1.31400098 1 N 0 ;0
L 4.12999961 -1.31400098 4.12599862 -1.30466722 1 N 0 ;0
L 4.12599862 -1.30466722 4.12399911 -1.29400039 1 N 0 ;0
L 4.12399911 -1.29400039 4.12399911 -1.28466663 1 N 0 ;0
L 4.12399911 -1.28466663 4.12599862 -1.27666831 1 N 0 ;0
L 4.12599862 -1.27666831 4.12999961 -1.26733209 1 N 0 ;0
L 4.12999961 -1.26733209 4.1360002 -1.25933386 1 N 0 ;0
L 4.1360002 -1.25933386 4.14199892 -1.25400167 1 N 0 ;0
L 4.14199892 -1.25400167 4.14999902 -1.25 1 N 0 ;0
L 4.14999902 -1.25 4.15699941 -1.25 1 N 0 ;0
L 4.15699941 -1.25 4.16499951 -1.25266614 1 N 0 ;0
L 4.16499951 -1.25266614 4.171 -1.25800079 1 N 0 ;0
L 4.2070003 -1.33 4.2070003 -1.25 1 N 0 ;0
L 4.2070003 -1.25 4.25299961 -1.33 1 N 0 ;0
L 4.25299961 -1.33 4.25299961 -1.25 1 N 0 ;0
L 4.2880001 -1.33 4.2880001 -1.25 1 N 0 ;0
L 4.2880001 -1.25 4.30799951 -1.25 1 N 0 ;0
L 4.30799951 -1.25 4.31599961 -1.25400167 1 N 0 ;0
L 4.31599961 -1.25400167 4.3220001 -1.25933386 1 N 0 ;0
L 4.3220001 -1.25933386 4.32700089 -1.26733209 1 N 0 ;0
L 4.32700089 -1.26733209 4.331 -1.27666831 1 N 0 ;0
L 4.331 -1.27666831 4.3319998 -1.29000128 1 N 0 ;0
L 4.3319998 -1.29000128 4.331 -1.30333415 1 N 0 ;0
L 4.331 -1.30333415 4.32700089 -1.31266801 1 N 0 ;0
L 4.32700089 -1.31266801 4.3220001 -1.3206687 1 N 0 ;0
L 4.3220001 -1.3206687 4.31599961 -1.32600089 1 N 0 ;0
L 4.31599961 -1.32600089 4.30799951 -1.33 1 N 0 ;0
L 4.30799951 -1.33 4.2880001 -1.33 1 N 0 ;0
L 4.3680001 -1.31400098 4.37399882 -1.32333484 1 N 0 ;0
L 4.37399882 -1.32333484 4.38199892 -1.32866703 1 N 0 ;0
L 4.38199892 -1.32866703 4.39100069 -1.33 1 N 0 ;0
L 4.39100069 -1.33 4.39900079 -1.32866703 1 N 0 ;0
L 4.39900079 -1.32866703 4.40700089 -1.32200177 1 N 0 ;0
L 4.40700089 -1.32200177 4.4119998 -1.31400098 1 N 0 ;0
L 4.4119998 -1.31400098 4.41299961 -1.3060003 1 N 0 ;0
L 4.41299961 -1.3060003 4.411 -1.296669 1 N 0 ;0
L 4.411 -1.296669 4.4039997 -1.29000128 1 N 0 ;0
L 4.4039997 -1.29000128 4.39699941 -1.28733278 1 N 0 ;0
L 4.39699941 -1.28733278 4.38799951 -1.28733278 1 N 0 ;0
L 4.39699941 -1.28733278 4.4029999 -1.28333356 1 N 0 ;0
L 4.4029999 -1.28333356 4.40800069 -1.27666831 1 N 0 ;0
L 4.40800069 -1.27666831 4.4100003 -1.26866762 1 N 0 ;0
L 4.4100003 -1.26866762 4.40800069 -1.26066683 1 N 0 ;0
L 4.40800069 -1.26066683 4.4029999 -1.25400167 1 N 0 ;0
L 4.4029999 -1.25400167 4.394 -1.25 1 N 0 ;0
L 4.394 -1.25 4.3850001 -1.25133307 1 N 0 ;0
L 4.3850001 -1.25133307 4.3760002 -1.25666772 1 N 0 ;0
L 3.16 -0.655 3.16 -1.58 2 N 0 ;0
L 1.36 -0.655 1.36 -1.58 2 N 0 ;0
L 1.36 -1.58 5.06 -1.58 2 N 0 ;0
L 5.06 -1.58 5.06 -0.655 2 N 0 ;0
L 5.06 -0.655 1.36 -0.655 2 N 0 ;0
A 1.559 -1.33655 1.559 -1.33655 1.55268002 -1.33655 1 N 0 N;0
A 1.54775 -1.205 1.54775 -1.205 1.53883002 -1.205 1 N 0 N;0
A 1.54763996 -0.99775 1.54763996 -0.99775 1.53871998 -0.99775 1 N 0 N;0
A 1.54063996 -1.10118002 1.54063996 -1.10118002 1.52603996 -1.10118002 1 N 0 N;0
A 1.49695 -1.10118002 1.49695 -1.10118002 1.48656998 -1.10118002 1 N 0 N;0
A 1.45963996 -1.10118002 1.45963996 -1.10118002 1.4533 -1.10118002 1 N 0 N;0
A 1.52135 -0.98681004 1.52135 -0.98681004 1.51503002 -0.98681004 1 N 0 N;0
A 1.79433002 -1.43586998 1.79433002 -1.43586998 1.78798996 -1.43586998 1 N 0 N;0
A 1.79841004 -1.40261004 1.79841004 -1.40261004 1.78798996 -1.40261004 1 N 0 N;0
A 1.80255 -1.36311004 1.80255 -1.36311004 1.78798996 -1.36311004 1 N 0 N;0
A 1.80668996 -1.31528002 1.80668996 -1.31528002 1.78798996 -1.31528002 1 N 0 N;0
A 1.68013002 -1.37456004 1.68013002 -1.37456004 1.67378996 -1.37456004 1 N 0 N;0
A 1.69321998 -1.35033002 1.69321998 -1.35033002 1.6843 -1.35033002 1 N 0 N;0
A 1.7108 -1.31738996 1.7108 -1.31738996 1.69798002 -1.31738996 1 N 0 N;0
A 1.89666998 -1.31511004 1.89666998 -1.31511004 1.88383996 -1.31511004 1 N 0 N;0
A 1.88198996 -1.16876004 1.88198996 -1.16876004 1.85558996 -1.16876004 1 N 0 N;0
A 1.87928002 -1.27801998 1.87928002 -1.27801998 1.86343996 -1.27801998 1 N 0 N;0
A 1.86176998 -1.23075 1.86176998 -1.23075 1.84206004 -1.23075 1 N 0 N;0
A 1.80978996 -1.25916998 1.80978996 -1.25916998 1.78798996 -1.25916998 1 N 0 N;0
A 1.74681004 -1.16876004 1.74681004 -1.16876004 1.72041004 -1.16876004 1 N 0 N;0
A 1.67813002 -1.15513002 1.67813002 -1.15513002 1.65841998 -1.15513002 1 N 0 N;0
A 1.73018002 -1.27816004 1.73018002 -1.27816004 1.71433996 -1.27816004 1 N 0 N;0
A 1.75373002 -1.23081004 1.75373002 -1.23081004 1.73405 -1.23081004 1 N 0 N;0
A 1.65531004 -1.25255 1.65531004 -1.25255 1.63661998 -1.25255 1 N 0 N;0
A 1.69808996 -1.21291998 1.69808996 -1.21291998 1.67628996 -1.21291998 1 N 0 N;0
A 1.81438996 -1.1968 1.81438996 -1.1968 1.78798996 -1.1968 1 N 0 N;0
A 1.6269 -1.1749 1.6269 -1.1749 1.61106004 -1.1749 1 N 0 N;0
A 1.58461004 -1.19126004 1.58461004 -1.19126004 1.57178002 -1.19126004 1 N 0 N;0
A 1.5853 -1.31428002 1.5853 -1.31428002 1.57488996 -1.31428002 1 N 0 N;0
A 1.61735 -1.28638996 1.61735 -1.28638996 1.60276998 -1.28638996 1 N 0 N;0
A 1.88198996 -1.03361004 1.88198996 -1.03361004 1.85558996 -1.03361004 1 N 0 N;0
A 1.71881004 -1.10118002 1.71881004 -1.10118002 1.69238996 -1.10118002 1 N 0 N;0
A 1.65183002 -1.10118002 1.65183002 -1.10118002 1.63003002 -1.10118002 1 N 0 N;0
A 1.67801998 -1.04738996 1.67801998 -1.04738996 1.65831004 -1.04738996 1 N 0 N;0
A 1.74681004 -1.03361004 1.74681004 -1.03361004 1.72041004 -1.03361004 1 N 0 N;0
A 1.69811998 -0.98951004 1.69811998 -0.98951004 1.67631998 -0.98951004 1 N 0 N;0
A 1.81438996 -1.00556004 1.81438996 -1.00556004 1.78798996 -1.00556004 1 N 0 N;0
A 1.59258002 -1.10118002 1.59258002 -1.10118002 1.5739 -1.10118002 1 N 0 N;0
A 1.58451004 -1.01148996 1.58451004 -1.01148996 1.57168002 -1.01148996 1 N 0 N;0
A 1.62681004 -1.02773996 1.62681004 -1.02773996 1.61096998 -1.02773996 1 N 0 N;0
A 1.92148002 -1.21285 1.92148002 -1.21285 1.89968002 -1.21285 1 N 0 N;0
A 1.92148002 -0.98951004 1.92148002 -0.98951004 1.89968002 -0.98951004 1 N 0 N;0
A 1.80978996 -0.9432 1.80978996 -0.9432 1.78798996 -0.9432 1 N 0 N;0
A 1.80668996 -0.88708002 1.80668996 -0.88708002 1.78798996 -0.88708002 1 N 0 N;0
A 1.80255 -0.83923996 1.80255 -0.83923996 1.78798996 -0.83923996 1 N 0 N;0
A 1.8919 -0.88538002 1.8919 -0.88538002 1.87906998 -0.88538002 1 N 0 N;0
A 1.87838996 -0.92456998 1.87838996 -0.92456998 1.86255 -0.92456998 1 N 0 N;0
A 1.65531004 -0.94981004 1.65531004 -0.94981004 1.63661998 -0.94981004 1 N 0 N;0
A 1.73123002 -0.92378002 1.73123002 -0.92378002 1.71538996 -0.92378002 1 N 0 N;0
A 1.71216998 -0.88443996 1.71216998 -0.88443996 1.69935 -0.88443996 1 N 0 N;0
A 1.86225 -0.97178002 1.86225 -0.97178002 1.84253996 -0.97178002 1 N 0 N;0
A 1.75451998 -0.97123996 1.75451998 -0.97123996 1.73483996 -0.97123996 1 N 0 N;0
A 1.61741998 -0.91601004 1.61741998 -0.91601004 1.60283996 -0.91601004 1 N 0 N;0
A 1.5853 -0.88808996 1.5853 -0.88808996 1.57488996 -0.88808996 1 N 0 N;0
A 1.79841004 -0.79975 1.79841004 -0.79975 1.78798996 -0.79975 1 N 0 N;0
A 1.79433002 -0.76648002 1.79433002 -0.76648002 1.78798996 -0.76648002 1 N 0 N;0
A 1.92135 -1.36781004 1.92135 -1.36781004 1.91503996 -1.36781004 1 N 0 N;0
A 1.91096004 -1.34658002 1.91096004 -1.34658002 1.90203996 -1.34658002 1 N 0 N;0
A 2.19078996 -1.1806 2.26591004 -1.16473002 2.21741014 -1.12088169 1 N 0 N;0
A 2.15903002 -1.1402 2.19078996 -1.18061004 2.22093406 -1.12423278 1 N 0 N;0
A 2.05721004 -1.16178996 2.08853002 -1.16658996 2.08281614 -1.09929134 1 N 0 N;0
A 2.00546998 -1.13951998 2.03345 -1.17196004 2.07793927 -1.10530069 1 N 0 N;0
A 2.03346004 -1.17195 2.0847 -1.18461004 2.07891181 -1.09801299 1 N 0 N;0
A 2.0847 -1.18461998 2.14261004 -1.15663002 2.07348435 -1.08751378 1 N 0 N;0
A 2.08853996 -1.16658002 2.13313002 -1.14451998 2.06368967 -1.06025512 1 N 0 N;0
A 1.95808002 -1.25255 1.95808002 -1.25255 1.93938996 -1.25255 1 N 0 N;0
A 1.98775 -1.28635 1.98775 -1.28635 1.97316998 -1.28635 1 N 0 N;0
A 2.27411998 -1.11835 2.15906004 -1.11835 2.21658996 -1.11611998 1 N 0 N;0
L 2.25188002 -1.11418002 2.1807 -1.11418002 1 N 0 ;0
L 2.1807 -1.11418002 2.1807 -1.11398996 1 N 8191 ;0
A 2.25188996 -1.11398996 2.18071004 -1.11398996 2.2163 -1.1124 1 N 0 N;0
A 2.08028996 -1.03428996 2.02048996 -1.08258996 2.0798126 -1.09486801 1 N 0 N;0
A 2.13151998 -1.05146004 2.0803 -1.0343 2.0802999 -1.11932195 1 N 0 N;0
A 2.1315 -1.05146998 2.14175 -1.03951004 2.1356003 -1.04461171 1 N 0 N;0
A 2.14175 -1.03951004 2.08283002 -1.01613002 2.07772461 -1.11492805 1 N 0 N;0
A 2.08283996 -1.01611998 2.00698002 -1.05835 2.08064724 -1.10143169 1 N 0 N;0
L 2.27413002 -1.12868996 2.18073996 -1.12868996 1 N 0 ;0
A 2.18075 -1.12868996 2.19083002 -1.15751998 2.22417795 -1.12968307 1 N 0 N;0
A 2.19083002 -1.15753002 2.25311004 -1.15211004 2.21927195 -1.12381791 1 N 0 N;0
L 2.15903996 -1.1402 2.15903996 -1.11835 1 N 8191 ;0
A 2.02048996 -1.0826 2.05721998 -1.16181004 2.09087933 -1.0980811 1 N 0 N;0
A 2.00698996 -1.05836004 2.00546998 -1.13953002 2.09672953 -1.10063967 1 N 0 N;0
A 2.14258996 -1.15661004 2.13313996 -1.14453002 2.13544892 -1.15246004 1 N 0 N;0
A 1.95808002 -0.94981004 1.95808002 -0.94981004 1.93938996 -0.94981004 1 N 0 N;0
A 1.90183996 -0.8525 1.90183996 -0.8525 1.89291004 -0.8525 1 N 0 N;0
A 1.91108002 -0.82726998 1.91108002 -0.82726998 1.90473996 -0.82726998 1 N 0 N;0
L 2.32081004 -1.02041004 2.32081004 -1.17625 1 N 0 ;0
A 2.49568002 -1.15528996 2.47898002 -1.16443002 2.4882003 -1.1614502 1 N 0 N;0
A 2.47896998 -1.16443996 2.50283002 -1.18086004 2.51649242 -1.13546152 1 N 0 N;0
A 2.50281998 -1.18086998 2.54318002 -1.1834 2.52887392 -1.08843022 1 N 0 N;0
A 2.52306998 -1.16761004 2.52848996 -1.16771998 2.52673258 -1.12070098 1 N 0 N;0
A 2.49566004 -1.15528996 2.52306998 -1.1676 2.5255122 -1.12549094 1 N 0 N;0
A 2.37851998 -1.15753002 2.4408 -1.15211004 2.40696191 -1.12381791 1 N 0 N;0
A 2.45358002 -1.16471998 2.44078996 -1.1521 2.44541191 -1.16020689 1 N 0 N;0
A 2.37848002 -1.1806 2.4536 -1.16473002 2.4051001 -1.12088169 1 N 0 N;0
A 2.34673002 -1.1402 2.37848996 -1.18061004 2.40863406 -1.12423278 1 N 0 N;0
A 2.2659 -1.16471998 2.25311004 -1.1521 2.25773199 -1.16020689 1 N 0 N;0
A 2.3006 -1.17626004 2.3208 -1.17626004 2.3107 -1.17386841 1 N 0 N;0
L 2.30058996 -1.17625 2.30058996 -1.02033996 1 N 0 ;0
A 2.50836998 -1.10106004 2.54306004 -1.11513002 2.56106673 -1.02093386 1 N 0 N;0
A 2.51081004 -1.07948002 2.50836998 -1.10103996 2.51886093 -1.09130915 1 N 0 N;0
A 2.53611004 -1.07688996 2.5108 -1.07948996 2.52742205 -1.11680827 1 N 0 N;0
A 2.56883996 -1.07368002 2.50178002 -1.06358996 2.5273123 -1.12178858 1 N 0 N;0
A 2.50178996 -1.06358996 2.48536998 -1.08248996 2.52926211 -1.10403986 1 N 0 N;0
L 2.48536998 -1.0825 2.48536998 -1.09748002 1 N 8191 ;0
A 2.48536998 -1.09748002 2.49956004 -1.12031004 2.51189104 -1.09682067 1 N 0 N;0
A 2.46181004 -1.11835 2.34675 -1.11835 2.40428002 -1.11611998 1 N 0 N;0
L 2.43956998 -1.11418002 2.36841004 -1.11418002 1 N 0 ;0
L 2.36841004 -1.11418002 2.36841004 -1.11398996 1 N 8191 ;0
A 2.43958002 -1.11398996 2.3684 -1.11398996 2.40398996 -1.1124 1 N 0 N;0
L 2.43956998 -1.11398996 2.43956998 -1.11418002 1 N 8191 ;0
A 2.49955 -1.1203 2.52723002 -1.12985 2.58163209 -0.92727982 1 N 0 N;0
A 2.55001998 -1.14328002 2.52723002 -1.12986004 2.51462185 -1.17733228 1 N 0 N;0
L 2.46181004 -1.12868996 2.36843996 -1.12868996 1 N 0 ;0
A 2.36843996 -1.12868996 2.37851998 -1.15751998 2.41186801 -1.12968307 1 N 0 N;0
L 2.34675 -1.1402 2.34675 -1.11835 1 N 8191 ;0
L 2.46181004 -1.11835 2.46181004 -1.12868996 1 N 8191 ;0
L 2.25188002 -1.11398996 2.25188002 -1.11418002 1 N 8191 ;0
A 2.3208 -1.02041004 2.3006 -1.02033996 2.31069163 -1.02276978 1 N 0 N;0
L 2.27413002 -1.11835 2.27413002 -1.12868996 1 N 8191 ;0
A 2.52848996 -1.16771004 2.54891998 -1.15895 2.52774557 -1.13777087 1 N 0 N;0
A 2.55608002 -1.08618002 2.53611998 -1.07688996 2.5249185 -1.12704419 1 N 0 N;0
L 2.71926004 -1.06796998 2.71926004 -1.17483996 1 N 0 ;0
A 2.78888996 -1.16296998 2.81508002 -1.16676998 2.8083499 -1.12100167 1 N 0 N;0
A 2.8151 -1.16675 2.83966004 -1.15211998 2.80521398 -1.12222392 1 N 0 N;0
A 2.85201004 -1.16508002 2.83966004 -1.15211004 2.84505768 -1.15933514 1 N 0 N;0
L 2.85201004 -1.16508002 2.84523996 -1.17161004 1 N 8191 ;0
A 2.81425 -1.1835 2.84525 -1.17161004 2.81425 -1.13714291 1 N 0 N;0
L 2.81425 -1.1835 2.79571004 -1.1835 1 N 8191 ;0
A 2.75886998 -1.16443002 2.79571998 -1.18351998 2.80278976 -1.12476142 1 N 0 N;0
A 2.74528996 -1.13568002 2.75888002 -1.16443002 2.80246565 -1.12624016 1 N 0 N;0
A 2.54316998 -1.1834 2.56906004 -1.1647 2.5305814 -1.13869892 1 N 0 N;0
A 2.56906004 -1.1647 2.57053996 -1.13728002 2.53763041 -1.14925374 1 N 0 N;0
A 2.65463996 -1.18351998 2.66863996 -1.17373996 2.65440246 -1.16826969 1 N 0 N;0
L 2.65463002 -1.1835 2.64165 -1.1835 1 N 8191 ;0
A 2.60955 -1.16043002 2.64163996 -1.18351004 2.63911063 -1.15317815 1 N 0 N;0
A 2.62978002 -1.15461998 2.66001998 -1.16328996 2.6502374 -1.14033868 1 N 0 N;0
A 2.66863996 -1.17375 2.66001998 -1.16328996 2.66100344 -1.17126132 1 N 0 N;0
A 2.6962 -1.17483996 2.71926004 -1.17483996 2.70773002 -1.17286427 1 N 0 N;0
L 2.69618996 -1.17483996 2.69618996 -1.06796998 1 N 0 ;0
A 2.83833002 -1.09275 2.82661998 -1.08201998 2.74555758 -1.18224094 1 N 0 N;0
A 2.82661998 -1.08198996 2.80036998 -1.07538996 2.80348839 -1.11848878 1 N 0 N;0
A 2.80036004 -1.07541998 2.76848996 -1.09933002 2.80700217 -1.1174685 1 N 0 N;0
A 2.76848996 -1.09931998 2.76446004 -1.12066004 2.82315728 -1.120694 1 N 0 N;0
A 2.74998002 -1.09273996 2.74528996 -1.11838996 2.8498563 -1.12425591 1 N 0 N;0
A 2.7954 -1.05776998 2.74998996 -1.09273996 2.80799961 -1.12109961 1 N 0 N;0
L 2.79541004 -1.05776998 2.80918996 -1.05776998 1 N 8191 ;0
A 2.85401998 -1.08106004 2.80918996 -1.05776998 2.80626024 -1.1181998 1 N 0 N;0
A 2.83833002 -1.09273996 2.85403002 -1.08106004 2.84418386 -1.08421683 1 N 0 N;0
L 2.76445 -1.12066004 2.76445 -1.12943002 1 N 8191 ;0
A 2.76446004 -1.12943002 2.76836998 -1.14305 2.80607844 -1.12485364 1 N 0 N;0
A 2.76836998 -1.14305 2.78891004 -1.16296998 2.80906152 -1.12164144 1 N 0 N;0
L 2.74528996 -1.13566004 2.74528996 -1.11838996 1 N 8191 ;0
A 2.55606004 -1.0862 2.56885 -1.07366998 2.56205354 -1.0795252 1 N 0 N;0
L 2.60953996 -1.07953996 2.59981998 -1.07953996 1 N 8191 ;0
A 2.5993 -1.05931998 2.59981004 -1.07955 2.6022813 -1.06936624 1 N 0 N;0
L 2.5993 -1.05931998 2.60953996 -1.05931998 1 N 8191 ;0
L 2.60953996 -1.05931998 2.60953996 -1.03491998 1 N 8191 ;0
A 2.62971998 -1.03418002 2.60953996 -1.03491004 2.61966791 -1.03559478 1 N 0 N;0
L 2.62971004 -1.03418996 2.62978002 -1.05931998 1 N 8191 ;0
L 2.62978002 -1.05931998 2.66008002 -1.05931998 1 N 8191 ;0
A 2.66003996 -1.07955 2.66008002 -1.05931998 2.65827421 -1.0694314 1 N 0 N;0
L 2.66003002 -1.07953996 2.62978002 -1.07953996 1 N 8191 ;0
A 2.71926004 -1.06796998 2.6962 -1.06796998 2.70773002 -1.0720561 1 N 0 N;0
A 2.71968996 -1.02341998 2.71968996 -1.02341998 2.70775 -1.02341998 1 N 0 N;0
A 2.57053996 -1.13728996 2.54306998 -1.11513002 2.53584449 -1.15219301 1 N 0 N;0
A 2.54891998 -1.15895 2.55001004 -1.14328002 2.54127923 -1.15054557 1 N 0 N;0
L 2.60953996 -1.16041004 2.60953996 -1.07953996 1 N 0 ;0
L 2.62978002 -1.07953996 2.62978002 -1.15463002 1 N 0 ;0
L 2.98495 -1.09393996 2.98495 -1.17625 1 N 0 ;0
A 2.96473996 -1.17626998 2.98493996 -1.17626998 2.97483996 -1.17442303 1 N 0 N;0
L 2.96473002 -1.17625 2.96473002 -1.17226004 1 N 8191 ;0
A 2.94165 -1.1835 2.96471004 -1.17226004 2.93076516 -1.1318935 1 N 0 N;0
L 2.94165 -1.1835 2.90701004 -1.1835 1 N 8191 ;0
A 2.90671004 -1.10841998 2.90703002 -1.18351004 2.9153065 -1.14592904 1 N 0 N;0
A 2.91853002 -1.12288996 2.91853002 -1.16618996 2.92048209 -1.14453996 1 N 0 N;0
L 2.91853002 -1.1662 2.94456004 -1.1662 1 N 8191 ;0
A 2.94456998 -1.16618996 2.94456998 -1.12288996 2.94406004 -1.14453996 1 N 0 N;0
A 2.96473002 -1.09686004 2.94741998 -1.07955 2.94874833 -1.09553169 1 N 0 N;0
L 2.9474 -1.07953996 2.90986998 -1.07953996 1 N 8191 ;0
A 2.90986998 -1.07953996 2.89821004 -1.0852 2.92433445 -1.12417766 1 N 0 N;0
A 2.89111998 -1.07086004 2.8982 -1.0852 2.8969689 -1.07688996 1 N 0 N;0
A 2.91561998 -1.05931998 2.89111998 -1.07085 2.92146033 -1.103525 1 N 0 N;0
L 2.91563002 -1.05931998 2.95031004 -1.05931998 1 N 8191 ;0
A 2.98496004 -1.09393996 2.95031004 -1.05933002 2.9453438 -1.09895197 1 N 0 N;0
A 2.92878996 -1.10535 2.9067 -1.10841998 2.93158484 -1.20646998 1 N 0 N;0
A 2.96471998 -1.10841004 2.92878002 -1.10536004 2.93215738 -1.27883829 1 N 0 N;0
L 2.96473002 -1.10841004 2.96473002 -1.09686004 1 N 8191 ;0
L 2.94456004 -1.12288002 2.91853002 -1.12288002 1 N 8191 ;0
L 3.04731004 -1.06001004 3.04191998 -1.07631998 1 N 8191 ;0
L 3.04191998 -1.07631998 3.03648002 -1.06001004 1 N 8191 ;0
L 3.03648002 -1.06001004 3.03243002 -1.06001004 1 N 8191 ;0
L 3.03243002 -1.06001004 3.02698002 -1.08543996 1 N 8191 ;0
L 3.02698002 -1.08543996 3.03226004 -1.08543996 1 N 8191 ;0
L 3.03226004 -1.08543996 3.03501004 -1.06886998 1 N 8191 ;0
L 3.03501004 -1.06886998 3.04086004 -1.08543996 1 N 8191 ;0
L 3.04086004 -1.08543996 3.04308996 -1.08543996 1 N 8191 ;0
L 3.04308996 -1.08543996 3.04888996 -1.06871004 1 N 8191 ;0
L 3.04888996 -1.06871004 3.05171004 -1.08543996 1 N 8191 ;0
L 3.05171004 -1.08543996 3.05713002 -1.08543996 1 N 8191 ;0
L 3.05713002 -1.08543996 3.05163996 -1.06001004 1 N 8191 ;0
L 3.05163996 -1.06001004 3.04731004 -1.06001004 1 N 8191 ;0
L 3.01066998 -1.06508002 3.00223002 -1.06508002 1 N 8191 ;0
L 3.00223002 -1.06508002 3.00223002 -1.06001004 1 N 8191 ;0
L 3.00223002 -1.06001004 3.02461004 -1.06001004 1 N 8191 ;0
L 3.02461004 -1.06001004 3.02461004 -1.06508002 1 N 8191 ;0
L 3.02461004 -1.06508002 3.01615 -1.06508002 1 N 8191 ;0
L 3.01615 -1.06508002 3.01615 -1.08533996 1 N 8191 ;0
L 3.01615 -1.08533996 3.01066998 -1.08533996 1 N 8191 ;0
L 3.01066998 -1.08533996 3.01066998 -1.06508002 1 N 8191 ;0
L 3.36933297 -0.955 3.36933297 -0.88 0 N 0 ;0
L 3.36933297 -0.88 3.39173337 -0.88 0 N 0 ;0
L 3.39173337 -0.88 3.3992001 -0.88375157 0 N 0 ;0
L 3.3992001 -0.88375157 3.40480059 -0.8924997 0 N 0 ;0
L 3.40480059 -0.8924997 3.40666693 -0.9024998 0 N 0 ;0
L 3.40666693 -0.9024998 3.40480059 -0.9125 0 N 0 ;0
L 3.40480059 -0.9125 3.40013327 -0.92000069 0 N 0 ;0
L 3.40013327 -0.92000069 3.39173337 -0.92375217 0 N 0 ;0
L 3.39173337 -0.92375217 3.36933297 -0.92375217 0 N 0 ;0
L 3.44619931 -0.95749941 3.47980059 -0.88 0 N 0 ;0
L 3.51653356 -0.955 3.51653356 -0.88 0 N 0 ;0
L 3.51653356 -0.88 3.55946634 -0.955 0 N 0 ;0
L 3.55946634 -0.955 3.55946634 -0.88 0 N 0 ;0
L 3.68799911 -0.95749941 3.68613287 -0.9562497 0 N 0 ;0
L 3.68613287 -0.9562497 3.68613287 -0.9537503 0 N 0 ;0
L 3.68613287 -0.9537503 3.68799911 -0.95250059 0 N 0 ;0
L 3.68799911 -0.95250059 3.68986703 -0.9537503 0 N 0 ;0
L 3.68986703 -0.9537503 3.68986703 -0.9562497 0 N 0 ;0
L 3.68986703 -0.9562497 3.68799911 -0.95749941 0 N 0 ;0
L 3.68799911 -0.92375217 3.68613287 -0.9225001 0 N 0 ;0
L 3.68613287 -0.9225001 3.68613287 -0.92000069 0 N 0 ;0
L 3.68613287 -0.92000069 3.68799911 -0.91875089 0 N 0 ;0
L 3.68799911 -0.91875089 3.68986703 -0.92000069 0 N 0 ;0
L 3.68986703 -0.92000069 3.68986703 -0.9225001 0 N 0 ;0
L 3.68986703 -0.9225001 3.68799911 -0.92375217 0 N 0 ;0
L 3.81933297 -0.955 3.81933297 -0.88 0 N 0 ;0
L 3.81933297 -0.88 3.84266644 -0.88 0 N 0 ;0
L 3.84266644 -0.88 3.85013327 -0.88375157 0 N 0 ;0
L 3.85013327 -0.88375157 3.85480059 -0.88875049 0 N 0 ;0
L 3.85480059 -0.88875049 3.85666693 -0.89875059 0 N 0 ;0
L 3.85666693 -0.89875059 3.85480059 -0.90875079 0 N 0 ;0
L 3.85480059 -0.90875079 3.8492001 -0.91499941 0 N 0 ;0
L 3.8492001 -0.91499941 3.84266644 -0.91875089 0 N 0 ;0
L 3.84266644 -0.91875089 3.81933297 -0.91875089 0 N 0 ;0
L 3.84266644 -0.91875089 3.85666693 -0.955 0 N 0 ;0
L 3.9242001 -0.955 3.9242001 -0.88 0 N 0 ;0
L 3.9242001 -0.88 3.88966565 -0.93375 0 N 0 ;0
L 3.88966565 -0.93375 3.93633425 -0.93375 0 N 0 ;0
L 3.98799911 -0.88 3.98053228 -0.88249951 0 N 0 ;0
L 3.98053228 -0.88249951 3.97493346 -0.88875049 0 N 0 ;0
L 3.97493346 -0.88875049 3.97119931 -0.89624882 0 N 0 ;0
L 3.97119931 -0.89624882 3.9683999 -0.90625128 0 N 0 ;0
L 3.9683999 -0.90625128 3.96746673 -0.91750118 0 N 0 ;0
L 3.96746673 -0.91750118 3.9683999 -0.92875108 0 N 0 ;0
L 3.9683999 -0.92875108 3.97119931 -0.93875128 0 N 0 ;0
L 3.97119931 -0.93875128 3.97493346 -0.94625187 0 N 0 ;0
L 3.97493346 -0.94625187 3.98053228 -0.95250059 0 N 0 ;0
L 3.98053228 -0.95250059 3.98799911 -0.955 0 N 0 ;0
L 3.98799911 -0.955 3.99546585 -0.95250059 0 N 0 ;0
L 3.99546585 -0.95250059 4.00106644 -0.94625187 0 N 0 ;0
L 4.00106644 -0.94625187 4.00480059 -0.93875128 0 N 0 ;0
L 4.00480059 -0.93875128 4.0076 -0.92875108 0 N 0 ;0
L 4.0076 -0.92875108 4.00853317 -0.91750118 0 N 0 ;0
L 4.00853317 -0.91750118 4.0076 -0.90625128 0 N 0 ;0
L 4.0076 -0.90625128 4.00480059 -0.89624882 0 N 0 ;0
L 4.00480059 -0.89624882 4.00106644 -0.88875049 0 N 0 ;0
L 4.00106644 -0.88875049 3.99546585 -0.88249951 0 N 0 ;0
L 3.99546585 -0.88249951 3.98799911 -0.88 0 N 0 ;0
L 4.06299911 -0.88 4.05553228 -0.88249951 0 N 0 ;0
L 4.05553228 -0.88249951 4.04993346 -0.88875049 0 N 0 ;0
L 4.04993346 -0.88875049 4.04619931 -0.89624882 0 N 0 ;0
L 4.04619931 -0.89624882 4.0433999 -0.90625128 0 N 0 ;0
L 4.0433999 -0.90625128 4.04246673 -0.91750118 0 N 0 ;0
L 4.04246673 -0.91750118 4.0433999 -0.92875108 0 N 0 ;0
L 4.0433999 -0.92875108 4.04619931 -0.93875128 0 N 0 ;0
L 4.04619931 -0.93875128 4.04993346 -0.94625187 0 N 0 ;0
L 4.04993346 -0.94625187 4.05553228 -0.95250059 0 N 0 ;0
L 4.05553228 -0.95250059 4.06299911 -0.955 0 N 0 ;0
L 4.06299911 -0.955 4.07046585 -0.95250059 0 N 0 ;0
L 4.07046585 -0.95250059 4.07606644 -0.94625187 0 N 0 ;0
L 4.07606644 -0.94625187 4.07980059 -0.93875128 0 N 0 ;0
L 4.07980059 -0.93875128 4.0826 -0.92875108 0 N 0 ;0
L 4.0826 -0.92875108 4.08353317 -0.91750118 0 N 0 ;0
L 4.08353317 -0.91750118 4.0826 -0.90625128 0 N 0 ;0
L 4.0826 -0.90625128 4.07980059 -0.89624882 0 N 0 ;0
L 4.07980059 -0.89624882 4.07606644 -0.88875049 0 N 0 ;0
L 4.07606644 -0.88875049 4.07046585 -0.88249951 0 N 0 ;0
L 4.07046585 -0.88249951 4.06299911 -0.88 0 N 0 ;0
L 4.12026614 -0.92375217 4.1267998 -0.91499941 0 N 0 ;0
L 4.1267998 -0.91499941 4.1324003 -0.91000049 0 N 0 ;0
L 4.1324003 -0.91000049 4.13986703 -0.90750108 0 N 0 ;0
L 4.13986703 -0.90750108 4.14640069 -0.91000049 0 N 0 ;0
L 4.14640069 -0.91000049 4.15106644 -0.91499941 0 N 0 ;0
L 4.15106644 -0.91499941 4.15480059 -0.9225001 0 N 0 ;0
L 4.15480059 -0.9225001 4.15573376 -0.93125059 0 N 0 ;0
L 4.15573376 -0.93125059 4.15480059 -0.93875128 0 N 0 ;0
L 4.15480059 -0.93875128 4.15106644 -0.94625187 0 N 0 ;0
L 4.15106644 -0.94625187 4.14546585 -0.95250059 0 N 0 ;0
L 4.14546585 -0.95250059 4.13893396 -0.955 0 N 0 ;0
L 4.13893396 -0.955 4.13146713 -0.95250059 0 N 0 ;0
L 4.13146713 -0.95250059 4.12493346 -0.94500217 0 N 0 ;0
L 4.12493346 -0.94500217 4.12119931 -0.93375 0 N 0 ;0
L 4.12119931 -0.93375 4.12026614 -0.92125039 0 N 0 ;0
L 4.12026614 -0.92125039 4.12213238 -0.90500157 0 N 0 ;0
L 4.12213238 -0.90500157 4.12493346 -0.89624882 0 N 0 ;0
L 4.12493346 -0.89624882 4.12959921 -0.88750069 0 N 0 ;0
L 4.12959921 -0.88750069 4.13613287 -0.8812498 0 N 0 ;0
L 4.13613287 -0.8812498 4.14266644 -0.88 0 N 0 ;0
L 4.14266644 -0.88 4.1492001 -0.88249951 0 N 0 ;0
L 4.1492001 -0.88249951 4.15386752 -0.88875049 0 N 0 ;0
L 4.20086663 -0.93000079 4.22513327 -0.93000079 0 N 0 ;0
L 4.29546585 -0.91499941 4.2992001 -0.9112502 0 N 0 ;0
L 4.2992001 -0.9112502 4.30199951 -0.90500157 0 N 0 ;0
L 4.30199951 -0.90500157 4.30386752 -0.89624882 0 N 0 ;0
L 4.30386752 -0.89624882 4.30199951 -0.88875049 0 N 0 ;0
L 4.30199951 -0.88875049 4.29826703 -0.88375157 0 N 0 ;0
L 4.29826703 -0.88375157 4.29173337 -0.88 0 N 0 ;0
L 4.29173337 -0.88 4.26653356 -0.88 0 N 0 ;0
L 4.26653356 -0.88 4.26653356 -0.955 0 N 0 ;0
L 4.26653356 -0.955 4.29733386 -0.955 0 N 0 ;0
L 4.29733386 -0.955 4.30386752 -0.95000108 0 N 0 ;0
L 4.30386752 -0.95000108 4.3076 -0.94250039 0 N 0 ;0
L 4.3076 -0.94250039 4.30946634 -0.93375 0 N 0 ;0
L 4.30946634 -0.93375 4.3076 -0.92500187 0 N 0 ;0
L 4.3076 -0.92500187 4.30199951 -0.91750118 0 N 0 ;0
L 4.30199951 -0.91750118 4.29546585 -0.91499941 0 N 0 ;0
L 4.29546585 -0.91499941 4.26653356 -0.91499941 0 N 0 ;0
L 4.36299911 -0.88 4.35553228 -0.88249951 0 N 0 ;0
L 4.35553228 -0.88249951 4.34993346 -0.88875049 0 N 0 ;0
L 4.34993346 -0.88875049 4.34619931 -0.89624882 0 N 0 ;0
L 4.34619931 -0.89624882 4.3433999 -0.90625128 0 N 0 ;0
L 4.3433999 -0.90625128 4.34246673 -0.91750118 0 N 0 ;0
L 4.34246673 -0.91750118 4.3433999 -0.92875108 0 N 0 ;0
L 4.3433999 -0.92875108 4.34619931 -0.93875128 0 N 0 ;0
L 4.34619931 -0.93875128 4.34993346 -0.94625187 0 N 0 ;0
L 4.34993346 -0.94625187 4.35553228 -0.95250059 0 N 0 ;0
L 4.35553228 -0.95250059 4.36299911 -0.955 0 N 0 ;0
L 4.36299911 -0.955 4.37046585 -0.95250059 0 N 0 ;0
L 4.37046585 -0.95250059 4.37606644 -0.94625187 0 N 0 ;0
L 4.37606644 -0.94625187 4.37980059 -0.93875128 0 N 0 ;0
L 4.37980059 -0.93875128 4.3826 -0.92875108 0 N 0 ;0
L 4.3826 -0.92875108 4.38353317 -0.91750118 0 N 0 ;0
L 4.38353317 -0.91750118 4.3826 -0.90625128 0 N 0 ;0
L 4.3826 -0.90625128 4.37980059 -0.89624882 0 N 0 ;0
L 4.37980059 -0.89624882 4.37606644 -0.88875049 0 N 0 ;0
L 4.37606644 -0.88875049 4.37046585 -0.88249951 0 N 0 ;0
L 4.37046585 -0.88249951 4.36299911 -0.88 0 N 0 ;0
L 4.43799911 -0.88 4.43053228 -0.88249951 0 N 0 ;0
L 4.43053228 -0.88249951 4.42493346 -0.88875049 0 N 0 ;0
L 4.42493346 -0.88875049 4.42119931 -0.89624882 0 N 0 ;0
L 4.42119931 -0.89624882 4.4183999 -0.90625128 0 N 0 ;0
L 4.4183999 -0.90625128 4.41746673 -0.91750118 0 N 0 ;0
L 4.41746673 -0.91750118 4.4183999 -0.92875108 0 N 0 ;0
L 4.4183999 -0.92875108 4.42119931 -0.93875128 0 N 0 ;0
L 4.42119931 -0.93875128 4.42493346 -0.94625187 0 N 0 ;0
L 4.42493346 -0.94625187 4.43053228 -0.95250059 0 N 0 ;0
L 4.43053228 -0.95250059 4.43799911 -0.955 0 N 0 ;0
L 4.43799911 -0.955 4.44546585 -0.95250059 0 N 0 ;0
L 4.44546585 -0.95250059 4.45106644 -0.94625187 0 N 0 ;0
L 4.45106644 -0.94625187 4.45480059 -0.93875128 0 N 0 ;0
L 4.45480059 -0.93875128 4.4576 -0.92875108 0 N 0 ;0
L 4.4576 -0.92875108 4.45853317 -0.91750118 0 N 0 ;0
L 4.45853317 -0.91750118 4.4576 -0.90625128 0 N 0 ;0
L 4.4576 -0.90625128 4.45480059 -0.89624882 0 N 0 ;0
L 4.45480059 -0.89624882 4.45106644 -0.88875049 0 N 0 ;0
L 4.45106644 -0.88875049 4.44546585 -0.88249951 0 N 0 ;0
L 4.44546585 -0.88249951 4.43799911 -0.88 0 N 0 ;0
L 4.51299911 -0.88 4.50553228 -0.88249951 0 N 0 ;0
L 4.50553228 -0.88249951 4.49993346 -0.88875049 0 N 0 ;0
L 4.49993346 -0.88875049 4.49619931 -0.89624882 0 N 0 ;0
L 4.49619931 -0.89624882 4.4933999 -0.90625128 0 N 0 ;0
L 4.4933999 -0.90625128 4.49246673 -0.91750118 0 N 0 ;0
L 4.49246673 -0.91750118 4.4933999 -0.92875108 0 N 0 ;0
L 4.4933999 -0.92875108 4.49619931 -0.93875128 0 N 0 ;0
L 4.49619931 -0.93875128 4.49993346 -0.94625187 0 N 0 ;0
L 4.49993346 -0.94625187 4.50553228 -0.95250059 0 N 0 ;0
L 4.50553228 -0.95250059 4.51299911 -0.955 0 N 0 ;0
L 4.51299911 -0.955 4.52046585 -0.95250059 0 N 0 ;0
L 4.52046585 -0.95250059 4.52606644 -0.94625187 0 N 0 ;0
L 4.52606644 -0.94625187 4.52980059 -0.93875128 0 N 0 ;0
L 4.52980059 -0.93875128 4.5326 -0.92875108 0 N 0 ;0
L 4.5326 -0.92875108 4.53353317 -0.91750118 0 N 0 ;0
L 4.53353317 -0.91750118 4.5326 -0.90625128 0 N 0 ;0
L 4.5326 -0.90625128 4.52980059 -0.89624882 0 N 0 ;0
L 4.52980059 -0.89624882 4.52606644 -0.88875049 0 N 0 ;0
L 4.52606644 -0.88875049 4.52046585 -0.88249951 0 N 0 ;0
L 4.52046585 -0.88249951 4.51299911 -0.88 0 N 0 ;0
L 4.58799911 -0.955 4.58799911 -0.88 0 N 0 ;0
L 4.58799911 -0.88 4.5767998 -0.89499911 0 N 0 ;0
L 4.5767998 -0.955 4.59919843 -0.955 0 N 0 ;0
L 4.65086663 -0.93000079 4.67513327 -0.93000079 0 N 0 ;0
L 4.73799911 -0.88 4.73053228 -0.88249951 0 N 0 ;0
L 4.73053228 -0.88249951 4.72493346 -0.88875049 0 N 0 ;0
L 4.72493346 -0.88875049 4.72119931 -0.89624882 0 N 0 ;0
L 4.72119931 -0.89624882 4.7183999 -0.90625128 0 N 0 ;0
L 4.7183999 -0.90625128 4.71746673 -0.91750118 0 N 0 ;0
L 4.71746673 -0.91750118 4.7183999 -0.92875108 0 N 0 ;0
L 4.7183999 -0.92875108 4.72119931 -0.93875128 0 N 0 ;0
L 4.72119931 -0.93875128 4.72493346 -0.94625187 0 N 0 ;0
L 4.72493346 -0.94625187 4.73053228 -0.95250059 0 N 0 ;0
L 4.73053228 -0.95250059 4.73799911 -0.955 0 N 0 ;0
L 4.73799911 -0.955 4.74546585 -0.95250059 0 N 0 ;0
L 4.74546585 -0.95250059 4.75106644 -0.94625187 0 N 0 ;0
L 4.75106644 -0.94625187 4.75480059 -0.93875128 0 N 0 ;0
L 4.75480059 -0.93875128 4.7576 -0.92875108 0 N 0 ;0
L 4.7576 -0.92875108 4.75853317 -0.91750118 0 N 0 ;0
L 4.75853317 -0.91750118 4.7576 -0.90625128 0 N 0 ;0
L 4.7576 -0.90625128 4.75480059 -0.89624882 0 N 0 ;0
L 4.75480059 -0.89624882 4.75106644 -0.88875049 0 N 0 ;0
L 4.75106644 -0.88875049 4.74546585 -0.88249951 0 N 0 ;0
L 4.74546585 -0.88249951 4.73799911 -0.88 0 N 0 ;0
L 4.79526614 -0.8924997 4.80086663 -0.88500128 0 N 0 ;0
L 4.80086663 -0.88500128 4.8074003 -0.8812498 0 N 0 ;0
L 4.8074003 -0.8812498 4.81486703 -0.88 0 N 0 ;0
L 4.81486703 -0.88 4.8242001 -0.88249951 0 N 0 ;0
L 4.8242001 -0.88249951 4.83073376 -0.88875049 0 N 0 ;0
L 4.83073376 -0.88875049 4.8326 -0.89624882 0 N 0 ;0
L 4.8326 -0.89624882 4.83166693 -0.90375187 0 N 0 ;0
L 4.83166693 -0.90375187 4.82793268 -0.91000049 0 N 0 ;0
L 4.82793268 -0.91000049 4.80926654 -0.9225001 0 N 0 ;0
L 4.80926654 -0.9225001 4.80086663 -0.93125059 0 N 0 ;0
L 4.80086663 -0.93125059 4.79526614 -0.94375246 0 N 0 ;0
L 4.79526614 -0.94375246 4.7933999 -0.955 0 N 0 ;0
L 4.7933999 -0.955 4.8326 -0.955 0 N 0 ;0
L 3.36746673 -1.205 3.36746673 -1.13 0 N 0 ;0
L 3.36746673 -1.13 3.38613287 -1.13 0 N 0 ;0
L 3.38613287 -1.13 3.39359961 -1.13375157 0 N 0 ;0
L 3.39359961 -1.13375157 3.3992001 -1.13875049 0 N 0 ;0
L 3.3992001 -1.13875049 3.40386752 -1.14624882 0 N 0 ;0
L 3.40386752 -1.14624882 3.4076 -1.15500157 0 N 0 ;0
L 3.4076 -1.15500157 3.40853317 -1.16750118 0 N 0 ;0
L 3.40853317 -1.16750118 3.4076 -1.18000079 0 N 0 ;0
L 3.4076 -1.18000079 3.40386752 -1.18875128 0 N 0 ;0
L 3.40386752 -1.18875128 3.3992001 -1.19625187 0 N 0 ;0
L 3.3992001 -1.19625187 3.39359961 -1.20125089 0 N 0 ;0
L 3.39359961 -1.20125089 3.38613287 -1.205 0 N 0 ;0
L 3.38613287 -1.205 3.36746673 -1.205 0 N 0 ;0
L 3.47980059 -1.205 3.47980059 -1.15500157 0 N 0 ;0
L 3.47980059 -1.1637497 3.47606644 -1.15875079 0 N 0 ;0
L 3.47606644 -1.15875079 3.47046585 -1.15625128 0 N 0 ;0
L 3.47046585 -1.15625128 3.46393396 -1.15500157 0 N 0 ;0
L 3.46393396 -1.15500157 3.4574003 -1.15750108 0 N 0 ;0
L 3.4574003 -1.15750108 3.4517998 -1.1625 0 N 0 ;0
L 3.4517998 -1.1625 3.44806555 -1.17000069 0 N 0 ;0
L 3.44806555 -1.17000069 3.44619931 -1.18000079 0 N 0 ;0
L 3.44619931 -1.18000079 3.44806555 -1.19000098 0 N 0 ;0
L 3.44806555 -1.19000098 3.4517998 -1.19750167 0 N 0 ;0
L 3.4517998 -1.19750167 3.4574003 -1.20250059 0 N 0 ;0
L 3.4574003 -1.20250059 3.46393396 -1.205 0 N 0 ;0
L 3.46393396 -1.205 3.47046585 -1.2037503 0 N 0 ;0
L 3.47046585 -1.2037503 3.47606644 -1.20000108 0 N 0 ;0
L 3.47606644 -1.20000108 3.47980059 -1.19500217 0 N 0 ;0
L 3.53799911 -1.13 3.53799911 -1.205 0 N 0 ;0
L 3.52493346 -1.15500157 3.55106644 -1.15500157 0 N 0 ;0
L 3.59900039 -1.17125039 3.62886752 -1.17125039 0 N 0 ;0
L 3.62886752 -1.17125039 3.62606644 -1.1625 0 N 0 ;0
L 3.62606644 -1.1625 3.62140069 -1.15750108 0 N 0 ;0
L 3.62140069 -1.15750108 3.61486703 -1.15500157 0 N 0 ;0
L 3.61486703 -1.15500157 3.60833346 -1.15625128 0 N 0 ;0
L 3.60833346 -1.15625128 3.60273287 -1.16000049 0 N 0 ;0
L 3.60273287 -1.16000049 3.59900039 -1.16875089 0 N 0 ;0
L 3.59900039 -1.16875089 3.59713238 -1.17625157 0 N 0 ;0
L 3.59713238 -1.17625157 3.59713238 -1.18375 0 N 0 ;0
L 3.59713238 -1.18375 3.59900039 -1.19125069 0 N 0 ;0
L 3.59900039 -1.19125069 3.60366604 -1.19875138 0 N 0 ;0
L 3.60366604 -1.19875138 3.60926654 -1.2037503 0 N 0 ;0
L 3.60926654 -1.2037503 3.6158002 -1.205 0 N 0 ;0
L 3.6158002 -1.205 3.62233386 -1.20250059 0 N 0 ;0
L 3.62233386 -1.20250059 3.62886752 -1.19500217 0 N 0 ;0
L 3.68799911 -1.20749941 3.68613287 -1.2062497 0 N 0 ;0
L 3.68613287 -1.2062497 3.68613287 -1.2037503 0 N 0 ;0
L 3.68613287 -1.2037503 3.68799911 -1.20250059 0 N 0 ;0
L 3.68799911 -1.20250059 3.68986703 -1.2037503 0 N 0 ;0
L 3.68986703 -1.2037503 3.68986703 -1.2062497 0 N 0 ;0
L 3.68986703 -1.2062497 3.68799911 -1.20749941 0 N 0 ;0
L 3.68799911 -1.17375217 3.68613287 -1.1725001 0 N 0 ;0
L 3.68613287 -1.1725001 3.68613287 -1.17000069 0 N 0 ;0
L 3.68613287 -1.17000069 3.68799911 -1.16875089 0 N 0 ;0
L 3.68799911 -1.16875089 3.68986703 -1.17000069 0 N 0 ;0
L 3.68986703 -1.17000069 3.68986703 -1.1725001 0 N 0 ;0
L 3.68986703 -1.1725001 3.68799911 -1.17375217 0 N 0 ;0
L 3.82026614 -1.1424997 3.82586663 -1.13500128 0 N 0 ;0
L 3.82586663 -1.13500128 3.8324003 -1.1312498 0 N 0 ;0
L 3.8324003 -1.1312498 3.83986703 -1.13 0 N 0 ;0
L 3.83986703 -1.13 3.8492001 -1.13249951 0 N 0 ;0
L 3.8492001 -1.13249951 3.85573376 -1.13875049 0 N 0 ;0
L 3.85573376 -1.13875049 3.8576 -1.14624882 0 N 0 ;0
L 3.8576 -1.14624882 3.85666693 -1.15375187 0 N 0 ;0
L 3.85666693 -1.15375187 3.85293268 -1.16000049 0 N 0 ;0
L 3.85293268 -1.16000049 3.83426654 -1.1725001 0 N 0 ;0
L 3.83426654 -1.1725001 3.82586663 -1.18125059 0 N 0 ;0
L 3.82586663 -1.18125059 3.82026614 -1.19375246 0 N 0 ;0
L 3.82026614 -1.19375246 3.8183999 -1.205 0 N 0 ;0
L 3.8183999 -1.205 3.8576 -1.205 0 N 0 ;0
L 3.91299911 -1.13 3.90553228 -1.13249951 0 N 0 ;0
L 3.90553228 -1.13249951 3.89993346 -1.13875049 0 N 0 ;0
L 3.89993346 -1.13875049 3.89619931 -1.14624882 0 N 0 ;0
L 3.89619931 -1.14624882 3.8933999 -1.15625128 0 N 0 ;0
L 3.8933999 -1.15625128 3.89246673 -1.16750118 0 N 0 ;0
L 3.89246673 -1.16750118 3.8933999 -1.17875108 0 N 0 ;0
L 3.8933999 -1.17875108 3.89619931 -1.18875128 0 N 0 ;0
L 3.89619931 -1.18875128 3.89993346 -1.19625187 0 N 0 ;0
L 3.89993346 -1.19625187 3.90553228 -1.20250059 0 N 0 ;0
L 3.90553228 -1.20250059 3.91299911 -1.205 0 N 0 ;0
L 3.91299911 -1.205 3.92046585 -1.20250059 0 N 0 ;0
L 3.92046585 -1.20250059 3.92606644 -1.19625187 0 N 0 ;0
L 3.92606644 -1.19625187 3.92980059 -1.18875128 0 N 0 ;0
L 3.92980059 -1.18875128 3.9326 -1.17875108 0 N 0 ;0
L 3.9326 -1.17875108 3.93353317 -1.16750118 0 N 0 ;0
L 3.93353317 -1.16750118 3.9326 -1.15625128 0 N 0 ;0
L 3.9326 -1.15625128 3.92980059 -1.14624882 0 N 0 ;0
L 3.92980059 -1.14624882 3.92606644 -1.13875049 0 N 0 ;0
L 3.92606644 -1.13875049 3.92046585 -1.13249951 0 N 0 ;0
L 3.92046585 -1.13249951 3.91299911 -1.13 0 N 0 ;0
L 3.97026614 -1.1424997 3.97586663 -1.13500128 0 N 0 ;0
L 3.97586663 -1.13500128 3.9824003 -1.1312498 0 N 0 ;0
L 3.9824003 -1.1312498 3.98986703 -1.13 0 N 0 ;0
L 3.98986703 -1.13 3.9992001 -1.13249951 0 N 0 ;0
L 3.9992001 -1.13249951 4.00573376 -1.13875049 0 N 0 ;0
L 4.00573376 -1.13875049 4.0076 -1.14624882 0 N 0 ;0
L 4.0076 -1.14624882 4.00666693 -1.15375187 0 N 0 ;0
L 4.00666693 -1.15375187 4.00293268 -1.16000049 0 N 0 ;0
L 4.00293268 -1.16000049 3.98426654 -1.1725001 0 N 0 ;0
L 3.98426654 -1.1725001 3.97586663 -1.18125059 0 N 0 ;0
L 3.97586663 -1.18125059 3.97026614 -1.19375246 0 N 0 ;0
L 3.97026614 -1.19375246 3.9683999 -1.205 0 N 0 ;0
L 3.9683999 -1.205 4.0076 -1.205 0 N 0 ;0
L 4.04526614 -1.1424997 4.05086663 -1.13500128 0 N 0 ;0
L 4.05086663 -1.13500128 4.0574003 -1.1312498 0 N 0 ;0
L 4.0574003 -1.1312498 4.06486703 -1.13 0 N 0 ;0
L 4.06486703 -1.13 4.0742001 -1.13249951 0 N 0 ;0
L 4.0742001 -1.13249951 4.08073376 -1.13875049 0 N 0 ;0
L 4.08073376 -1.13875049 4.0826 -1.14624882 0 N 0 ;0
L 4.0826 -1.14624882 4.08166693 -1.15375187 0 N 0 ;0
L 4.08166693 -1.15375187 4.07793268 -1.16000049 0 N 0 ;0
L 4.07793268 -1.16000049 4.05926654 -1.1725001 0 N 0 ;0
L 4.05926654 -1.1725001 4.05086663 -1.18125059 0 N 0 ;0
L 4.05086663 -1.18125059 4.04526614 -1.19375246 0 N 0 ;0
L 4.04526614 -1.19375246 4.0433999 -1.205 0 N 0 ;0
L 4.0433999 -1.205 4.0826 -1.205 0 N 0 ;0
L 4.12586663 -1.18000079 4.15013327 -1.18000079 0 N 0 ;0
L 4.21299911 -1.13 4.20553228 -1.13249951 0 N 0 ;0
L 4.20553228 -1.13249951 4.19993346 -1.13875049 0 N 0 ;0
L 4.19993346 -1.13875049 4.19619931 -1.14624882 0 N 0 ;0
L 4.19619931 -1.14624882 4.1933999 -1.15625128 0 N 0 ;0
L 4.1933999 -1.15625128 4.19246673 -1.16750118 0 N 0 ;0
L 4.19246673 -1.16750118 4.1933999 -1.17875108 0 N 0 ;0
L 4.1933999 -1.17875108 4.19619931 -1.18875128 0 N 0 ;0
L 4.19619931 -1.18875128 4.19993346 -1.19625187 0 N 0 ;0
L 4.19993346 -1.19625187 4.20553228 -1.20250059 0 N 0 ;0
L 4.20553228 -1.20250059 4.21299911 -1.205 0 N 0 ;0
L 4.21299911 -1.205 4.22046585 -1.20250059 0 N 0 ;0
L 4.22046585 -1.20250059 4.22606644 -1.19625187 0 N 0 ;0
L 4.22606644 -1.19625187 4.22980059 -1.18875128 0 N 0 ;0
L 4.22980059 -1.18875128 4.2326 -1.17875108 0 N 0 ;0
L 4.2326 -1.17875108 4.23353317 -1.16750118 0 N 0 ;0
L 4.23353317 -1.16750118 4.2326 -1.15625128 0 N 0 ;0
L 4.2326 -1.15625128 4.22980059 -1.14624882 0 N 0 ;0
L 4.22980059 -1.14624882 4.22606644 -1.13875049 0 N 0 ;0
L 4.22606644 -1.13875049 4.22046585 -1.13249951 0 N 0 ;0
L 4.22046585 -1.13249951 4.21299911 -1.13 0 N 0 ;0
L 4.27026614 -1.1424997 4.27586663 -1.13500128 0 N 0 ;0
L 4.27586663 -1.13500128 4.2824003 -1.1312498 0 N 0 ;0
L 4.2824003 -1.1312498 4.28986703 -1.13 0 N 0 ;0
L 4.28986703 -1.13 4.2992001 -1.13249951 0 N 0 ;0
L 4.2992001 -1.13249951 4.30573376 -1.13875049 0 N 0 ;0
L 4.30573376 -1.13875049 4.3076 -1.14624882 0 N 0 ;0
L 4.3076 -1.14624882 4.30666693 -1.15375187 0 N 0 ;0
L 4.30666693 -1.15375187 4.30293268 -1.16000049 0 N 0 ;0
L 4.30293268 -1.16000049 4.28426654 -1.1725001 0 N 0 ;0
L 4.28426654 -1.1725001 4.27586663 -1.18125059 0 N 0 ;0
L 4.27586663 -1.18125059 4.27026614 -1.19375246 0 N 0 ;0
L 4.27026614 -1.19375246 4.2683999 -1.205 0 N 0 ;0
L 4.2683999 -1.205 4.3076 -1.205 0 N 0 ;0
L 4.35086663 -1.18000079 4.37513327 -1.18000079 0 N 0 ;0
L 4.42026614 -1.1424997 4.42586663 -1.13500128 0 N 0 ;0
L 4.42586663 -1.13500128 4.4324003 -1.1312498 0 N 0 ;0
L 4.4324003 -1.1312498 4.43986703 -1.13 0 N 0 ;0
L 4.43986703 -1.13 4.4492001 -1.13249951 0 N 0 ;0
L 4.4492001 -1.13249951 4.45573376 -1.13875049 0 N 0 ;0
L 4.45573376 -1.13875049 4.4576 -1.14624882 0 N 0 ;0
L 4.4576 -1.14624882 4.45666693 -1.15375187 0 N 0 ;0
L 4.45666693 -1.15375187 4.45293268 -1.16000049 0 N 0 ;0
L 4.45293268 -1.16000049 4.43426654 -1.1725001 0 N 0 ;0
L 4.43426654 -1.1725001 4.42586663 -1.18125059 0 N 0 ;0
L 4.42586663 -1.18125059 4.42026614 -1.19375246 0 N 0 ;0
L 4.42026614 -1.19375246 4.4183999 -1.205 0 N 0 ;0
L 4.4183999 -1.205 4.4576 -1.205 0 N 0 ;0
L 4.49246673 -1.19375246 4.49806555 -1.20000108 0 N 0 ;0
L 4.49806555 -1.20000108 4.50459921 -1.2037503 0 N 0 ;0
L 4.50459921 -1.2037503 4.51299911 -1.205 0 N 0 ;0
L 4.51299911 -1.205 4.52140069 -1.20250059 0 N 0 ;0
L 4.52140069 -1.20250059 4.52793268 -1.19750167 0 N 0 ;0
L 4.52793268 -1.19750167 4.5326 -1.18875128 0 N 0 ;0
L 4.5326 -1.18875128 4.53353317 -1.17875108 0 N 0 ;0
L 4.53353317 -1.17875108 4.53166693 -1.16875089 0 N 0 ;0
L 4.53166693 -1.16875089 4.52699951 -1.1625 0 N 0 ;0
L 4.52699951 -1.1625 4.52046585 -1.15750108 0 N 0 ;0
L 4.52046585 -1.15750108 4.51393396 -1.15625128 0 N 0 ;0
L 4.51393396 -1.15625128 4.5074003 -1.15750108 0 N 0 ;0
L 4.5074003 -1.15750108 4.49900039 -1.1625 0 N 0 ;0
L 4.49900039 -1.1625 4.5017998 -1.13 0 N 0 ;0
L 4.5017998 -1.13 4.52699951 -1.13 0 N 0 ;0
L 3.29433297 -1.255 3.29433297 -1.33 0 N 0 ;0
L 3.29433297 -1.33 3.33166693 -1.33 0 N 0 ;0
L 3.40480059 -1.33 3.40480059 -1.28000157 0 N 0 ;0
L 3.40480059 -1.2887497 3.40106644 -1.28375079 0 N 0 ;0
L 3.40106644 -1.28375079 3.39546585 -1.28125128 0 N 0 ;0
L 3.39546585 -1.28125128 3.38893396 -1.28000157 0 N 0 ;0
L 3.38893396 -1.28000157 3.3824003 -1.28250108 0 N 0 ;0
L 3.3824003 -1.28250108 3.3767998 -1.2875 0 N 0 ;0
L 3.3767998 -1.2875 3.37306555 -1.29500069 0 N 0 ;0
L 3.37306555 -1.29500069 3.37119931 -1.30500079 0 N 0 ;0
L 3.37119931 -1.30500079 3.37306555 -1.31500098 0 N 0 ;0
L 3.37306555 -1.31500098 3.3767998 -1.32250167 0 N 0 ;0
L 3.3767998 -1.32250167 3.3824003 -1.32750059 0 N 0 ;0
L 3.3824003 -1.32750059 3.38893396 -1.33 0 N 0 ;0
L 3.38893396 -1.33 3.39546585 -1.3287503 0 N 0 ;0
L 3.39546585 -1.3287503 3.40106644 -1.32500108 0 N 0 ;0
L 3.40106644 -1.32500108 3.40480059 -1.32000217 0 N 0 ;0
L 3.4433999 -1.3524997 3.44900039 -1.35499921 0 N 0 ;0
L 3.44900039 -1.35499921 3.45646713 -1.3524997 0 N 0 ;0
L 3.45646713 -1.3524997 3.46113287 -1.34750079 0 N 0 ;0
L 3.46113287 -1.34750079 3.46486703 -1.3412498 0 N 0 ;0
L 3.46486703 -1.3412498 3.47046585 -1.32125187 0 N 0 ;0
L 3.47046585 -1.32125187 3.4826 -1.28000157 0 N 0 ;0
L 3.45273287 -1.28000157 3.47046585 -1.32125187 0 N 0 ;0
L 3.52400039 -1.29625039 3.55386752 -1.29625039 0 N 0 ;0
L 3.55386752 -1.29625039 3.55106644 -1.2875 0 N 0 ;0
L 3.55106644 -1.2875 3.54640069 -1.28250108 0 N 0 ;0
L 3.54640069 -1.28250108 3.53986703 -1.28000157 0 N 0 ;0
L 3.53986703 -1.28000157 3.53333346 -1.28125128 0 N 0 ;0
L 3.53333346 -1.28125128 3.52773287 -1.28500049 0 N 0 ;0
L 3.52773287 -1.28500049 3.52400039 -1.29375089 0 N 0 ;0
L 3.52400039 -1.29375089 3.52213238 -1.30125157 0 N 0 ;0
L 3.52213238 -1.30125157 3.52213238 -1.30875 0 N 0 ;0
L 3.52213238 -1.30875 3.52400039 -1.31625069 0 N 0 ;0
L 3.52400039 -1.31625069 3.52866604 -1.32375138 0 N 0 ;0
L 3.52866604 -1.32375138 3.53426654 -1.3287503 0 N 0 ;0
L 3.53426654 -1.3287503 3.5408002 -1.33 0 N 0 ;0
L 3.5408002 -1.33 3.54733386 -1.32750059 0 N 0 ;0
L 3.54733386 -1.32750059 3.55386752 -1.32000217 0 N 0 ;0
L 3.59993346 -1.33 3.59993346 -1.28000157 0 N 0 ;0
L 3.59993346 -1.28999941 3.60459921 -1.28500049 0 N 0 ;0
L 3.60459921 -1.28500049 3.60926654 -1.28125128 0 N 0 ;0
L 3.60926654 -1.28125128 3.6158002 -1.28000157 0 N 0 ;0
L 3.6158002 -1.28000157 3.62046585 -1.28125128 0 N 0 ;0
L 3.62046585 -1.28125128 3.62606644 -1.28500049 0 N 0 ;0
L 3.68799911 -1.33249941 3.68613287 -1.3312497 0 N 0 ;0
L 3.68613287 -1.3312497 3.68613287 -1.3287503 0 N 0 ;0
L 3.68613287 -1.3287503 3.68799911 -1.32750059 0 N 0 ;0
L 3.68799911 -1.32750059 3.68986703 -1.3287503 0 N 0 ;0
L 3.68986703 -1.3287503 3.68986703 -1.3312497 0 N 0 ;0
L 3.68986703 -1.3312497 3.68799911 -1.33249941 0 N 0 ;0
L 3.68799911 -1.29875217 3.68613287 -1.2975001 0 N 0 ;0
L 3.68613287 -1.2975001 3.68613287 -1.29500069 0 N 0 ;0
L 3.68613287 -1.29500069 3.68799911 -1.29375089 0 N 0 ;0
L 3.68799911 -1.29375089 3.68986703 -1.29500069 0 N 0 ;0
L 3.68986703 -1.29500069 3.68986703 -1.2975001 0 N 0 ;0
L 3.68986703 -1.2975001 3.68799911 -1.29875217 0 N 0 ;0
L 3.36933297 -1.08 3.36933297 -1.005 0 N 0 ;0
L 3.36933297 -1.005 3.39266644 -1.005 0 N 0 ;0
L 3.39266644 -1.005 3.40013327 -1.00875157 0 N 0 ;0
L 3.40013327 -1.00875157 3.40480059 -1.01375049 0 N 0 ;0
L 3.40480059 -1.01375049 3.40666693 -1.02375059 0 N 0 ;0
L 3.40666693 -1.02375059 3.40480059 -1.03375079 0 N 0 ;0
L 3.40480059 -1.03375079 3.3992001 -1.03999941 0 N 0 ;0
L 3.3992001 -1.03999941 3.39266644 -1.04375089 0 N 0 ;0
L 3.39266644 -1.04375089 3.36933297 -1.04375089 0 N 0 ;0
L 3.39266644 -1.04375089 3.40666693 -1.08 0 N 0 ;0
L 3.44900039 -1.04625039 3.47886752 -1.04625039 0 N 0 ;0
L 3.47886752 -1.04625039 3.47606644 -1.0375 0 N 0 ;0
L 3.47606644 -1.0375 3.47140069 -1.03250108 0 N 0 ;0
L 3.47140069 -1.03250108 3.46486703 -1.03000157 0 N 0 ;0
L 3.46486703 -1.03000157 3.45833346 -1.03125128 0 N 0 ;0
L 3.45833346 -1.03125128 3.45273287 -1.03500049 0 N 0 ;0
L 3.45273287 -1.03500049 3.44900039 -1.04375089 0 N 0 ;0
L 3.44900039 -1.04375089 3.44713238 -1.05125157 0 N 0 ;0
L 3.44713238 -1.05125157 3.44713238 -1.05875 0 N 0 ;0
L 3.44713238 -1.05875 3.44900039 -1.06625069 0 N 0 ;0
L 3.44900039 -1.06625069 3.45366604 -1.07375138 0 N 0 ;0
L 3.45366604 -1.07375138 3.45926654 -1.0787503 0 N 0 ;0
L 3.45926654 -1.0787503 3.4658002 -1.08 0 N 0 ;0
L 3.4658002 -1.08 3.47233386 -1.07750059 0 N 0 ;0
L 3.47233386 -1.07750059 3.47886752 -1.07000217 0 N 0 ;0
L 3.52119931 -1.03000157 3.53799911 -1.08 0 N 0 ;0
L 3.53799911 -1.08 3.55480059 -1.03000157 0 N 0 ;0
L 3.68799911 -1.08249941 3.68613287 -1.0812497 0 N 0 ;0
L 3.68613287 -1.0812497 3.68613287 -1.0787503 0 N 0 ;0
L 3.68613287 -1.0787503 3.68799911 -1.07750059 0 N 0 ;0
L 3.68799911 -1.07750059 3.68986703 -1.0787503 0 N 0 ;0
L 3.68986703 -1.0787503 3.68986703 -1.0812497 0 N 0 ;0
L 3.68986703 -1.0812497 3.68799911 -1.08249941 0 N 0 ;0
L 3.68799911 -1.04875217 3.68613287 -1.0475001 0 N 0 ;0
L 3.68613287 -1.0475001 3.68613287 -1.04500069 0 N 0 ;0
L 3.68613287 -1.04500069 3.68799911 -1.04375089 0 N 0 ;0
L 3.68799911 -1.04375089 3.68986703 -1.04500069 0 N 0 ;0
L 3.68986703 -1.04500069 3.68986703 -1.0475001 0 N 0 ;0
L 3.68986703 -1.0475001 3.68799911 -1.04875217 0 N 0 ;0
L 3.83799911 -1.005 3.83053228 -1.00749951 0 N 0 ;0
L 3.83053228 -1.00749951 3.82493346 -1.01375049 0 N 0 ;0
L 3.82493346 -1.01375049 3.82119931 -1.02124882 0 N 0 ;0
L 3.82119931 -1.02124882 3.8183999 -1.03125128 0 N 0 ;0
L 3.8183999 -1.03125128 3.81746673 -1.04250118 0 N 0 ;0
L 3.81746673 -1.04250118 3.8183999 -1.05375108 0 N 0 ;0
L 3.8183999 -1.05375108 3.82119931 -1.06375128 0 N 0 ;0
L 3.82119931 -1.06375128 3.82493346 -1.07125187 0 N 0 ;0
L 3.82493346 -1.07125187 3.83053228 -1.07750059 0 N 0 ;0
L 3.83053228 -1.07750059 3.83799911 -1.08 0 N 0 ;0
L 3.83799911 -1.08 3.84546585 -1.07750059 0 N 0 ;0
L 3.84546585 -1.07750059 3.85106644 -1.07125187 0 N 0 ;0
L 3.85106644 -1.07125187 3.85480059 -1.06375128 0 N 0 ;0
L 3.85480059 -1.06375128 3.8576 -1.05375108 0 N 0 ;0
L 3.8576 -1.05375108 3.85853317 -1.04250118 0 N 0 ;0
L 3.85853317 -1.04250118 3.8576 -1.03125128 0 N 0 ;0
L 3.8576 -1.03125128 3.85480059 -1.02124882 0 N 0 ;0
L 3.85480059 -1.02124882 3.85106644 -1.01375049 0 N 0 ;0
L 3.85106644 -1.01375049 3.84546585 -1.00749951 0 N 0 ;0
L 3.84546585 -1.00749951 3.83799911 -1.005 0 N 0 ;0
L 3.91299911 -1.08 3.91299911 -1.005 0 N 0 ;0
L 3.91299911 -1.005 3.9017998 -1.01999911 0 N 0 ;0
L 3.9017998 -1.08 3.92419843 -1.08 0 N 0 ;0

### steps/pcb/layers/l08_sig2/features
#
#Num Features
#
F 4967

#
#Units
#
U INCH

#
#Feature symbol names
#
$0 r3.5
$1 r4
$2 r4.5
$3 r4.6
$4 r5
$5 r6
$6 r6.2
$7 r10
$8 r15
$9 r18
$10 r20
$11 r24

#
#Feature attribute names
#
@0 .nomenclature
@1 .geometry
@2 .string
@3 .pad_usage
@4 .string_angle

#
#Feature attribute text strings
#
&0 V010C020P_TP030B
&1 V008C018P-ANTI28-NSM
&2 V010C020P
&3 TPV010CT020B030
&4 V008C018P_ANTI026_TP030B
&5 V008C018P_NATI28_TP030B_NSMT
&6 016C024P
&7 V008C018P_TP030B
&8 V008C018P
&9 V008C018P_ANTI28
&10 059C086P
&11 V008C018P_ANTI026_NSM
&12 076S104P
&13 076C104P
&14 079C100P
&15 V010C020P_SM014-NTH
&16 V012C024-NTH
&17 024X063OB035X075P
&18 166CT244CB198P
&19 024X051OB071X075P_R
&20 024X051OB071X075P_L
&21 033C057P
&22 063C090P
&23 L08_SIG2
&24 MTH100C090N
&25 MTH125C115N
&26 MTH118C108N
&27 P/N : R4006-B0001-02
&28 Date: 2022-02-25
&29 Layer:
&30 Rev : 01

#
#Layer features
#
L 4.61 2.3 4.605 2.305 4 P 0 
L 4.605 2.305 4.575 2.305 4 P 0 
L 4.575 2.305 4.485 2.215 4 P 0 
L 4.485 2.215 4.485 2.07681004 4 P 0 
L 4.485 2.07681004 4.50185 2.05996004 4 P 0 
P 4.61 2.3 10 P 0 8 0;1=0,3=1
P 4.50185 2.05996004 9 P 0 8 0;1=1,3=1
L 3.65 2.68 3.64 2.69 4 P 0 
L 3.64 2.69 3.5566 2.69 4 P 0 
L 3.5566 2.69 3.5441 2.7025 4 P 0 
L 3.5441 2.7025 3.35291998 2.7025 4 P 0 
L 3.35291998 2.7025 3.34 2.68958002 4 P 0 
L 3.34 2.68958002 3.34 2.635 4 P 0 
L 3.34 2.635 3.325 2.62 4 P 0 
L 3.325 2.62 3.2639 2.62 4 P 0 
L 3.2639 2.62 3.2439 2.6 4 P 0 
L 3.2439 2.6 3.165 2.6 4 P 0 
L 3.165 2.6 3.12 2.645 4 P 0 
P 3.65 2.68 10 P 0 8 0;1=2,3=1
P 3.12 2.645 10 P 0 8 0;1=2,3=1
L 4.1869 2.09933002 4.205 2.11743002 4 P 0 
L 4.205 2.11743002 4.205 2.2084 4 P 0 
L 4.205 2.2084 4.1125 2.3009 4 P 0 
L 4.1125 2.3009 4.1125 2.55421004 4 P 0 
L 4.1125 2.55421004 4.05121004 2.6155 4 P 0 
L 4.05121004 2.6155 4.00451004 2.6155 4 P 0 
L 4.00451004 2.6155 3.93001004 2.69 4 P 0 
L 3.93001004 2.69 3.765 2.69 4 P 0 
P 4.1869 2.09933002 9 P 0 8 0;1=1,3=1
P 3.765 2.69 10 P 0 8 0;1=0,3=1
S P 0
OB 1.412630019685 3.74 I
OS 1.415 3.74
OS 1.450330019685 3.704669980315
OS 1.45021003937 3.7037
OC 1.449980019685 3.7 1.479999409449 3.699990944882 N
OC 1.48 3.669980019685 1.48 3.7 N
OC 1.4837 3.67021003937 1.479990944882 3.699999409449 N
OS 1.484669980315 3.670330019685
OS 1.49 3.665
OS 1.49 3.596619980315
OC 1.484980019685 3.58 1.515002362205 3.58 N
OC 1.514230019685 3.54998996063 1.514999901575 3.58 N
OS 1.515030019685 3.549969980315
OS 1.560969980315 3.504030019685
OS 1.56098996063 3.503230019685
OC 1.590230019685 3.47398996063 1.591 3.504 N
OS 1.591030019685 3.473969980315
OS 1.63 3.435
OS 1.63 3.17
OS 1.57075 3.11075
OC 1.56405 3.112569980315 1.567920767717 3.113577165354 Y
OC 1.535 3.135019980315 1.535 3.10499980315 N
OC 1.51793996063 3.1297 1.534999901575 3.105006299213 N
OC 1.495 3.14036003937 1.494999901575 3.110346948819 N
OC 1.46563996063 3.1166 1.495 3.110340059055 N
OS 1.4653 3.115019980315
OS 1.38401003937 3.115019980315
OC 1.38001003937 3.119130019685 1.384005511811 3.119017027559 Y
OC 1.380019980315 3.12 1.349998917323 3.119907972441 N
OC 1.319980019685 3.12 1.35 3.12 N
OC 1.31998996063 3.119130019685 1.350001082677 3.119907972441 N
OC 1.31598996063 3.115019980315 1.315994488189 3.119017027559 Y
OS 1.31498996063 3.115019980315
OS 1.3 3.13
OS 0.97463996063 3.13
OS 0.97428996063 3.13156003937
OC 0.91571003937 3.13156003937 0.945 3.125005610236 N
OS 0.91536003937 3.13
OS 0.835 3.13
OS 0.81361003937 3.10861003937
OS 0.81223996063 3.109580019685
OC 0.795 3.115019980315 0.79500511811 3.084998425197 N
OC 0.76571003937 3.09156003937 0.795 3.085005610236 N
OS 0.76536003937 3.09
OS 0.64238996063 3.09
OC 0.59761003937 3.09 0.62 3.069994389764 N
OS 0.535 3.09
OS 0.45 3.175
OS 0.43106003937 3.175
OC 0.43 3.175019980315 0.429964370079 3.145000688976 N
OC 0.42893996063 3.175 0.430035629921 3.145000688976 N
OS 0.39 3.175
OS 0.307380019685 3.257619980315
OS 0.307869980315 3.25883996063
OC 0.310019980315 3.27 0.279999311024 3.269996456693 N
OC 0.28 3.300019980315 0.28 3.27 N
OC 0.25906003937 3.29151003937 0.28 3.270002165354 N
OC 0.25345 3.29155 0.256275295276 3.294381397638 Y
OS 0.25 3.295
OS 0.25 3.32233996063
OS 0.268069980315 3.32233996063
OC 0.305580019685 3.35985 0.268069980315 3.35985 N
OC 0.3002 3.37921003937 0.268056397638 3.35985 N
OC 0.30275 3.385169980315 0.303629133858 3.381268307087 Y
OC 0.3134 3.39335 0.29921476378 3.400795570866 N
OC 0.320480019685 3.39335 0.316940059055 3.391483956693 Y
OC 0.34883996063 3.39335 0.33466003937 3.400796161417 N
OC 0.355919980315 3.39335 0.352380019685 3.391483956693 Y
OC 0.3701 3.384780019685 0.370099901575 3.400796161417 N
OC 0.386119980315 3.4008 0.3701 3.4008 N
OC 0.38363996063 3.40936003937 0.370107086614 3.4008 N
OC 0.387180019685 3.41548996063 0.387022145669 3.411493996063 Y
OC 0.387819980315 3.415480019685 0.387748818898 3.431501082677 N
OC 0.387819980315 3.447519980315 0.387819980315 3.4315 N
OC 0.37363996063 3.43895 0.38781988189 3.431503838583 N
OC 0.36656003937 3.43895 0.3701 3.440816043307 Y
OC 0.3382 3.43895 0.352380019685 3.431503838583 N
OC 0.331119980315 3.43895 0.33466003937 3.440816043307 Y
OC 0.31693996063 3.447519980315 0.316940059055 3.431503838583 N
OC 0.300919980315 3.4315 0.31693996063 3.4315 N
OC 0.3034 3.42293996063 0.316932874016 3.4315 N
OC 0.29986003937 3.41681003937 0.300017814961 3.420806003937 Y
OC 0.299219980315 3.416819980315 0.299291240157 3.400798917323 N
OC 0.2832 3.4008 0.299219980315 3.4008 N
OC 0.283219980315 3.400030019685 0.299219192913 3.400830413386 N
OC 0.27815 3.39598996063 0.279225688976 3.399841338583 Y
OC 0.268069980315 3.39736003937 0.268104133858 3.359845374016 N
OS 0.25 3.39736003937
OS 0.25 3.41591003937
OS 0.25133996063 3.416380019685
OC 0.262069980315 3.43105 0.246059153543 3.431501673228 N
OC 0.266069980315 3.43493996063 0.266070964567 3.430937401575 Y
OS 0.268069980315 3.43493996063
OC 0.305580019685 3.47245 0.268069980315 3.47245 N
OC 0.29975 3.49253996063 0.268068503937 3.472455216535 N
OS 0.29888996063 3.49388996063
OS 0.31748996063 3.512480019685
OS 0.375 3.512480019685
OC 0.377630019685 3.51263996063 0.374950492126 3.534996948819 N
OC 0.37985 3.51091003937 0.377866338583 3.510653838583 Y
OC 0.41705 3.47823996063 0.41705 3.515754035433 N
OS 0.45705 3.47823996063
OC 0.49451003937 3.51378996063 0.45705 3.515751279528 N
OS 0.49455 3.51455
OS 0.51851003937 3.53851003937
OC 0.52471003937 3.537830019685 0.521336811024 3.535679232283 Y
OC 0.55 3.523980019685 0.55 3.553994685039 N
OC 0.58001003937 3.55306003937 0.550000098425 3.554004822835 N
OS 0.580069980315 3.555
OS 0.64 3.555
OS 0.7 3.495
OS 0.76151003937 3.495
OC 0.76545 3.49028996063 0.761513779528 3.49100019685 Y
OC 0.764980019685 3.485 0.794999901575 3.484998818898 N
OC 0.795 3.454980019685 0.795 3.485 N
OC 0.79633996063 3.45501003937 0.79499773622 3.485 N
OC 0.80045 3.45031003937 0.796514074803 3.451015255906 Y
OC 0.80031003937 3.44945 0.830008464567 3.445058366142 N
OC 0.798130019685 3.44776003937 0.798334251969 3.449747637795 Y
OC 0.795 3.447919980315 0.79503503937 3.417898228346 N
OC 0.795 3.387880019685 0.795 3.4179 N
OS 0.79505 3.387880019685
OC 0.825 3.359980019685 0.825 3.390005314961 N
OC 0.855019980315 3.39 0.825 3.39 N
OC 0.844669980315 3.412680019685 0.824995570866 3.39 N
OC 0.84526003937 3.41915 0.847289074803 3.415703051181 Y
OC 0.860019980315 3.445 0.830003740157 3.445 N
OC 0.83 3.475019980315 0.83 3.445 N
OC 0.82866003937 3.47498996063 0.83000226378 3.445 N
OC 0.82455 3.47968996063 0.828485925197 3.478984744094 Y
OC 0.825019980315 3.485 0.794998326772 3.484981299213 N
OC 0.82455 3.49028996063 0.795000098425 3.484998818898 N
OC 0.82848996063 3.495 0.828486220472 3.49100019685 Y
OS 0.82893996063 3.495
OC 0.83 3.494980019685 0.830035629921 3.524999311024 N
OC 0.83106003937 3.495 0.829964370079 3.524999311024 N
OS 0.932969980315 3.495
OC 0.951 3.488980019685 0.950999901575 3.518990059055 N
OC 0.95961003937 3.49023996063 0.951004133858 3.519000590551 N
OC 0.96205 3.48905 0.960186220472 3.48832480315 Y
OC 0.99 3.469980019685 0.99 3.49999753937 N
OC 1.004480019685 3.4737 0.990005216535 3.500001377953 N
OC 1.010380019685 3.470680019685 1.006411220472 3.470199606299 Y
OC 1.04018996063 3.444230019685 1.040190059055 3.474253444882 N
OC 1.07021003937 3.47425 1.040190059055 3.47425 N
OC 1.0559 3.499830019685 1.040192125984 3.47425 N
OC 1.060019980315 3.515 1.030002165354 3.515007972441 N
OC 1.03 3.545019980315 1.03 3.515 N
OC 1.02028996063 3.54341003937 1.029989173228 3.514998228346 N
OC 1.015 3.54718996063 1.018998425197 3.547194192913 Y
OS 1.015 3.57
OS 1.05626003937 3.61126003937
OS 1.057369980315 3.610969980315
OC 1.065 3.609980019685 1.065015452756 3.639997933071 N
OC 1.0825 3.61561003937 1.065 3.639993011811 N
OC 1.1 3.609980019685 1.1 3.639993011811 N
OC 1.130019980315 3.64 1.1 3.64 N
OC 1.1167 3.66495 1.099992814961 3.64 N
OC 1.1161 3.6711 1.118926377953 3.668271456693 Y
OS 1.16315 3.71815
OC 1.169980019685 3.71528996063 1.165980905512 3.71532519685 Y
OS 1.169980019685 3.715
OC 1.17561003937 3.6975 1.199993011811 3.715 N
OC 1.17561003937 3.6625 1.199993011811 3.68 N
OC 1.169980019685 3.645 1.199993011811 3.645 N
OC 1.230019980315 3.645 1.2 3.645 N
OC 1.22438996063 3.6625 1.200006988189 3.645 N
OC 1.22438996063 3.6975 1.200006988189 3.68 N
OC 1.230019980315 3.715 1.200006988189 3.715 N
OC 1.223619980315 3.733530019685 1.19999488189 3.715 N
OC 1.22676003937 3.74 1.226764862205 3.736000688976 Y
OS 1.294 3.74
OC 1.29528996063 3.73795 1.320031791339 3.754949606299 N
OC 1.293419980315 3.734819980315 1.293647047244 3.736807972441 Y
OC 1.29 3.735019980315 1.289960433071 3.705002362205 N
OC 1.259980019685 3.705 1.29 3.705 N
OC 1.272330019685 3.680730019685 1.29000246063 3.705 N
OC 1.272330019685 3.674269980315 1.269972834646 3.6775 Y
OC 1.259980019685 3.65 1.29000246063 3.65 N
OC 1.320019980315 3.65 1.29 3.65 N
OC 1.307669980315 3.674269980315 1.28999753937 3.65 N
OC 1.307669980315 3.680730019685 1.310027165354 3.6775 Y
OC 1.320019980315 3.705 1.28999753937 3.705 N
OC 1.3165 3.7191 1.290001181102 3.704995374016 N
OC 1.320030019685 3.724980019685 1.320031397638 3.720979527559 Y
OC 1.346 3.74 1.319996751969 3.754998917323 N
OS 1.352369980315 3.74
OC 1.356019980315 3.734369980315 1.352367027559 3.735999901575 Y
OC 1.353480019685 3.7225 1.382499409449 3.722497145669 N
OC 1.411519980315 3.7225 1.3825 3.7225 N
OC 1.408980019685 3.734369980315 1.382500590551 3.722497145669 N
OC 1.412630019685 3.74 1.412632972441 3.735999901575 Y
OE
OB 0.41705 3.35406003937 H
OC 0.41705 3.27903996063 0.41705 3.31655 N
OS 0.45705 3.27903996063
OC 0.45705 3.35406003937 0.45705 3.31655 N
OS 0.41705 3.35406003937
OE
OB 1.256469980315 3.20981003937 H
OC 1.229980019685 3.18 1.259998031496 3.180000098425 N
OC 1.290019980315 3.18 1.26 3.18 N
OC 1.29 3.181069980315 1.260000492126 3.179974606299 N
OC 1.293530019685 3.18518996063 1.293997834646 3.181216830709 Y
OC 1.320019980315 3.215 1.290001968504 3.214999901575 N
OC 1.259980019685 3.215 1.29 3.215 N
OC 1.26 3.213930019685 1.289999507874 3.215025393701 N
OC 1.256469980315 3.20981003937 1.256002165354 3.213783169291 Y
OE
OB 0.634419980315 3.200719980315 H
OC 0.629980019685 3.185 0.660002165354 3.18500757874 N
OC 0.690019980315 3.185 0.66 3.185 N
OC 0.68036003937 3.20706003937 0.660001377953 3.185000098425 N
OC 0.68036003937 3.21293996063 0.683072440945 3.21 Y
OC 0.690019980315 3.235 0.660001377953 3.234999901575 N
OC 0.66 3.265019980315 0.66 3.235 N
OC 0.64 3.25738996063 0.66 3.234992716535 N
OC 0.62 3.265019980315 0.62 3.234992716535 N
OC 0.62 3.204980019685 0.62 3.235 N
OC 0.629719980315 3.2066 0.619991929134 3.234998622047 N
OC 0.634419980315 3.200719980315 0.631014074803 3.202815944882 Y
OE
OB 1.39816003937 3.22868996063 H
OC 1.376980019685 3.2 1.407001476378 3.199999901575 N
OC 1.437019980315 3.2 1.407 3.2 N
OC 1.42846003937 3.22098996063 1.407005216535 3.2 N
OC 1.43013996063 3.22761003937 1.431318602362 3.223787795276 Y
OC 1.451319980315 3.2563 1.421298523622 3.256300098425 N
OC 1.391280019685 3.2563 1.4213 3.2563 N
OC 1.39983996063 3.23531003937 1.421294783465 3.2563 N
OC 1.39816003937 3.22868996063 1.396981397638 3.232512204724 Y
OE
OB 1.534769980315 3.266269980315 H
OC 1.52888996063 3.265330019685 1.531408366142 3.268437401575 Y
OC 1.51 3.272019980315 1.51 3.242005905512 N
OC 1.51 3.211980019685 1.51 3.242 N
OC 1.535230019685 3.225730019685 1.51 3.242002362205 N
OC 1.54111003937 3.226669980315 1.538591633858 3.223562598425 Y
OC 1.56 3.219980019685 1.56 3.249994094488 N
OC 1.590019980315 3.25 1.56 3.25 N
OC 1.58238996063 3.27 1.559992716535 3.25 N
OC 1.590019980315 3.29 1.559992716535 3.29 N
OC 1.529980019685 3.29 1.56 3.29 N
OC 1.53761003937 3.27 1.560007283465 3.29 N
OC 1.534769980315 3.266269980315 1.560002559055 3.250003937008 N
OE
OB 1.439130019685 3.361580019685 H
OC 1.41916003937 3.369180019685 1.419165649606 3.339157874016 N
OC 1.41916003937 3.30913996063 1.41916003937 3.33916003937 N
OC 1.440030019685 3.317580019685 1.419159940945 3.339163090551 N
OC 1.46 3.309980019685 1.459994389764 3.340002165354 N
OC 1.46 3.370019980315 1.46 3.34 N
OC 1.439130019685 3.361580019685 1.46 3.339996850394 N
OE
OB 0.945180019685 3.413480019685 H
OC 0.944980019685 3.41 0.975001181102 3.410020374016 N
OC 0.975 3.379980019685 0.975 3.41 N
OC 0.995 3.38761003937 0.975 3.410007283465 N
OC 1.015 3.379980019685 1.015 3.410007283465 N
OC 1.015 3.440019980315 1.015 3.41 N
OC 0.995 3.43238996063 1.015 3.409992716535 N
OC 0.981380019685 3.439330019685 0.975010137795 3.409994291339 N
OC 0.979819980315 3.441519980315 0.981806496063 3.441284448819 Y
OC 0.980019980315 3.445 0.949998818898 3.444979625984 N
OC 0.919980019685 3.445 0.95 3.445 N
OC 0.943619980315 3.415669980315 0.949994783465 3.445 N
OC 0.945180019685 3.413480019685 0.943193503937 3.413715551181 Y
OE
OB 1.39788996063 3.52031003937 H
OC 1.389980019685 3.5 1.420009350394 3.500000098425 N
OC 1.450019980315 3.5 1.42 3.5 N
OC 1.4324 3.52733996063 1.419999015748 3.5 N
OC 1.43111003937 3.53368996063 1.434051771654 3.530981496063 Y
OC 1.439019980315 3.554 1.408990649606 3.553999901575 N
OC 1.378980019685 3.554 1.409 3.554 N
OC 1.3966 3.52666003937 1.409000984252 3.554 N
OC 1.39788996063 3.52031003937 1.394948228346 3.523018503937 Y
OE
OB 0.64491003937 3.32328996063 H
OC 0.64491003937 3.32328996063 0.61488996063 3.32328996063 N
OE
OB 1.325019980315 3.28 H
OC 1.325019980315 3.28 1.295 3.28 N
OE
OB 1.160019980315 3.445 H
OC 1.160019980315 3.445 1.13 3.445 N
OE
OB 1.400019980315 3.64 H
OC 1.400019980315 3.64 1.37 3.64 N
OE
OB 0.980019980315 3.215 H
OC 0.980019980315 3.215 0.95 3.215 N
OE
OB 1.084119980315 3.185 H
OC 1.084119980315 3.185 1.0541 3.185 N
OE
OB 0.98595 3.333469980315 H
OC 0.98595 3.333469980315 0.955930019685 3.333469980315 N
OE
OB 0.580019980315 3.36 H
OC 0.580019980315 3.36 0.55 3.36 N
OE
OB 0.750019980315 3.35 H
OC 0.750019980315 3.35 0.72 3.35 N
OE
OB 0.820019980315 3.155 H
OC 0.820019980315 3.155 0.79 3.155 N
OE
OB 0.385019980315 3.27 H
OC 0.385019980315 3.27 0.355 3.27 N
OE
OB 0.769069980315 3.27703996063 H
OC 0.769819980315 3.269980019685 0.767613287402 3.273315452756 Y
OC 0.756330019685 3.244919980315 0.786351673228 3.24492007874 N
OC 0.816369980315 3.244919980315 0.78635 3.244919980315 N
OC 0.816330019685 3.24643996063 0.786350787402 3.244891240157 N
OC 0.82141003937 3.25048996063 0.820324015748 3.246641141732 Y
OC 0.82951003937 3.249380019685 0.829497834646 3.279401673228 N
OC 0.82951003937 3.309419980315 0.82951003937 3.2794 N
OC 0.815569980315 3.30598996063 0.82950492126 3.279398720472 N
OC 0.80975 3.309 0.813713976378 3.309532874016 Y
OC 0.78 3.335019980315 0.78 3.30500265748 N
OC 0.749980019685 3.305 0.78 3.305 N
OC 0.769069980315 3.27703996063 0.780000688976 3.304999901575 N
OE
OB 0.44516003937 3.42293996063 H
OC 0.441619980315 3.41681003937 0.441777854331 3.420806003937 Y
OC 0.440980019685 3.416819980315 0.441051181102 3.400798917323 N
OC 0.457 3.4008 0.440980019685 3.4008 N
OC 0.454519980315 3.40936003937 0.440987106299 3.4008 N
OC 0.45806003937 3.41548996063 0.457902165354 3.411493996063 Y
OC 0.4587 3.415480019685 0.458628838583 3.431501082677 N
OC 0.442680019685 3.4315 0.4587 3.4315 N
OC 0.44516003937 3.42293996063 0.458692913386 3.4315 N
OE
OB 1.214269980315 3.537669980315 H
OC 1.19 3.550019980315 1.19 3.51999753937 N
OC 1.16793996063 3.54036003937 1.189999901575 3.520001377953 N
OC 1.16206003937 3.54036003937 1.165 3.543072440945 Y
OC 1.14 3.550019980315 1.140000098425 3.520001377953 N
OC 1.14 3.489980019685 1.14 3.52 N
OC 1.16206003937 3.49963996063 1.140000098425 3.519998622047 N
OC 1.16793996063 3.49963996063 1.165 3.496927559055 Y
OC 1.19 3.489980019685 1.189999901575 3.519998622047 N
OC 1.20235 3.49263996063 1.189995964567 3.519999114173 N
OC 1.20763996063 3.48735 1.203991240157 3.488991240157 Y
OC 1.204980019685 3.475 1.234999114173 3.474995964567 N
OC 1.265019980315 3.475 1.235 3.475 N
OC 1.260969980315 3.49006003937 1.234994586614 3.475000098425 N
OC 1.26213996063 3.49536003937 1.264425885827 3.492076279528 Y
OC 1.26365 3.496480019685 1.245022145669 3.520017519685 N
OC 1.270119980315 3.493730019685 1.266137992126 3.493347637795 Y
OC 1.3 3.466619980315 1.3 3.496641535433 N
OC 1.3 3.52666003937 1.3 3.496640059055 N
OC 1.28135 3.52016003937 1.300004527559 3.496641535433 N
OC 1.274880019685 3.52291003937 1.278862007874 3.52329242126 Y
OC 1.245 3.550019980315 1.245000098425 3.519998523622 N
OC 1.220730019685 3.537669980315 1.245 3.51999753937 N
OC 1.214269980315 3.537669980315 1.2175 3.540027165354 Y
OE
SE
P 1.45 3.59 10 P 0 8 0;1=0,3=1
P 1.56 3.165 10 P 0 8 0;1=2,3=1
P 1.56 3.205 10 P 0 8 0;1=0,3=1
P 0.72 3.463 10 P 0 8 0;1=2,3=1
P 0.42326004 3.4315 11 P 0 8 0;1=6,3=0
P 0.40553996 3.4008 11 P 0 8 0;1=6,3=0
P 0.2815 3.4315 11 P 0 8 0;1=6,3=0
P 0.26378002 3.4008 11 P 0 8 0;1=6,3=0
P 0.71 3.305 10 P 0 8 0;1=3,3=0
P 1.515 3.58 10 P 0 8 0;1=2,3=1
L 1.515 3.58 1.585 3.65 8 P 0 
L 1.585 3.65 1.7289 3.65 8 P 0 
L 1.7289 3.65 1.7989 3.72 8 P 0 
L 1.7989 3.72 2.72 3.72 8 P 0 
L 2.72 3.72 2.81 3.81 8 P 0 
L 2.81 3.81 2.81 4.13 8 P 0 
L 2.81 4.13 2.985 4.305 8 P 0 
L 2.985 4.305 6.01 4.305 8 P 0 
L 6.01 4.305 6.075 4.24 8 P 0 
L 6.075 4.24 6.075 4.2 8 P 0 
L 6.075 4.2 6.145 4.13 8 P 0 
L 6.145 4.13 6.145 4.035 8 P 0 
P 6.145 4.035 10 P 0 8 0;1=0,3=1
L 2.19 3.488 2.19 3.39 8 P 0 
L 2.19 3.39 2.192 3.388 8 P 0 
P 2.19 3.488 10 P 0 8 0;1=2,3=1
P 2.192 3.388 10 P 0 8 0;1=2,3=1
L 3.51 3.08 3.51 3.095 4 P 0 
L 3.51 3.095 3.5565 3.1415 4 P 0 
L 3.5565 3.1415 3.8385 3.1415 4 P 0 
L 3.8385 3.1415 3.9105 3.0695 4 P 0 
L 3.9105 3.0695 3.92491004 3.0695 4 P 0 
L 3.92491004 3.0695 3.9375 3.05691004 4 P 0 
L 3.9375 3.05691004 3.9375 3.0425 4 P 0 
L 3.9375 3.0425 4.05 2.93 4 P 0 
L 4.05 2.93 4.05 2.785 4 P 0 
L 4.05 2.785 4.06 2.775 4 P 0 
L 4.06 2.775 4.11658002 2.775 4 P 0 
L 4.11658002 2.775 4.279 2.61258002 4 P 0 
L 4.279 2.61258002 4.279 2.45145 4 P 0 
L 4.279 2.45145 4.325 2.40545 4 P 0 
L 4.325 2.40545 4.325 2.1614 4 P 0 
L 4.325 2.1614 4.33 2.1564 4 P 0 
L 4.33 2.1564 4.3536 2.1564 4 P 0 
L 4.3536 2.1564 4.365 2.145 4 P 0 
L 4.365 2.145 4.365 1.97 4 P 0 
L 4.365 1.97 4.375 1.96 4 P 0 
L 4.375 1.96 4.40496004 1.96 4 P 0 
L 4.40496004 1.96 4.42311004 1.94185 4 P 0 
P 3.51 3.08 10 P 0 8 0;1=0,3=1
P 4.42311004 1.94185 9 P 0 8 0;1=1,3=1
L 3.46 3.065 3.46 3.0625 4 P 0 
L 3.46 3.0625 3.465 3.0575 4 P 0 
L 3.465 3.0575 3.51933002 3.0575 4 P 0 
L 3.51933002 3.0575 3.5325 3.07066998 4 P 0 
L 3.5325 3.07066998 3.5325 3.07433002 4 P 0 
L 3.5325 3.07433002 3.57966998 3.1215 4 P 0 
L 3.57966998 3.1215 3.8285 3.1215 4 P 0 
L 3.8285 3.1215 3.8945 3.0555 4 P 0 
L 3.8945 3.0555 3.8945 3.03908996 4 P 0 
L 3.8945 3.03908996 3.90708996 3.0265 4 P 0 
L 3.90708996 3.0265 3.9235 3.0265 4 P 0 
L 3.9235 3.0265 4.025 2.925 4 P 0 
L 4.025 2.925 4.025 2.90926998 4 P 0 
L 4.025 2.90926998 4.02 2.90426998 4 P 0 
L 4.02 2.90426998 3.9892 2.90426998 4 P 0 
L 3.9892 2.90426998 3.9842 2.89926998 4 P 0 
L 3.9842 2.89926998 3.9842 2.88426998 4 P 0 
L 3.9842 2.88426998 3.9892 2.87926998 4 P 0 
L 3.9892 2.87926998 4.02 2.87926998 4 P 0 
L 4.02 2.87926998 4.025 2.87426998 4 P 0 
L 4.025 2.87426998 4.025 2.85926998 4 P 0 
L 4.025 2.85926998 4.02 2.85426998 4 P 0 
L 4.02 2.85426998 3.9892 2.85426998 4 P 0 
L 3.9892 2.85426998 3.9842 2.84926998 4 P 0 
L 3.9842 2.84926998 3.9842 2.83426998 4 P 0 
L 3.9842 2.83426998 3.9892 2.82926998 4 P 0 
L 3.9892 2.82926998 4.02 2.82926998 4 P 0 
L 4.02 2.82926998 4.025 2.82426998 4 P 0 
L 4.025 2.82426998 4.025 2.77463996 4 P 0 
L 4.025 2.77463996 4.04963996 2.75 4 P 0 
L 4.04963996 2.75 4.11328996 2.75 4 P 0 
L 4.11328996 2.75 4.259 2.60428996 4 P 0 
L 4.259 2.60428996 4.259 2.42063996 4 P 0 
L 4.259 2.42063996 4.31 2.36963996 4 P 0 
L 4.31 2.36963996 4.31 2.245 4 P 0 
L 4.31 2.245 4.305 2.24 4 P 0 
L 4.305 2.24 4.305 2.15 4 P 0 
L 4.305 2.15 4.32 2.135 4 P 0 
L 4.32 2.135 4.32 1.97 4 P 0 
L 4.32 1.97 4.3275 1.9625 4 P 0 
L 4.3275 1.9625 4.3525 1.9625 4 P 0 
L 4.3525 1.9625 4.3656 1.9494 4 P 0 
L 4.3656 1.9494 4.3656 1.925 4 P 0 
L 4.3656 1.925 4.3706 1.92 4 P 0 
L 4.3706 1.92 4.395 1.92 4 P 0 
L 4.395 1.92 4.41251998 1.90248002 4 P 0 
L 4.41251998 1.90248002 4.42311004 1.90248002 4 P 0 
P 3.46 3.065 10 P 0 8 0;1=0,3=1
P 4.42311004 1.90248002 9 P 0 8 0;1=1,3=1
P 3.035 1.64 10 P 0 8 0;1=2,3=1
L 1.1288 0.7302 1.2148 0.7302 4 P 0 
L 1.2148 0.7302 1.2475 0.6975 4 P 0 
L 1.2475 0.6975 1.3475 0.6975 4 P 0 
L 1.3475 0.6975 1.375 0.67 4 P 0 
L 1.375 0.67 1.435 0.67 4 P 0 
L 1.435 0.67 1.49 0.725 4 P 0 
L 1.49 0.725 1.52 0.725 4 P 0 
L 1.52 0.725 1.54 0.745 4 P 0 
L 1.54 0.745 1.54 0.839 4 P 0 
L 1.54 0.839 1.73721004 1.03621004 4 P 0 
L 1.73721004 1.03621004 2.15621004 1.03621004 4 P 0 
L 2.15621004 1.03621004 2.76 1.64 4 P 0 
L 2.76 1.64 3.035 1.64 4 P 0 
P 1.1288 0.7302 9 P 0 8 0;1=7,3=1
P 3.075 1.605 10 P 0 8 0;1=2,3=1
L 0.755 0.62 0.805 0.62 4 P 0 
L 0.805 0.62 0.84 0.655 4 P 0 
L 0.84 0.655 0.87 0.655 4 P 0 
L 0.87 0.655 0.8844 0.6406 4 P 0 
L 0.8844 0.6406 1.19938996 0.6406 4 P 0 
L 1.19938996 0.6406 1.24998996 0.59 4 P 0 
L 1.24998996 0.59 1.43741004 0.59 4 P 0 
L 1.43741004 0.59 1.4635 0.61608996 4 P 0 
L 1.4635 0.61608996 1.4635 0.63391004 4 P 0 
L 1.4635 0.63391004 1.47608996 0.6465 4 P 0 
L 1.47608996 0.6465 1.53321004 0.6465 4 P 0 
L 1.53321004 0.6465 1.574 0.68728996 4 P 0 
L 1.574 0.68728996 1.574 0.726 4 P 0 
L 1.574 0.726 1.56 0.74 4 P 0 
L 1.56 0.74 1.56 0.829 4 P 0 
L 1.56 0.829 1.746 1.015 4 P 0 
L 1.746 1.015 2.165 1.015 4 P 0 
L 2.165 1.015 2.75 1.6 4 P 0 
L 2.75 1.6 3.07 1.6 4 P 0 
L 3.07 1.6 3.075 1.605 4 P 0 
P 0.755 0.62 10 P 0 8 0;1=3,3=0
P 1.073 3.825 9 P 0 8 0;1=9,3=1
P 0.703 3.575 9 P 0 8 0;1=9,3=1
L 0.703 3.575 0.70796998 3.57996998 6 P 0 
A 0.70796998 3.57996998 0.71166998 3.58588996 0.69705502 3.59090807 6 P 0 N
L 0.71166998 3.58588996 0.7125 3.5909 6 P 0 
L 0.7125 3.5909 0.7125 3.6035 6 P 0 
A 0.7125 3.6035 0.7317 3.6227 0.7317 3.6035 6 P 0 Y
L 0.7317 3.6227 0.75101004 3.6227 6 P 0 
A 0.75101004 3.6227 0.79023996 3.60645 0.75100443 3.56720817 6 P 0 Y
L 0.79023996 3.60645 0.8168 3.5799 6 P 0 
A 0.8168 3.5799 0.85033996 3.566 0.85034469 3.61342657 6 P 0 N
L 0.85033996 3.566 0.9341 3.566 6 P 0 
A 0.9341 3.566 0.9772 3.6091 0.9341 3.6091 6 P 0 N
L 0.9772 3.6091 0.9772 3.62741004 6 P 0 
A 0.9772 3.62741004 0.98743002 3.65213002 1.01215059 3.62742293 6 P 0 Y
L 0.98743002 3.65213002 1.04763996 3.71233996 6 P 0 
A 1.04763996 3.71233996 1.0825 3.7965 0.96347923 3.7965 6 P 0 N
L 1.0825 3.7965 1.0825 3.81205 6 P 0 
L 1.0825 3.81205 1.082 3.81488996 6 P 0 
A 1.082 3.81488996 1.08006004 3.81793996 1.07416988 3.81205148 6 P 0 N
L 1.08006004 3.81793996 1.073 3.825 6 P 0 
P 0.735 3.575 9 P 0 8 0;1=9,3=1
P 1.105 3.825 9 P 0 8 0;1=9,3=1
L 0.735 3.575 0.73003002 3.57996998 6 P 0 
A 0.73003002 3.57996998 0.72633002 3.58588996 0.74094498 3.59090807 6 P 0 Y
L 0.72633002 3.58588996 0.7255 3.5909 6 P 0 
L 0.7255 3.5909 0.7255 3.6035 6 P 0 
A 0.7255 3.6035 0.7317 3.6097 0.7317 3.6035 6 P 0 Y
L 0.7317 3.6097 0.751 3.6097 6 P 0 
A 0.751 3.6097 0.78103996 3.59725 0.75099144 3.56721348 6 P 0 Y
L 0.78103996 3.59725 0.8076 3.5707 6 P 0 
A 0.8076 3.5707 0.85033002 3.553 0.85033091 3.61343012 6 P 0 N
L 0.85033002 3.553 0.9341 3.553 6 P 0 
A 0.9341 3.553 0.9902 3.6091 0.9341 3.6091 6 P 0 N
L 0.9902 3.6091 0.9902 3.62741004 6 P 0 
A 0.9902 3.62741004 0.99663002 3.64293002 1.01214518 3.62740994 6 P 0 Y
L 0.99663002 3.64293002 1.05683996 3.70313996 6 P 0 
A 1.05683996 3.70313996 1.0955 3.7965 0.96347392 3.79648691 6 P 0 N
L 1.0955 3.7965 1.0955 3.81205 6 P 0 
L 1.0955 3.81205 1.096 3.81488996 6 P 0 
A 1.096 3.81488996 1.09793996 3.81793996 1.10383012 3.81205148 6 P 0 Y
L 1.09793996 3.81793996 1.105 3.825 6 P 0 
L 5.195 0.755 5.23 0.79 4 P 0 
L 5.23 0.79 5.23 0.82 4 P 0 
L 5.23 0.82 5.21 0.84 4 P 0 
L 5.21 0.84 5.17 0.84 4 P 0 
L 5.17 0.84 5.16 0.85 4 P 0 
L 5.16 0.85 4.96 0.85 4 P 0 
P 5.195 0.755 10 P 0 8 0;1=0,3=1
P 4.96 0.85 10 P 0 8 0;1=2,3=1
L 4.937 0.79161004 4.93941004 0.79161004 4 P 0 
L 4.93941004 0.79161004 4.9628 0.815 4 P 0 
L 4.9628 0.815 5.00611998 0.815 4 P 0 
L 5.00611998 0.815 5.01111998 0.81 4 P 0 
L 5.01111998 0.81 5.01111998 0.7927 4 P 0 
L 5.01111998 0.7927 5.01611998 0.7877 4 P 0 
L 5.01611998 0.7877 5.03111998 0.7877 4 P 0 
L 5.03111998 0.7877 5.03611998 0.7927 4 P 0 
L 5.03611998 0.7927 5.03611998 0.81 4 P 0 
L 5.03611998 0.81 5.04111998 0.815 4 P 0 
L 5.04111998 0.815 5.05611998 0.815 4 P 0 
L 5.05611998 0.815 5.06111998 0.81 4 P 0 
L 5.06111998 0.81 5.06111998 0.7946 4 P 0 
L 5.06111998 0.7946 5.06611998 0.7896 4 P 0 
L 5.06611998 0.7896 5.08111998 0.7896 4 P 0 
L 5.08111998 0.7896 5.08611998 0.7946 4 P 0 
L 5.08611998 0.7946 5.08611998 0.81 4 P 0 
L 5.08611998 0.81 5.09111998 0.815 4 P 0 
L 5.09111998 0.815 5.10611998 0.815 4 P 0 
L 5.10611998 0.815 5.11111998 0.81 4 P 0 
L 5.11111998 0.81 5.11111998 0.7946 4 P 0 
L 5.11111998 0.7946 5.11611998 0.7896 4 P 0 
L 5.11611998 0.7896 5.13111998 0.7896 4 P 0 
L 5.13111998 0.7896 5.13611998 0.7946 4 P 0 
L 5.13611998 0.7946 5.13611998 0.81 4 P 0 
L 5.13611998 0.81 5.14111998 0.815 4 P 0 
L 5.14111998 0.815 5.195 0.815 4 P 0 
P 5.195 0.815 10 P 0 8 0;1=0,3=1
P 4.937 0.79161004 10 P 0 8 0;1=2,3=1
L 5.814 2.821 5.754 2.821 4 P 0 
L 5.754 2.821 5.715 2.86 4 P 0 
L 5.715 2.86 5.715 2.88223002 4 P 0 
L 5.715 2.88223002 5.72 2.88723002 4 P 0 
L 5.72 2.88723002 5.75 2.88723002 4 P 0 
L 5.75 2.88723002 5.755 2.89223002 4 P 0 
L 5.755 2.89223002 5.755 2.90723002 4 P 0 
L 5.755 2.90723002 5.75 2.91223002 4 P 0 
L 5.75 2.91223002 5.72 2.91223002 4 P 0 
L 5.72 2.91223002 5.715 2.91723002 4 P 0 
L 5.715 2.91723002 5.715 2.93223002 4 P 0 
L 5.715 2.93223002 5.72 2.93723002 4 P 0 
L 5.72 2.93723002 5.75 2.93723002 4 P 0 
L 5.75 2.93723002 5.755 2.94223002 4 P 0 
L 5.755 2.94223002 5.755 2.95723002 4 P 0 
L 5.755 2.95723002 5.75 2.96223002 4 P 0 
L 5.75 2.96223002 5.72 2.96223002 4 P 0 
L 5.72 2.96223002 5.715 2.96723002 4 P 0 
L 5.715 2.96723002 5.715 2.98223002 4 P 0 
L 5.715 2.98223002 5.72 2.98723002 4 P 0 
L 5.72 2.98723002 5.75 2.98723002 4 P 0 
L 5.75 2.98723002 5.755 2.99223002 4 P 0 
L 5.755 2.99223002 5.755 3.00723002 4 P 0 
L 5.755 3.00723002 5.75 3.01223002 4 P 0 
L 5.75 3.01223002 5.72 3.01223002 4 P 0 
L 5.72 3.01223002 5.715 3.01723002 4 P 0 
L 5.715 3.01723002 5.715 3.05001004 4 P 0 
L 5.715 3.05001004 5.65 3.11501004 4 P 0 
L 5.65 3.11501004 5.65 3.41281004 4 P 0 
L 5.65 3.41281004 5.58431004 3.4785 4 P 0 
L 5.58431004 3.4785 5.22811004 3.4785 4 P 0 
L 5.22811004 3.4785 4.96635 3.74026004 4 P 0 
L 4.96635 3.74026004 4.64973996 3.74026004 4 P 0 
L 4.64973996 3.74026004 4.53 3.86 4 P 0 
L 4.53 3.86 4.45541004 3.86 4 P 0 
L 4.45541004 3.86 4.43891004 3.8435 4 P 0 
L 4.43891004 3.8435 4.41148996 3.8435 4 P 0 
L 4.41148996 3.8435 4.40498996 3.85 4 P 0 
L 4.40498996 3.85 4.34501004 3.85 4 P 0 
L 4.34501004 3.85 4.33501004 3.84 4 P 0 
L 4.33501004 3.84 4.3139 3.84 4 P 0 
L 4.3139 3.84 4.3114 3.8375 4 P 0 
L 4.3114 3.8375 4.2886 3.8375 4 P 0 
L 4.2886 3.8375 4.2861 3.84 4 P 0 
L 4.2861 3.84 4.235 3.84 4 P 0 
L 4.235 3.84 4.205 3.81 4 P 0 
P 4.205 3.81 10 P 0 8 0;1=2,3=1
P 5.814 2.821 9 P 0 8 0;1=7,3=1
L 4.19 3.735 4.2425 3.7875 4 P 0 
L 4.2425 3.7875 4.37933002 3.7875 4 P 0 
L 4.37933002 3.7875 4.40683002 3.815 4 P 0 
L 4.40683002 3.815 4.50316998 3.815 4 P 0 
L 4.50316998 3.815 4.52566998 3.7925 4 P 0 
L 4.52566998 3.7925 4.56921004 3.7925 4 P 0 
L 4.56921004 3.7925 4.64558002 3.71613002 4 P 0 
L 4.64558002 3.71613002 4.64561004 3.71611998 4 P 0 
L 4.64561004 3.71611998 4.9622 3.71611998 4 P 0 
L 4.9622 3.71611998 5.218 3.46031998 4 P 0 
L 5.218 3.46031998 5.218 3.172 4 P 0 
L 5.218 3.172 5.26 3.13 4 P 0 
L 5.26 3.13 5.47 3.13 4 P 0 
L 5.47 3.13 5.53323996 3.06676004 4 P 0 
L 5.53323996 3.06676004 5.54031998 3.06676004 4 P 0 
L 5.54031998 3.06676004 5.55173996 3.07818002 4 P 0 
L 5.55173996 3.07818002 5.55881998 3.07818002 4 P 0 
L 5.55881998 3.07818002 5.56941998 3.06758002 4 P 0 
L 5.56941998 3.06758002 5.56941998 3.0605 4 P 0 
L 5.56941998 3.0605 5.558 3.04908002 4 P 0 
L 5.558 3.04908002 5.558 3.042 4 P 0 
L 5.558 3.042 5.5686 3.0314 4 P 0 
L 5.5686 3.0314 5.57568002 3.0314 4 P 0 
L 5.57568002 3.0314 5.5871 3.04281998 4 P 0 
L 5.5871 3.04281998 5.59418002 3.04281998 4 P 0 
L 5.59418002 3.04281998 5.60478002 3.03221998 4 P 0 
L 5.60478002 3.03221998 5.60478002 3.02513996 4 P 0 
L 5.60478002 3.02513996 5.59336004 3.01371998 4 P 0 
L 5.59336004 3.01371998 5.59336004 3.00663996 4 P 0 
L 5.59336004 3.00663996 5.60396004 2.99603996 4 P 0 
L 5.60396004 2.99603996 5.61103996 2.99603996 4 P 0 
L 5.61103996 2.99603996 5.62246004 3.00746004 4 P 0 
L 5.62246004 3.00746004 5.62953996 3.00746004 4 P 0 
L 5.62953996 3.00746004 5.64013996 2.99686004 4 P 0 
L 5.64013996 2.99686004 5.64013996 2.98978002 4 P 0 
L 5.64013996 2.98978002 5.62871998 2.97836004 4 P 0 
L 5.62871998 2.97836004 5.62871998 2.97128002 4 P 0 
L 5.62871998 2.97128002 5.63931998 2.96068002 4 P 0 
L 5.63931998 2.96068002 5.6464 2.96068002 4 P 0 
L 5.6464 2.96068002 5.65781998 2.9721 4 P 0 
L 5.65781998 2.9721 5.6649 2.9721 4 P 0 
L 5.6649 2.9721 5.6755 2.9615 4 P 0 
L 5.6755 2.9615 5.6755 2.95441998 4 P 0 
L 5.6755 2.95441998 5.66408002 2.943 4 P 0 
L 5.66408002 2.943 5.66408002 2.93591998 4 P 0 
L 5.66408002 2.93591998 5.685 2.915 4 P 0 
L 5.685 2.915 5.685 2.835 4 P 0 
L 5.685 2.835 5.799 2.721 4 P 0 
L 5.799 2.721 5.814 2.721 4 P 0 
P 4.19 3.735 10 P 0 8 0;1=2,3=1
P 5.814 2.721 9 P 0 8 0;1=7,3=1
L 3.895 3.7 3.895 3.705 4 P 0 
L 3.895 3.705 3.955 3.765 4 P 0 
L 3.955 3.765 4.125 3.765 4 P 0 
L 4.125 3.765 4.255 3.895 4 P 0 
L 4.255 3.895 4.53 3.895 4 P 0 
L 4.53 3.895 4.66 3.765 4 P 0 
L 4.66 3.765 4.9699 3.765 4 P 0 
L 4.9699 3.765 5.2349 3.5 4 P 0 
L 5.2349 3.5 5.5911 3.5 4 P 0 
L 5.5911 3.5 5.67 3.4211 4 P 0 
L 5.67 3.4211 5.67 3.13 4 P 0 
L 5.67 3.13 5.779 3.021 4 P 0 
L 5.779 3.021 5.815 3.021 4 P 0 
P 3.895 3.7 10 P 0 8 0;1=2,3=1
P 5.815 3.021 9 P 0 8 0;1=7,3=1
L 4.135 3.735 4.16 3.71 4 P 0 
L 4.16 3.71 4.2 3.71 4 P 0 
L 4.2 3.71 4.2575 3.7675 4 P 0 
L 4.2575 3.7675 4.56591004 3.7675 4 P 0 
L 4.56591004 3.7675 4.58331998 3.75008996 4 P 0 
L 4.58331998 3.75008996 4.58331998 3.74303002 4 P 0 
L 4.58331998 3.74303002 4.55968002 3.7194 4 P 0 
L 4.55968002 3.7194 4.55968002 3.71233996 4 P 0 
L 4.55968002 3.71233996 4.5703 3.70171998 4 P 0 
L 4.5703 3.70171998 4.57736004 3.70171998 4 P 0 
L 4.57736004 3.70171998 4.601 3.72535 4 P 0 
L 4.601 3.72535 4.60806004 3.72535 4 P 0 
L 4.60806004 3.72535 4.61868002 3.71473002 4 P 0 
L 4.61868002 3.71473002 4.61868002 3.70766998 4 P 0 
L 4.61868002 3.70766998 4.59503996 3.68403996 4 P 0 
L 4.59503996 3.68403996 4.59503996 3.67698002 4 P 0 
L 4.59503996 3.67698002 4.60566004 3.66636004 4 P 0 
L 4.60566004 3.66636004 4.61271998 3.66636004 4 P 0 
L 4.61271998 3.66636004 4.63636004 3.68998996 4 P 0 
L 4.63636004 3.68998996 4.64341998 3.68998996 4 P 0 
L 4.64341998 3.68998996 4.66028996 3.67311998 4 P 0 
L 4.66028996 3.67311998 4.71353002 3.67311998 4 P 0 
L 4.71353002 3.67311998 4.73471998 3.69431004 4 P 0 
L 4.73471998 3.69431004 4.95571998 3.69431004 4 P 0 
L 4.95571998 3.69431004 5.198 3.45203002 4 P 0 
L 5.198 3.45203002 5.198 3.15858996 4 P 0 
L 5.198 3.15858996 5.24658996 3.11 4 P 0 
L 5.24658996 3.11 5.455 3.11 4 P 0 
L 5.455 3.11 5.665 2.9 4 P 0 
L 5.665 2.9 5.665 2.815 4 P 0 
L 5.665 2.815 5.79 2.69 4 P 0 
L 5.79 2.69 5.79 2.645 4 P 0 
L 5.79 2.645 5.814 2.621 4 P 0 
P 4.135 3.735 10 P 0 8 0;1=2,3=1
P 5.814 2.621 9 P 0 8 0;1=7,3=1
L 5.045 3.405 5.04 3.405 4 P 0 
L 5.04 3.405 4.96 3.485 4 P 0 
L 4.96 3.485 4.775 3.485 4 P 0 
L 4.775 3.485 4.72 3.43 4 P 0 
L 4.72 3.43 4.555 3.43 4 P 0 
L 4.555 3.43 4.475 3.51 4 P 0 
L 4.475 3.51 4.4 3.51 4 P 0 
L 4.4 3.51 4.3525 3.5575 4 P 0 
L 4.3525 3.5575 4.3075 3.5575 4 P 0 
L 4.3075 3.5575 4.29 3.54 4 P 0 
L 4.29 3.54 4.29 3.5 4 P 0 
L 4.29 3.5 4.26 3.47 4 P 0 
L 4.26 3.47 3.945 3.47 4 P 0 
L 3.945 3.47 3.835 3.58 4 P 0 
L 3.835 3.58 3.63171004 3.58 4 P 0 
L 3.63171004 3.58 3.53171004 3.48 4 P 0 
L 3.53171004 3.48 2.305 3.48 4 P 0 
L 2.305 3.48 2.3 3.475 4 P 0 
P 2.3 3.475 10 P 0 8 0;1=2,3=1
P 5.045 3.405 10 P 0 8 0;1=2,3=1
L 5.09 3.405 5.0675 3.4275 4 P 0 
L 5.0675 3.4275 5.04578996 3.4275 4 P 0 
L 5.04578996 3.4275 4.96828996 3.505 4 P 0 
L 4.96828996 3.505 4.76671004 3.505 4 P 0 
L 4.76671004 3.505 4.75671004 3.495 4 P 0 
L 4.75671004 3.495 4.52 3.495 4 P 0 
L 4.52 3.495 4.485 3.53 4 P 0 
L 4.485 3.53 4.415 3.53 4 P 0 
L 4.415 3.53 4.3675 3.5775 4 P 0 
L 4.3675 3.5775 4.2975 3.5775 4 P 0 
L 4.2975 3.5775 4.255 3.535 4 P 0 
L 4.255 3.535 4.255 3.52 4 P 0 
L 4.255 3.52 4.225 3.49 4 P 0 
L 4.225 3.49 3.955 3.49 4 P 0 
L 3.955 3.49 3.845 3.6 4 P 0 
L 3.845 3.6 3.78728002 3.6 4 P 0 
L 3.78728002 3.6 3.78228002 3.605 4 P 0 
L 3.78228002 3.605 3.78228002 3.665 4 P 0 
L 3.78228002 3.665 3.77728002 3.67 4 P 0 
L 3.77728002 3.67 3.76228002 3.67 4 P 0 
L 3.76228002 3.67 3.75728002 3.665 4 P 0 
L 3.75728002 3.665 3.75728002 3.605 4 P 0 
L 3.75728002 3.605 3.75228002 3.6 4 P 0 
L 3.75228002 3.6 3.73728002 3.6 4 P 0 
L 3.73728002 3.6 3.73228002 3.605 4 P 0 
L 3.73228002 3.605 3.73228002 3.665 4 P 0 
L 3.73228002 3.665 3.72728002 3.67 4 P 0 
L 3.72728002 3.67 3.71228002 3.67 4 P 0 
L 3.71228002 3.67 3.70728002 3.665 4 P 0 
L 3.70728002 3.665 3.70728002 3.605 4 P 0 
L 3.70728002 3.605 3.70228002 3.6 4 P 0 
L 3.70228002 3.6 3.67683996 3.6 4 P 0 
L 3.67683996 3.6 3.67183996 3.605 4 P 0 
L 3.67183996 3.605 3.67183996 3.62 4 P 0 
L 3.67183996 3.62 3.66683996 3.625 4 P 0 
L 3.66683996 3.625 3.65183996 3.625 4 P 0 
L 3.65183996 3.625 3.64683996 3.62 4 P 0 
L 3.64683996 3.62 3.64683996 3.605 4 P 0 
L 3.64683996 3.605 3.64183996 3.6 4 P 0 
L 3.64183996 3.6 3.62341998 3.6 4 P 0 
L 3.62341998 3.6 3.52463002 3.50121004 4 P 0 
L 3.52463002 3.50121004 2.28121004 3.50121004 4 P 0 
L 2.28121004 3.50121004 2.255 3.475 4 P 0 
P 2.255 3.475 10 P 0 8 0;1=2,3=1
P 5.09 3.405 10 P 0 8 0;1=2,3=1
L 4.575 2.235 4.5626 2.2226 4 P 0 
L 4.5626 2.2226 4.5626 1.9726 4 P 0 
L 4.5626 1.9726 4.5523 1.9623 4 P 0 
L 4.5523 1.9623 4.5223 1.9623 4 P 0 
L 4.5223 1.9623 4.50185 1.94185 4 P 0 
P 4.575 2.235 10 P 0 8 0;1=2,3=1
P 4.50185 1.94185 9 P 0 8 0;1=1,3=1
L 4.575 2.275 4.57 2.275 4 P 0 
L 4.57 2.275 4.545 2.25 4 P 0 
L 4.545 2.25 4.545 2.23 4 P 0 
L 4.545 2.23 4.52 2.205 4 P 0 
L 4.52 2.205 4.52 2.005 4 P 0 
L 4.52 2.005 4.515 2 4 P 0 
L 4.515 2 4.40251998 2 4 P 0 
L 4.40251998 2 4.38373996 1.98121998 4 P 0 
P 4.575 2.275 10 P 0 8 0;1=2,3=1
P 4.38373996 1.98121998 9 P 0 8 0;1=1,3=1
L 5.92 1.41 5.84 1.49 4 P 0 
L 5.84 1.49 5.41 1.49 4 P 0 
L 5.41 1.49 5.38 1.46 4 P 0 
L 5.38 1.46 5.285 1.46 4 P 0 
L 5.285 1.46 5.24 1.505 4 P 0 
L 5.24 1.505 5.24 1.575 4 P 0 
L 5.24 1.575 5.1 1.715 4 P 0 
L 5.1 1.715 5.1 1.935 4 P 0 
L 5.1 1.935 5.075 1.96 4 P 0 
L 5.075 1.96 5.075 2.08 4 P 0 
L 5.075 2.08 5.08 2.085 4 P 0 
L 5.08 2.085 5.08 2.145 4 P 0 
L 5.08 2.145 5.09 2.155 4 P 0 
P 5.92 1.41 10 P 0 8 0;1=0,3=1
P 5.09 2.155 10 P 0 8 0;1=2,3=1
L 5.135 2.155 5.1 2.12 4 P 0 
L 5.1 2.12 5.1 2.08378002 4 P 0 
L 5.1 2.08378002 5.091 2.07478002 4 P 0 
L 5.091 2.07478002 5.091 1.969 4 P 0 
L 5.091 1.969 5.115 1.945 4 P 0 
L 5.115 1.945 5.115 1.72828996 4 P 0 
L 5.115 1.72828996 5.29413996 1.54915 4 P 0 
L 5.29413996 1.54915 5.36085 1.54915 4 P 0 
L 5.36085 1.54915 5.395 1.515 4 P 0 
L 5.395 1.515 5.92 1.515 4 P 0 
P 5.92 1.515 10 P 0 8 0;1=0,3=1
P 5.135 2.155 10 P 0 8 0;1=2,3=1
L 5.115 2.065 5.115 1.96621998 4 P 0 
L 5.115 1.96621998 5.13 1.95121998 4 P 0 
L 5.13 1.95121998 5.13 1.74158002 4 P 0 
L 5.13 1.74158002 5.29658002 1.575 4 P 0 
L 5.29658002 1.575 5.385 1.575 4 P 0 
L 5.385 1.575 5.42 1.54 4 P 0 
L 5.42 1.54 5.845 1.54 4 P 0 
L 5.845 1.54 5.92 1.615 4 P 0 
L 5.92 1.615 5.92 1.63 4 P 0 
P 5.92 1.63 10 P 0 8 0;1=0,3=1
P 5.115 2.065 10 P 0 8 0;1=2,3=1
L 5.13 2.105 5.14 2.095 4 P 0 
L 5.14 2.095 5.14 2.036 4 P 0 
L 5.14 2.036 5.132 2.028 4 P 0 
L 5.132 2.028 5.132 1.97646998 4 P 0 
L 5.132 1.97646998 5.145 1.96346998 4 P 0 
L 5.145 1.96346998 5.145 1.84501004 4 P 0 
L 5.145 1.84501004 5.43001004 1.56 4 P 0 
L 5.43001004 1.56 5.83 1.56 4 P 0 
L 5.83 1.56 5.895 1.625 4 P 0 
L 5.895 1.625 5.895 1.7 4 P 0 
L 5.895 1.7 5.92 1.725 4 P 0 
L 5.92 1.725 5.92 1.73 4 P 0 
P 5.92 1.73 10 P 0 8 0;1=0,3=1
P 5.13 2.105 10 P 0 8 0;1=2,3=1
L 4.1 3.38 4.135 3.345 4 P 0 
L 4.135 3.345 4.27998996 3.345 4 P 0 
L 4.27998996 3.345 4.315 3.30998996 4 P 0 
L 4.315 3.30998996 4.315 3.27 4 P 0 
L 4.315 3.27 4.425 3.16 4 P 0 
L 4.425 3.16 4.5422 3.16 4 P 0 
L 4.5422 3.16 4.565 3.1372 4 P 0 
L 4.565 3.1372 4.565 3.105 4 P 0 
L 4.565 3.105 4.54 3.08 4 P 0 
L 4.54 3.08 4.54 3.015 4 P 0 
L 4.54 3.015 4.56 2.995 4 P 0 
L 4.56 2.995 4.56 2.82378002 4 P 0 
L 4.56 2.82378002 4.6625 2.72128002 4 P 0 
L 4.6625 2.72128002 4.6625 2.69066998 4 P 0 
L 4.6625 2.69066998 4.685 2.66816998 4 P 0 
L 4.685 2.66816998 4.685 2.645 4 P 0 
P 4.685 2.645 10 P 0 8 0;1=2,3=1
P 4.1 3.38 10 P 0 8 0;1=0,3=1
L 4.53 2.5 4.472 2.558 4 P 0 
L 4.472 2.558 4.472 2.689 4 P 0 
L 4.472 2.689 4.428 2.733 4 P 0 
L 4.428 2.733 4.428 2.947 4 P 0 
L 4.428 2.947 4.447 2.966 4 P 0 
L 4.447 2.966 4.447 2.998 4 P 0 
L 4.447 2.998 4.415 3.03 4 P 0 
L 4.415 3.03 4.415 3.09501004 4 P 0 
L 4.415 3.09501004 4.29 3.22001004 4 P 0 
L 4.29 3.22001004 4.29 3.295 4 P 0 
L 4.29 3.295 4.265 3.32 4 P 0 
L 4.265 3.32 4.205 3.32 4 P 0 
L 4.205 3.32 4.19 3.305 4 P 0 
L 4.19 3.305 3.98283002 3.305 4 P 0 
L 3.98283002 3.305 3.98233002 3.3045 4 P 0 
L 3.98233002 3.3045 3.96366998 3.3045 4 P 0 
L 3.96366998 3.3045 3.9505 3.31766998 4 P 0 
L 3.9505 3.31766998 3.9505 3.3345 4 P 0 
L 3.9505 3.3345 3.9 3.385 4 P 0 
P 4.53 2.5 10 P 0 8 0;1=2,3=1
P 3.9 3.385 10 P 0 8 0;1=0,3=1
L 4.575 2.374 4.5525 2.3965 4 P 0 
L 4.5525 2.3965 4.5525 2.3968 4 P 0 
L 4.5525 2.3968 4.5475 2.4018 4 P 0 
L 4.5475 2.4018 4.511 2.4018 4 P 0 
L 4.511 2.4018 4.506 2.4068 4 P 0 
L 4.506 2.4068 4.506 2.4218 4 P 0 
L 4.506 2.4218 4.511 2.4268 4 P 0 
L 4.511 2.4268 4.5475 2.4268 4 P 0 
L 4.5475 2.4268 4.5525 2.4318 4 P 0 
L 4.5525 2.4318 4.5525 2.4468 4 P 0 
L 4.5525 2.4468 4.5475 2.4518 4 P 0 
L 4.5475 2.4518 4.511 2.4518 4 P 0 
L 4.511 2.4518 4.506 2.4568 4 P 0 
L 4.506 2.4568 4.506 2.4718 4 P 0 
L 4.506 2.4718 4.511 2.4768 4 P 0 
L 4.511 2.4768 4.5475 2.4768 4 P 0 
L 4.5475 2.4768 4.5525 2.4818 4 P 0 
L 4.5525 2.4818 4.5525 2.525 4 P 0 
L 4.5525 2.525 4.52 2.5575 4 P 0 
L 4.52 2.5575 4.52 2.57798996 4 P 0 
L 4.52 2.57798996 4.525 2.58298996 4 P 0 
L 4.525 2.58298996 4.54 2.58298996 4 P 0 
L 4.54 2.58298996 4.545 2.58798996 4 P 0 
L 4.545 2.58798996 4.545 2.60298996 4 P 0 
L 4.545 2.60298996 4.54 2.60798996 4 P 0 
L 4.54 2.60798996 4.525 2.60798996 4 P 0 
L 4.525 2.60798996 4.52 2.61298996 4 P 0 
L 4.52 2.61298996 4.52 2.62798996 4 P 0 
L 4.52 2.62798996 4.525 2.63298996 4 P 0 
L 4.525 2.63298996 4.575 2.63298996 4 P 0 
L 4.575 2.63298996 4.58 2.63798996 4 P 0 
L 4.58 2.63798996 4.58 2.65298996 4 P 0 
L 4.58 2.65298996 4.575 2.65798996 4 P 0 
L 4.575 2.65798996 4.525 2.65798996 4 P 0 
L 4.525 2.65798996 4.52 2.66298996 4 P 0 
L 4.52 2.66298996 4.52 2.67798996 4 P 0 
L 4.52 2.67798996 4.525 2.68298996 4 P 0 
L 4.525 2.68298996 4.575 2.68298996 4 P 0 
L 4.575 2.68298996 4.58 2.68798996 4 P 0 
L 4.58 2.68798996 4.58 2.70298996 4 P 0 
L 4.58 2.70298996 4.575 2.70798996 4 P 0 
L 4.575 2.70798996 4.525 2.70798996 4 P 0 
L 4.525 2.70798996 4.52 2.71298996 4 P 0 
L 4.52 2.71298996 4.52 2.72798996 4 P 0 
L 4.52 2.72798996 4.525 2.73298996 4 P 0 
L 4.525 2.73298996 4.557 2.73298996 4 P 0 
L 4.557 2.73298996 4.562 2.73798996 4 P 0 
L 4.562 2.73798996 4.562 2.75298996 4 P 0 
L 4.562 2.75298996 4.557 2.75798996 4 P 0 
L 4.557 2.75798996 4.525 2.75798996 4 P 0 
L 4.525 2.75798996 4.4955 2.78748996 4 P 0 
L 4.4955 2.78748996 4.4955 2.98451004 4 P 0 
L 4.4955 2.98451004 4.46 3.02001004 4 P 0 
L 4.46 3.02001004 4.46 3.09 4 P 0 
L 4.46 3.09 4.485 3.115 4 P 0 
P 4.485 3.115 10 P 0 8 0;1=0,3=1
P 4.575 2.374 10 P 0 8 0;1=2,3=1
L 4.485 2.5 4.46 2.525 4 P 0 
L 4.46 2.525 4.4225 2.525 4 P 0 
L 4.4225 2.525 4.4175 2.53 4 P 0 
L 4.4175 2.53 4.4175 2.53948002 4 P 0 
L 4.4175 2.53948002 4.4125 2.54448002 4 P 0 
L 4.4125 2.54448002 4.376 2.54448002 4 P 0 
L 4.376 2.54448002 4.371 2.54948002 4 P 0 
L 4.371 2.54948002 4.371 2.56448002 4 P 0 
L 4.371 2.56448002 4.376 2.56948002 4 P 0 
L 4.376 2.56948002 4.4125 2.56948002 4 P 0 
L 4.4125 2.56948002 4.4175 2.57448002 4 P 0 
L 4.4175 2.57448002 4.4175 2.58948002 4 P 0 
L 4.4175 2.58948002 4.4125 2.59448002 4 P 0 
L 4.4125 2.59448002 4.376 2.59448002 4 P 0 
L 4.376 2.59448002 4.371 2.59948002 4 P 0 
L 4.371 2.59948002 4.371 2.61448002 4 P 0 
L 4.371 2.61448002 4.376 2.61948002 4 P 0 
L 4.376 2.61948002 4.4125 2.61948002 4 P 0 
L 4.4125 2.61948002 4.4175 2.62448002 4 P 0 
L 4.4175 2.62448002 4.4175 2.6835 4 P 0 
L 4.4175 2.6835 4.398 2.703 4 P 0 
L 4.398 2.703 4.361 2.703 4 P 0 
L 4.361 2.703 4.323 2.741 4 P 0 
L 4.323 2.741 4.323 2.81001004 4 P 0 
L 4.323 2.81001004 4.29441998 2.83858996 4 P 0 
L 4.29441998 2.83858996 4.29441998 2.95001998 4 P 0 
L 4.29441998 2.95001998 4.28941998 2.95501998 4 P 0 
L 4.28941998 2.95501998 4.247 2.95501998 4 P 0 
L 4.247 2.95501998 4.242 2.96001998 4 P 0 
L 4.242 2.96001998 4.242 2.97501998 4 P 0 
L 4.242 2.97501998 4.247 2.98001998 4 P 0 
L 4.247 2.98001998 4.28941998 2.98001998 4 P 0 
L 4.28941998 2.98001998 4.29441998 2.98501998 4 P 0 
L 4.29441998 2.98501998 4.29441998 3.00001998 4 P 0 
L 4.29441998 3.00001998 4.28941998 3.00501998 4 P 0 
L 4.28941998 3.00501998 4.247 3.00501998 4 P 0 
L 4.247 3.00501998 4.242 3.01001998 4 P 0 
L 4.242 3.01001998 4.242 3.02501998 4 P 0 
L 4.242 3.02501998 4.247 3.03001998 4 P 0 
L 4.247 3.03001998 4.28941998 3.03001998 4 P 0 
L 4.28941998 3.03001998 4.29441998 3.03501998 4 P 0 
L 4.29441998 3.03501998 4.29441998 3.05001998 4 P 0 
L 4.29441998 3.05001998 4.28941998 3.05501998 4 P 0 
L 4.28941998 3.05501998 4.247 3.05501998 4 P 0 
L 4.247 3.05501998 4.242 3.06001998 4 P 0 
L 4.242 3.06001998 4.242 3.07501998 4 P 0 
L 4.242 3.07501998 4.247 3.08001998 4 P 0 
L 4.247 3.08001998 4.28941998 3.08001998 4 P 0 
L 4.28941998 3.08001998 4.29441998 3.08501998 4 P 0 
L 4.29441998 3.08501998 4.29441998 3.10075 4 P 0 
P 4.485 2.5 10 P 0 8 0;1=2,3=1
P 4.29441998 3.10075 10 P 0 8 0;1=0,3=1
L 4.61 2.345 4.61 2.4 4 P 0 
L 4.61 2.4 4.5975 2.4125 4 P 0 
L 4.5975 2.4125 4.5975 2.51286998 4 P 0 
L 4.5975 2.51286998 4.627 2.54236998 4 P 0 
L 4.627 2.54236998 4.652 2.54236998 4 P 0 
L 4.652 2.54236998 4.657 2.54736998 4 P 0 
L 4.657 2.54736998 4.657 2.56236998 4 P 0 
L 4.657 2.56236998 4.652 2.56736998 4 P 0 
L 4.652 2.56736998 4.627 2.56736998 4 P 0 
L 4.627 2.56736998 4.622 2.57236998 4 P 0 
L 4.622 2.57236998 4.622 2.58736998 4 P 0 
L 4.622 2.58736998 4.627 2.59236998 4 P 0 
L 4.627 2.59236998 4.652 2.59236998 4 P 0 
L 4.652 2.59236998 4.657 2.59736998 4 P 0 
L 4.657 2.59736998 4.657 2.61236998 4 P 0 
L 4.657 2.61236998 4.652 2.61736998 4 P 0 
L 4.652 2.61736998 4.627 2.61736998 4 P 0 
L 4.627 2.61736998 4.622 2.62236998 4 P 0 
L 4.622 2.62236998 4.622 2.63901004 4 P 0 
L 4.622 2.63901004 4.64 2.65701004 4 P 0 
L 4.64 2.65701004 4.64 2.71 4 P 0 
L 4.64 2.71 4.54 2.81 4 P 0 
L 4.54 2.81 4.54 2.8696 4 P 0 
L 4.54 2.8696 4.535 2.8746 4 P 0 
L 4.535 2.8746 4.528 2.8746 4 P 0 
L 4.528 2.8746 4.523 2.8796 4 P 0 
L 4.523 2.8796 4.523 2.8946 4 P 0 
L 4.523 2.8946 4.528 2.8996 4 P 0 
L 4.528 2.8996 4.535 2.8996 4 P 0 
L 4.535 2.8996 4.54 2.9046 4 P 0 
L 4.54 2.9046 4.54 2.9196 4 P 0 
L 4.54 2.9196 4.535 2.9246 4 P 0 
L 4.535 2.9246 4.528 2.9246 4 P 0 
L 4.528 2.9246 4.523 2.9296 4 P 0 
L 4.523 2.9296 4.523 2.9446 4 P 0 
L 4.523 2.9446 4.528 2.9496 4 P 0 
L 4.528 2.9496 4.535 2.9496 4 P 0 
L 4.535 2.9496 4.54 2.9546 4 P 0 
L 4.54 2.9546 4.54 2.97 4 P 0 
L 4.54 2.97 4.48 3.03 4 P 0 
L 4.48 3.03 4.48 3.07 4 P 0 
L 4.48 3.07 4.535 3.125 4 P 0 
L 4.535 3.125 4.54 3.125 4 P 0 
P 4.61 2.345 10 P 0 8 0;1=2,3=1
P 4.54 3.125 10 P 0 8 0;1=0,3=1
L 4.085 3.21998002 4.205 3.09998002 4 P 0 
L 4.205 3.09998002 4.205 2.775 4 P 0 
L 4.205 2.775 4.35 2.63 4 P 0 
L 4.35 2.63 4.35 2.505 4 P 0 
P 4.085 3.21998002 10 P 0 8 0;1=0,3=1
P 4.35 2.505 10 P 0 8 0;1=2,3=1
L 0.785 0.8225 0.7679 0.8225 4 P 0 
L 0.7679 0.8225 0.74071004 0.79531004 4 P 0 
L 0.74071004 0.79531004 0.74071004 0.74428996 4 P 0 
L 0.74071004 0.74428996 0.78 0.705 4 P 0 
L 0.78 0.705 1.0953 0.705 4 P 0 
L 1.0953 0.705 1.1116 0.6887 4 P 0 
L 1.1116 0.6887 1.1913 0.6887 4 P 0 
L 1.1913 0.6887 1.26 0.62 4 P 0 
L 0.74 1.3 0.77813996 1.26186004 4 P 0 
L 0.77813996 1.26186004 0.77813996 1.09186004 4 P 0 
L 0.77813996 1.09186004 0.815 1.055 4 P 0 
L 0.815 1.055 0.815 0.88481998 4 P 0 
L 0.815 0.88481998 0.8105 0.88031998 4 P 0 
L 0.8105 0.88031998 0.8105 0.848 4 P 0 
L 0.8105 0.848 0.785 0.8225 4 P 0 
P 0.74 1.3 10 P 0 8 0;1=2,3=1
P 1.26 0.62 9 P 0 8 0;1=7,3=1
P 0.785 0.8225 10 P 0 8 0;1=2,3=1
L 0.76321004 0.783 0.76321004 0.75008002 4 P 0 
L 0.76321004 0.75008002 0.78828996 0.725 4 P 0 
L 0.78828996 0.725 0.86871998 0.725 4 P 0 
L 0.86871998 0.725 0.87371998 0.73 4 P 0 
L 0.87371998 0.73 0.87371998 0.7347 4 P 0 
L 0.87371998 0.7347 0.87871998 0.7397 4 P 0 
L 0.87871998 0.7397 0.89371998 0.7397 4 P 0 
L 0.89371998 0.7397 0.89871998 0.7347 4 P 0 
L 0.89871998 0.7347 0.89871998 0.73 4 P 0 
L 0.89871998 0.73 0.90371998 0.725 4 P 0 
L 0.90371998 0.725 0.91871998 0.725 4 P 0 
L 0.91871998 0.725 0.92371998 0.73 4 P 0 
L 0.92371998 0.73 0.92371998 0.7501 4 P 0 
L 0.92371998 0.7501 0.92871998 0.7551 4 P 0 
L 0.92871998 0.7551 0.94371998 0.7551 4 P 0 
L 0.94371998 0.7551 0.94871998 0.7501 4 P 0 
L 0.94871998 0.7501 0.94871998 0.73 4 P 0 
L 0.94871998 0.73 0.95371998 0.725 4 P 0 
L 0.95371998 0.725 0.96871998 0.725 4 P 0 
L 0.96871998 0.725 0.97371998 0.73 4 P 0 
L 0.97371998 0.73 0.97371998 0.7501 4 P 0 
L 0.97371998 0.7501 0.97871998 0.7551 4 P 0 
L 0.97871998 0.7551 0.99371998 0.7551 4 P 0 
L 0.99371998 0.7551 0.99871998 0.7501 4 P 0 
L 0.99871998 0.7501 0.99871998 0.73 4 P 0 
L 0.99871998 0.73 1.00371998 0.725 4 P 0 
L 1.00371998 0.725 1.10358996 0.725 4 P 0 
L 1.10358996 0.725 1.11988996 0.7087 4 P 0 
L 1.11988996 0.7087 1.2063 0.7087 4 P 0 
L 1.2063 0.7087 1.239 0.676 4 P 0 
L 1.239 0.676 1.254 0.676 4 P 0 
L 1.254 0.676 1.26 0.67 4 P 0 
L 0.76321004 0.783 0.77916998 0.783 4 P 0 
L 0.77916998 0.783 0.8675 0.87133002 4 P 0 
L 0.8675 0.87133002 0.8675 1.0325 4 P 0 
L 0.8675 1.0325 0.8 1.1 4 P 0 
L 0.8 1.1 0.8 1.28 4 P 0 
L 0.8 1.28 0.755 1.325 4 P 0 
L 0.755 1.325 0.72 1.325 4 P 0 
L 0.72 1.325 0.695 1.3 4 P 0 
P 0.695 1.3 10 P 0 8 0;1=2,3=1
P 1.26 0.67 9 P 0 8 0;1=7,3=1
P 0.76321004 0.783 10 P 0 8 0;1=2,3=1
L 3.01 3.17 2.94 3.17 8 P 0 
L 2.94 3.17 2.937 3.173 8 P 0 
P 2.937 3.173 10 P 0 8 0;1=0,3=1
P 3.01 3.17 10 P 0 8 0;1=2,3=1
L 1.42 0.69535 1.38685 0.7285 4 P 0 
L 1.38685 0.7285 1.34651004 0.7285 4 P 0 
L 1.34651004 0.7285 1.28501004 0.79 4 P 0 
L 1.28501004 0.79 1.1769 0.79 4 P 0 
L 1.1769 0.79 1.025 0.9419 4 P 0 
L 1.025 0.9419 1.025 1.26 4 P 0 
L 1.025 1.26 0.915 1.37 4 P 0 
L 0.915 1.37 0.915 1.4 4 P 0 
P 0.915 1.4 10 P 0 8 0;1=2,3=1
P 1.42 0.69535 9 P 0 8 0;1=7,3=1
L 0.965 1.4 0.965 1.355 4 P 0 
L 0.965 1.355 1.05 1.27 4 P 0 
L 1.05 1.27 1.05 1 4 P 0 
L 1.05 1 1.08405 0.96595 4 P 0 
L 1.08405 0.96595 1.08405 0.95886998 4 P 0 
L 1.08405 0.95886998 1.07103002 0.94585 4 P 0 
L 1.07103002 0.94585 1.07103002 0.93876998 4 P 0 
L 1.07103002 0.93876998 1.08163002 0.92816998 4 P 0 
L 1.08163002 0.92816998 1.08871004 0.92816998 4 P 0 
L 1.08871004 0.92816998 1.10173002 0.94118996 4 P 0 
L 1.10173002 0.94118996 1.10881004 0.94118996 4 P 0 
L 1.10881004 0.94118996 1.11941004 0.93058996 4 P 0 
L 1.11941004 0.93058996 1.11941004 0.92351004 4 P 0 
L 1.11941004 0.92351004 1.10638996 0.91048996 4 P 0 
L 1.10638996 0.91048996 1.10638996 0.90341004 4 P 0 
L 1.10638996 0.90341004 1.11698996 0.89281004 4 P 0 
L 1.11698996 0.89281004 1.12406998 0.89281004 4 P 0 
L 1.12406998 0.89281004 1.13708996 0.90583002 4 P 0 
L 1.13708996 0.90583002 1.14416998 0.90583002 4 P 0 
L 1.14416998 0.90583002 1.15476998 0.89523002 4 P 0 
L 1.15476998 0.89523002 1.15476998 0.88815 4 P 0 
L 1.15476998 0.88815 1.14175 0.87513002 4 P 0 
L 1.14175 0.87513002 1.14175 0.86805 4 P 0 
L 1.14175 0.86805 1.15235 0.85745 4 P 0 
L 1.15235 0.85745 1.15943002 0.85745 4 P 0 
L 1.15943002 0.85745 1.17245 0.87046998 4 P 0 
L 1.17245 0.87046998 1.17953002 0.87046998 4 P 0 
L 1.17953002 0.87046998 1.19013002 0.85986998 4 P 0 
L 1.19013002 0.85986998 1.19013002 0.85278996 4 P 0 
L 1.19013002 0.85278996 1.17711004 0.83976998 4 P 0 
L 1.17711004 0.83976998 1.17711004 0.83268996 4 P 0 
L 1.17711004 0.83268996 1.18771004 0.82208996 4 P 0 
L 1.18771004 0.82208996 1.19478996 0.82208996 4 P 0 
L 1.19478996 0.82208996 1.20781004 0.83511004 4 P 0 
L 1.20781004 0.83511004 1.21488996 0.83511004 4 P 0 
L 1.21488996 0.83511004 1.235 0.815 4 P 0 
L 1.235 0.815 1.33098996 0.815 4 P 0 
L 1.33098996 0.815 1.33598996 0.81 4 P 0 
L 1.33598996 0.81 1.33598996 0.799 4 P 0 
L 1.33598996 0.799 1.34098996 0.794 4 P 0 
L 1.34098996 0.794 1.35598996 0.794 4 P 0 
L 1.35598996 0.794 1.36098996 0.799 4 P 0 
L 1.36098996 0.799 1.36098996 0.81 4 P 0 
L 1.36098996 0.81 1.36598996 0.815 4 P 0 
L 1.36598996 0.815 1.3847 0.815 4 P 0 
L 1.3847 0.815 1.4207 0.779 4 P 0 
P 0.965 1.4 10 P 0 8 0;1=2,3=1
P 1.4207 0.779 9 P 0 8 0;1=7,3=1
L 4.33 3.535 4.375 3.49 4 P 0 
L 4.375 3.49 4.42328996 3.49 4 P 0 
L 4.42328996 3.49 4.55328996 3.36 4 P 0 
L 4.55328996 3.36 4.6 3.36 4 P 0 
L 4.6 3.36 4.68 3.28 4 P 0 
L 4.68 3.28 4.68 3.19286998 4 P 0 
L 4.68 3.19286998 4.749 3.12386998 4 P 0 
L 4.749 3.12386998 4.749 2.896 4 P 0 
L 4.749 2.896 4.8885 2.7565 4 P 0 
L 4.8885 2.7565 4.8885 2.3524 4 P 0 
L 4.8885 2.3524 4.81 2.2739 4 P 0 
L 4.81 2.2739 4.81 2.23998996 4 P 0 
L 4.81 2.23998996 4.75456998 2.18456004 4 P 0 
L 4.75456998 2.18456004 4.75456998 2.09248996 4 P 0 
L 4.75456998 2.09248996 4.74208002 2.08 4 P 0 
L 4.74208002 2.08 4.73618002 2.08 4 P 0 
L 4.73618002 2.08 4.7152 2.05901998 4 P 0 
L 4.7152 2.05901998 4.7152 2.05311998 4 P 0 
L 4.7152 2.05311998 4.70208002 2.04 4 P 0 
L 4.70208002 2.04 4.67873996 2.04 4 P 0 
L 4.67873996 2.04 4.65933002 2.02058996 4 P 0 
P 4.65933002 2.02058996 9 P 0 8 0;1=5,3=1
P 4.33 3.535 10 P 0 8 0;1=2,3=1
L 4.61996004 2.05996004 4.641 2.081 4 P 0 
L 4.641 2.081 4.641 2.106 4 P 0 
L 4.641 2.106 4.66 2.125 4 P 0 
L 4.66 2.125 4.66 2.21876998 4 P 0 
L 4.66 2.21876998 4.71 2.26876998 4 P 0 
L 4.71 2.26876998 4.71 2.30328996 4 P 0 
L 4.71 2.30328996 4.735 2.32828996 4 P 0 
L 4.735 2.32828996 4.735 2.48 4 P 0 
L 4.735 2.48 4.7525 2.4975 4 P 0 
L 4.7525 2.4975 4.7525 2.60961998 4 P 0 
L 4.7525 2.60961998 4.765 2.62211998 4 P 0 
L 4.765 2.62211998 4.765 2.78 4 P 0 
L 4.765 2.78 4.689 2.856 4 P 0 
L 4.689 2.856 4.689 3.099 4 P 0 
L 4.689 3.099 4.623 3.165 4 P 0 
L 4.623 3.165 4.615 3.165 4 P 0 
L 4.615 3.165 4.475 3.305 4 P 0 
L 4.475 3.305 4.475 3.34671004 4 P 0 
L 4.475 3.34671004 4.40671004 3.415 4 P 0 
L 4.40671004 3.415 4.395 3.415 4 P 0 
P 4.61996004 2.05996004 9 P 0 8 0;1=1,3=1
P 4.395 3.415 9 P 0 8 0;1=8,3=1
L 4.61996004 2.09933002 4.61996004 2.11196004 4 P 0 
L 4.61996004 2.11196004 4.639 2.131 4 P 0 
L 4.639 2.131 4.639 2.229 4 P 0 
L 4.639 2.229 4.655 2.245 4 P 0 
L 4.655 2.245 4.655 2.43001004 4 P 0 
L 4.655 2.43001004 4.7325 2.50751004 4 P 0 
L 4.7325 2.50751004 4.7325 2.62248996 4 P 0 
L 4.7325 2.62248996 4.745 2.63498996 4 P 0 
L 4.745 2.63498996 4.745 2.76501004 4 P 0 
L 4.745 2.76501004 4.669 2.84101004 4 P 0 
L 4.669 2.84101004 4.669 3.09071004 4 P 0 
L 4.669 3.09071004 4.61471004 3.145 4 P 0 
L 4.61471004 3.145 4.60671004 3.145 4 P 0 
L 4.60671004 3.145 4.47978002 3.27193002 4 P 0 
L 4.47978002 3.27193002 4.4727 3.27193002 4 P 0 
L 4.4727 3.27193002 4.46791998 3.26715 4 P 0 
L 4.46791998 3.26715 4.46083996 3.26715 4 P 0 
L 4.46083996 3.26715 4.45023996 3.27775 4 P 0 
L 4.45023996 3.27775 4.45023996 3.28483002 4 P 0 
L 4.45023996 3.28483002 4.45501998 3.28961004 4 P 0 
L 4.45501998 3.28961004 4.45501998 3.29668996 4 P 0 
L 4.45501998 3.29668996 4.4475 3.30421004 4 P 0 
L 4.4475 3.30421004 4.4475 3.33838996 4 P 0 
L 4.4475 3.33838996 4.425 3.36088996 4 P 0 
P 4.61996004 2.09933002 9 P 0 8 0;1=1,3=1
P 4.425 3.36088996 9 P 0 8 0;1=8,3=1
L 0.638 2.74 0.64248002 2.73551998 4 P 0 
L 0.64248002 2.73551998 0.64248002 2.66451998 4 P 0 
L 0.64248002 2.66451998 0.769 2.538 4 P 0 
L 0.769 2.538 0.769 2.331 4 P 0 
L 0.769 2.331 0.795 2.305 4 P 0 
L 0.795 2.305 0.825 2.305 4 P 0 
P 0.638 2.74 9 P 0 8 0;1=8,3=1
P 0.825 2.305 9 P 0 8 0;1=4,3=1
L 0.755 2.825 0.7365 2.8065 4 P 0 
L 0.7365 2.8065 0.7365 2.73408996 4 P 0 
L 0.7365 2.73408996 0.752 2.71858996 4 P 0 
L 0.752 2.71858996 0.752 2.58328996 4 P 0 
L 0.752 2.58328996 0.77631004 2.55898002 4 P 0 
L 0.77631004 2.55898002 0.81081004 2.55898002 4 P 0 
L 0.81081004 2.55898002 0.82398002 2.54581004 4 P 0 
L 0.82398002 2.54581004 0.82398002 2.52715 4 P 0 
L 0.82398002 2.52715 0.8175 2.52066998 4 P 0 
L 0.8175 2.52066998 0.8175 2.48008996 4 P 0 
L 0.8175 2.48008996 0.80213002 2.46471998 4 P 0 
L 0.80213002 2.46471998 0.80213002 2.35213002 4 P 0 
L 0.80213002 2.35213002 0.795 2.345 4 P 0 
P 0.755 2.825 9 P 0 8 0;1=8,3=1
P 0.795 2.345 9 P 0 8 0;1=4,3=1
L 4.06878996 2.02058996 4.05 2.03938002 4 P 0 
L 4.05 2.03938002 4.05 2.14998996 4 P 0 
L 4.05 2.14998996 4.0125 2.18748996 4 P 0 
L 4.0125 2.18748996 4.0125 2.3425 4 P 0 
L 4.0125 2.3425 3.955 2.4 4 P 0 
L 3.955 2.4 3.955 2.495 4 P 0 
L 3.955 2.495 3.9055 2.5445 4 P 0 
L 3.9055 2.5445 3.8416 2.5445 4 P 0 
L 3.8416 2.5445 3.7811 2.605 4 P 0 
L 3.7811 2.605 3.7417 2.605 4 P 0 
L 3.7417 2.605 3.7292 2.5925 4 P 0 
L 3.7292 2.5925 3.66908996 2.5925 4 P 0 
L 3.66908996 2.5925 3.63158996 2.555 4 P 0 
L 3.63158996 2.555 3.48941004 2.555 4 P 0 
L 3.48941004 2.555 3.46091004 2.5265 4 P 0 
L 3.46091004 2.5265 3.28121998 2.5265 4 P 0 
L 3.28121998 2.5265 3.25121998 2.4965 4 P 0 
L 3.25121998 2.4965 3.03846004 2.4965 4 P 0 
L 3.03846004 2.4965 2.94246004 2.4005 4 P 0 
L 2.94246004 2.4005 2.5525 2.4005 4 P 0 
L 2.5525 2.4005 2.506 2.447 4 P 0 
L 2.506 2.447 2.328 2.447 4 P 0 
L 2.328 2.447 2.3 2.419 4 P 0 
L 2.3 2.419 1.185 2.419 4 P 0 
L 1.185 2.419 1.014 2.248 4 P 0 
L 1.014 2.248 0.96278002 2.248 4 P 0 
L 0.96278002 2.248 0.92 2.20521998 4 P 0 
L 0.92 2.20521998 0.92 2.01 4 P 0 
L 0.92 2.01 0.905 1.995 4 P 0 
L 0.905 1.995 0.905 1.935 4 P 0 
P 4.06878996 2.02058996 9 P 0 8 0;1=1,3=1
P 0.905 1.935 10 P 0 8 0;1=0,3=1
L 3.99005 2.05996004 3.9718 2.07821004 4 P 0 
L 3.9718 2.07821004 3.9718 2.15563996 4 P 0 
L 3.9718 2.15563996 3.9125 2.21493996 4 P 0 
L 3.9125 2.21493996 3.9125 2.2464 4 P 0 
L 3.9125 2.2464 3.925 2.2589 4 P 0 
L 3.925 2.2589 3.925 2.335 4 P 0 
L 3.925 2.335 3.825 2.435 4 P 0 
L 3.825 2.435 3.72 2.435 4 P 0 
L 3.72 2.435 3.7 2.455 4 P 0 
L 3.7 2.455 3.7 2.47 4 P 0 
L 3.7 2.47 3.645 2.525 4 P 0 
L 3.645 2.525 3.50185 2.525 4 P 0 
L 3.50185 2.525 3.47335 2.4965 4 P 0 
L 3.47335 2.4965 3.3915 2.4965 4 P 0 
L 3.3915 2.4965 3.3395 2.4445 4 P 0 
L 3.3395 2.4445 3.2302 2.4445 4 P 0 
L 3.2302 2.4445 3.2082 2.4665 4 P 0 
L 3.2082 2.4665 3.0509 2.4665 4 P 0 
L 3.0509 2.4665 2.9549 2.3705 4 P 0 
L 2.9549 2.3705 2.5105 2.3705 4 P 0 
L 2.5105 2.3705 2.464 2.417 4 P 0 
L 2.464 2.417 2.382 2.417 4 P 0 
L 2.382 2.417 2.337 2.372 4 P 0 
L 2.337 2.372 1.191 2.372 4 P 0 
L 1.191 2.372 1.034 2.215 4 P 0 
L 1.034 2.215 0.976 2.215 4 P 0 
L 0.976 2.215 0.95 2.189 4 P 0 
L 0.95 2.189 0.95 1.975 4 P 0 
L 0.95 1.975 0.945 1.97 4 P 0 
P 3.99005 2.05996004 9 P 0 8 0;1=1,3=1
P 0.945 1.97 10 P 0 8 0;1=0,3=1
L 4.02941998 2.05996004 4.01391998 2.07546004 4 P 0 
L 4.01391998 2.07546004 4.01391998 2.15608002 4 P 0 
L 4.01391998 2.15608002 3.9675 2.2025 4 P 0 
L 3.9675 2.2025 3.9675 2.3475 4 P 0 
L 3.9675 2.3475 3.94 2.375 4 P 0 
L 3.94 2.375 3.94 2.48878002 4 P 0 
L 3.94 2.48878002 3.89928002 2.5295 4 P 0 
L 3.89928002 2.5295 3.8305 2.5295 4 P 0 
L 3.8305 2.5295 3.77 2.59 4 P 0 
L 3.77 2.59 3.74791998 2.59 4 P 0 
L 3.74791998 2.59 3.73541998 2.5775 4 P 0 
L 3.73541998 2.5775 3.6875 2.5775 4 P 0 
L 3.6875 2.5775 3.65 2.54 4 P 0 
L 3.65 2.54 3.49563002 2.54 4 P 0 
L 3.49563002 2.54 3.46713002 2.5115 4 P 0 
L 3.46713002 2.5115 3.28743996 2.5115 4 P 0 
L 3.28743996 2.5115 3.25743996 2.4815 4 P 0 
L 3.25743996 2.4815 3.04468002 2.4815 4 P 0 
L 3.04468002 2.4815 2.94868002 2.3855 4 P 0 
L 2.94868002 2.3855 2.5415 2.3855 4 P 0 
L 2.5415 2.3855 2.495 2.432 4 P 0 
L 2.495 2.432 2.348 2.432 4 P 0 
L 2.348 2.432 2.303 2.387 4 P 0 
L 2.303 2.387 1.179 2.387 4 P 0 
L 1.179 2.387 1.024 2.232 4 P 0 
L 1.024 2.232 0.968 2.232 4 P 0 
L 0.968 2.232 0.935 2.199 4 P 0 
L 0.935 2.199 0.935 2 4 P 0 
L 0.935 2 0.92 1.985 4 P 0 
L 0.92 1.985 0.92 1.95498996 4 P 0 
L 0.92 1.95498996 0.9275 1.94748996 4 P 0 
L 0.9275 1.94748996 0.9275 1.9075 4 P 0 
L 0.9275 1.9075 0.905 1.885 4 P 0 
P 4.02941998 2.05996004 9 P 0 8 0;1=1,3=1
P 0.905 1.885 10 P 0 8 0;1=0,3=1
L 3.95066998 2.02058996 3.932 2.03926004 4 P 0 
L 3.932 2.03926004 3.932 2.1687 4 P 0 
L 3.932 2.1687 3.88 2.2207 4 P 0 
L 3.88 2.2207 3.88 2.335 4 P 0 
L 3.88 2.335 3.86 2.355 4 P 0 
L 3.86 2.355 3.86 2.375 4 P 0 
L 3.86 2.375 3.825 2.41 4 P 0 
L 3.825 2.41 3.70426004 2.41 4 P 0 
L 3.70426004 2.41 3.67933002 2.43493002 4 P 0 
L 3.67933002 2.43493002 3.6444 2.43493002 4 P 0 
L 3.6444 2.43493002 3.57433002 2.505 4 P 0 
L 3.57433002 2.505 3.52 2.505 4 P 0 
L 3.52 2.505 3.485 2.47 4 P 0 
L 3.485 2.47 3.46141004 2.47 4 P 0 
L 3.46141004 2.47 3.42091004 2.4295 4 P 0 
L 3.42091004 2.4295 3.1645 2.4295 4 P 0 
L 3.1645 2.4295 3.1465 2.4115 4 P 0 
L 3.1465 2.4115 3.01711998 2.4115 4 P 0 
L 3.01711998 2.4115 2.96111998 2.3555 4 P 0 
L 2.96111998 2.3555 1.19571998 2.3555 4 P 0 
L 1.19571998 2.3555 1.02521998 2.185 4 P 0 
L 1.02521998 2.185 0.985 2.185 4 P 0 
L 0.63 2.15 0.5975 2.1825 4 P 0 
L 0.5975 2.1825 0.5975 2.19433002 4 P 0 
L 0.5975 2.19433002 0.57683002 2.215 4 P 0 
L 0.57683002 2.215 0.56 2.215 4 P 0 
L 0.56 2.215 0.445 2.33 4 P 0 
L 0.445 2.33 0.445 2.48001004 4 P 0 
L 0.445 2.48001004 0.29993002 2.62508002 4 P 0 
L 0.29993002 2.62508002 0.287 2.62508002 4 P 0 
P 0.63 2.15 10 P 0 8 0;1=2,3=1
P 3.95066998 2.02058996 9 P 0 8 0;1=1,3=1
P 0.985 2.185 10 P 0 8 0;1=0,3=1
P 0.287 2.62508002 10 P 0 8 0;1=2,3=1
L 0.99 2.015 0.99 2.03 4 P 0 
L 0.99 2.03 1.2555 2.2955 4 P 0 
L 1.2555 2.2955 3.0845 2.2955 4 P 0 
L 3.0845 2.2955 3.1035 2.2765 4 P 0 
L 3.1035 2.2765 3.1465 2.2765 4 P 0 
L 3.1465 2.2765 3.175 2.305 4 P 0 
L 3.175 2.305 3.245 2.305 4 P 0 
L 3.245 2.305 3.255 2.295 4 P 0 
L 3.255 2.295 3.3475 2.295 4 P 0 
L 3.3475 2.295 3.375 2.2675 4 P 0 
L 3.375 2.2675 3.5125 2.2675 4 P 0 
L 3.5125 2.2675 3.5415 2.2965 4 P 0 
L 3.5415 2.2965 3.7835 2.2965 4 P 0 
L 3.7835 2.2965 3.8 2.28 4 P 0 
L 3.8 2.28 3.8 2.175 4 P 0 
L 3.8 2.175 3.84813996 2.12686004 4 P 0 
L 3.84813996 2.12686004 3.84813996 2.08958996 4 P 0 
L 3.84813996 2.08958996 3.883 2.05473002 4 P 0 
L 3.883 2.05473002 3.883 2.02426998 4 P 0 
L 3.883 2.02426998 3.92605 1.98121998 4 P 0 
L 3.92605 1.98121998 3.95066998 1.98121998 4 P 0 
L 0.43 2.555 0.46 2.525 4 P 0 
L 0.46 2.525 0.46 2.34 4 P 0 
L 0.46 2.34 0.57 2.23 4 P 0 
L 0.57 2.23 0.58305 2.23 4 P 0 
L 0.58305 2.23 0.655 2.15805 4 P 0 
L 0.655 2.15805 0.655 2.13 4 P 0 
L 0.655 2.13 0.63 2.105 4 P 0 
P 0.43 2.555 10 P 0 8 0;1=0,3=1
P 3.95066998 1.98121998 9 P 0 8 0;1=1,3=1
P 0.63 2.105 10 P 0 8 0;1=2,3=1
P 0.99 2.015 10 P 0 8 0;1=2,3=1
L 0.99 1.975 0.965 2 4 P 0 
L 0.965 2 0.965 2.075 4 P 0 
L 0.965 2.075 1.2155 2.3255 4 P 0 
L 1.2155 2.3255 2.97356004 2.3255 4 P 0 
L 2.97356004 2.3255 3.02956004 2.3815 4 P 0 
L 3.02956004 2.3815 3.25348996 2.3815 4 P 0 
L 3.25348996 2.3815 3.27498996 2.36 4 P 0 
L 3.27498996 2.36 3.345 2.36 4 P 0 
L 3.345 2.36 3.3775 2.3925 4 P 0 
L 3.3775 2.3925 3.47945 2.3925 4 P 0 
L 3.47945 2.3925 3.49445 2.4075 4 P 0 
L 3.49445 2.4075 3.52555 2.4075 4 P 0 
L 3.52555 2.4075 3.54805 2.385 4 P 0 
L 3.54805 2.385 3.61813996 2.385 4 P 0 
L 3.61813996 2.385 3.64321004 2.35993002 4 P 0 
L 3.64321004 2.35993002 3.76263002 2.35993002 4 P 0 
L 3.76263002 2.35993002 3.83 2.29256004 4 P 0 
L 3.83 2.29256004 3.83 2.18 4 P 0 
L 3.83 2.18 3.8936 2.1164 4 P 0 
L 3.8936 2.1164 3.8936 2.0407 4 P 0 
L 3.8936 2.0407 3.9321 2.0022 4 P 0 
L 3.9321 2.0022 3.96906998 2.0022 1 P 0 
L 3.96906998 2.0022 3.99005 1.98121998 1 P 0 
L 0.63 2.06 0.605 2.085 4 P 0 
L 0.605 2.085 0.605 2.145 4 P 0 
L 0.605 2.145 0.59 2.16 4 P 0 
L 0.59 2.16 0.55 2.16 4 P 0 
L 0.55 2.16 0.545 2.165 4 P 0 
L 0.545 2.165 0.545 2.205 4 P 0 
L 0.545 2.205 0.525 2.225 4 P 0 
L 0.525 2.225 0.425 2.225 4 P 0 
L 0.425 2.225 0.355 2.295 4 P 0 
L 0.355 2.295 0.355 2.54878996 4 P 0 
L 0.355 2.54878996 0.30378996 2.6 4 P 0 
L 0.30378996 2.6 0.26708002 2.6 4 P 0 
L 0.26708002 2.6 0.242 2.62508002 4 P 0 
P 0.242 2.62508002 10 P 0 8 0;1=0,3=1
P 3.99005 1.98121998 9 P 0 8 0;1=1,3=1
P 0.63 2.06 10 P 0 8 0;1=2,3=1
P 0.99 1.975 10 P 0 8 0;1=2,3=1
L 4.02941998 1.82373996 4.01441998 1.83873996 1 P 0 
L 4.01441998 1.83873996 3.85126004 1.83873996 1 P 0 
L 3.85126004 1.83873996 3.82795 1.83873996 4 P 0 
L 3.82795 1.83873996 3.6736 1.99308996 4 P 0 
L 3.6736 1.99308996 3.57935 1.99308996 4 P 0 
L 3.57935 1.99308996 3.55393996 2.0185 4 P 0 
L 3.55393996 2.0185 3.12121998 2.0185 4 P 0 
L 3.12121998 2.0185 3.10521998 2.0025 4 P 0 
L 3.10521998 2.0025 3.065 2.0025 4 P 0 
L 3.065 2.0025 3.0425 2.025 4 P 0 
L 3.0425 2.025 2.985 2.025 4 P 0 
L 2.985 2.025 2.96 2.05 4 P 0 
L 2.96 2.05 2.635 2.05 4 P 0 
L 2.635 2.05 2.61 2.025 4 P 0 
L 2.61 2.025 2.495 2.025 4 P 0 
L 2.495 2.025 2.468 1.998 4 P 0 
L 2.468 1.998 2.467 1.998 4 P 0 
L 2.467 1.998 2.027 1.558 4 P 0 
L 2.027 1.558 0.966 1.558 4 P 0 
L 0.966 1.558 0.939 1.585 4 P 0 
L 0.939 1.585 0.88818002 1.585 4 P 0 
L 0.88818002 1.585 0.8275 1.52431998 4 P 0 
L 0.8275 1.52431998 0.8275 1.4175 4 P 0 
L 0.8275 1.4175 0.935 1.31 4 P 0 
L 0.935 1.31 0.935 1.3 4 P 0 
P 4.02941998 1.82373996 9 P 0 8 0;1=1,3=1
P 0.935 1.3 10 P 0 8 0;1=0,3=1
L 0.87 1.255 0.865 1.255 4 P 0 
L 0.865 1.255 0.79 1.33 4 P 0 
L 0.79 1.33 0.79 1.57641004 4 P 0 
L 0.79 1.57641004 0.90858996 1.695 4 P 0 
L 0.90858996 1.695 2.0375 1.695 4 P 0 
L 2.0375 1.695 2.45 2.1075 4 P 0 
L 2.45 2.1075 2.5625 2.1075 4 P 0 
L 2.5625 2.1075 2.58 2.125 4 P 0 
L 2.58 2.125 3.0075 2.125 4 P 0 
L 3.0075 2.125 3.025 2.1075 4 P 0 
L 3.025 2.1075 3.21993996 2.1075 4 P 0 
L 3.21993996 2.1075 3.23393996 2.0935 4 P 0 
L 3.23393996 2.0935 3.58503996 2.0935 4 P 0 
L 3.58503996 2.0935 3.60853996 2.07 4 P 0 
L 3.60853996 2.07 3.7028 2.07 4 P 0 
L 3.7028 2.07 3.8538 1.919 4 P 0 
L 3.8538 1.919 3.92478996 1.919 4 P 0 
L 3.92478996 1.919 3.94131004 1.90248002 4 P 0 
L 3.94131004 1.90248002 3.95066998 1.90248002 4 P 0 
P 3.95066998 1.90248002 9 P 0 8 0;1=1,3=1
P 0.87 1.255 10 P 0 8 0;1=0,3=1
L 0.935 1.25 0.9 1.285 4 P 0 
L 0.9 1.285 0.9 1.315 4 P 0 
L 0.9 1.315 0.81 1.405 4 P 0 
L 0.81 1.405 0.81 1.52803996 4 P 0 
L 0.81 1.52803996 0.88596004 1.604 4 P 0 
L 0.88596004 1.604 0.95243002 1.604 4 P 0 
L 0.95243002 1.604 0.96843002 1.62 4 P 0 
L 0.96843002 1.62 1.02 1.62 4 P 0 
L 1.02 1.62 1.036 1.604 4 P 0 
L 1.036 1.604 2.03056004 1.604 4 P 0 
L 2.03056004 1.604 2.48906004 2.0625 4 P 0 
L 2.48906004 2.0625 2.5925 2.0625 4 P 0 
L 2.5925 2.0625 2.61 2.08 4 P 0 
L 2.61 2.08 2.98 2.08 4 P 0 
L 2.98 2.08 2.9975 2.0625 4 P 0 
L 2.9975 2.0625 3.1975 2.0625 4 P 0 
L 3.1975 2.0625 3.2115 2.0485 4 P 0 
L 3.2115 2.0485 3.56638002 2.0485 4 P 0 
L 3.56638002 2.0485 3.59178996 2.02308996 4 P 0 
L 3.59178996 2.02308996 3.68605 2.02308996 4 P 0 
L 3.68605 2.02308996 3.82953996 1.8796 4 P 0 
L 3.82953996 1.8796 3.85888002 1.8796 4 P 0 
L 3.85888002 1.8796 3.9183 1.8796 1 P 0 
L 3.9183 1.8796 3.93478996 1.86311004 1 P 0 
L 3.93478996 1.86311004 3.95066998 1.86311004 1 P 0 
P 3.95066998 1.86311004 9 P 0 8 0;1=1,3=1
P 0.935 1.25 10 P 0 8 0;1=0,3=1
L 4.06878996 1.94185 4.05378996 1.95685 1 P 0 
L 4.05378996 1.95685 3.90813996 1.95685 1 P 0 
L 3.90813996 1.95685 3.8595 2.00548996 4 P 0 
L 3.8595 2.00548996 3.8595 2.0455 4 P 0 
L 3.8595 2.0455 3.825 2.08 4 P 0 
L 3.825 2.08 3.825 2.09833996 4 P 0 
L 3.825 2.09833996 3.79333996 2.13 4 P 0 
L 3.79333996 2.13 3.77378002 2.13 4 P 0 
L 3.77378002 2.13 3.73628002 2.1675 4 P 0 
L 3.73628002 2.1675 3.5975 2.1675 4 P 0 
L 3.5975 2.1675 3.5835 2.1535 4 P 0 
L 3.5835 2.1535 3.5215 2.1535 4 P 0 
L 3.5215 2.1535 3.5108 2.1642 4 P 0 
L 3.5108 2.1642 3.5108 2.19135 4 P 0 
L 3.5108 2.19135 3.46965 2.2325 4 P 0 
L 3.46965 2.2325 3.32778002 2.2325 4 P 0 
L 3.32778002 2.2325 3.28028002 2.185 4 P 0 
L 3.28028002 2.185 3.18621998 2.185 4 P 0 
L 3.18621998 2.185 3.15471998 2.2165 4 P 0 
L 3.15471998 2.2165 3.1035 2.2165 4 P 0 
L 3.1035 2.2165 3.0545 2.2655 4 P 0 
L 3.0545 2.2655 1.33671998 2.2655 4 P 0 
L 1.33671998 2.2655 0.935 1.86378002 4 P 0 
L 0.935 1.86378002 0.935 1.79998996 4 P 0 
L 0.935 1.79998996 0.925 1.78998996 4 P 0 
L 0.925 1.78998996 0.925 1.745 4 P 0 
L 0.925 1.745 0.92 1.74 4 P 0 
L 0.92 1.74 0.92 1.73 4 P 0 
P 4.06878996 1.94185 9 P 0 8 0;1=1,3=1
P 0.92 1.73 10 P 0 8 0;1=0,3=1
L 0.985 1.655 1.01 1.655 4 P 0 
L 1.01 1.655 1.04508002 1.61991998 4 P 0 
L 1.04508002 1.61991998 2.02526004 1.61991998 4 P 0 
L 2.02526004 1.61991998 2.48283996 2.0775 4 P 0 
L 2.48283996 2.0775 2.5825 2.0775 4 P 0 
L 2.5825 2.0775 2.6 2.095 4 P 0 
L 2.6 2.095 2.9925 2.095 4 P 0 
L 2.9925 2.095 3.01 2.0775 4 P 0 
L 3.01 2.0775 3.2075 2.0775 4 P 0 
L 3.2075 2.0775 3.2215 2.0635 4 P 0 
L 3.2215 2.0635 3.5726 2.0635 4 P 0 
L 3.5726 2.0635 3.59801004 2.03808996 4 P 0 
L 3.59801004 2.03808996 3.69226998 2.03808996 4 P 0 
L 3.69226998 2.03808996 3.83536004 1.895 4 P 0 
L 3.83536004 1.895 3.865 1.895 4 P 0 
L 3.865 1.895 3.91798996 1.895 1 P 0 
L 3.91798996 1.895 3.93388002 1.87911004 1 P 0 
L 3.93388002 1.87911004 4.05278996 1.87911004 1 P 0 
L 4.05278996 1.87911004 4.06878996 1.86311004 1 P 0 
P 4.06878996 1.86311004 9 P 0 8 0;1=1,3=1
P 0.985 1.655 10 P 0 8 0;1=0,3=1
L 4.06878996 1.82373996 4.04578996 1.84673996 1 P 0 
L 4.04578996 1.84673996 3.85826004 1.84673996 1 P 0 
L 3.85826004 1.84673996 3.85 1.855 1 P 0 
L 3.85 1.855 3.835 1.855 1 P 0 
L 3.835 1.855 3.83291004 1.855 4 P 0 
L 3.83291004 1.855 3.67981998 2.00808996 4 P 0 
L 3.67981998 2.00808996 3.58556998 2.00808996 4 P 0 
L 3.58556998 2.00808996 3.56016004 2.0335 4 P 0 
L 3.56016004 2.0335 3.115 2.0335 4 P 0 
L 3.115 2.0335 3.099 2.0175 4 P 0 
L 3.099 2.0175 3.0725 2.0175 4 P 0 
L 3.0725 2.0175 3.05 2.04 4 P 0 
L 3.05 2.04 2.995 2.04 4 P 0 
L 2.995 2.04 2.97 2.065 4 P 0 
L 2.97 2.065 2.62 2.065 4 P 0 
L 2.62 2.065 2.595 2.04 4 P 0 
L 2.595 2.04 2.48778002 2.04 4 P 0 
L 2.48778002 2.04 2.02878002 1.581 4 P 0 
L 2.02878002 1.581 0.994 1.581 4 P 0 
L 0.994 1.581 0.985 1.59 4 P 0 
P 4.06878996 1.82373996 9 P 0 8 0;1=1,3=1
P 0.985 1.59 10 P 0 8 0;1=0,3=1
L 0.99 1.885 1.3125 2.2075 4 P 0 
L 1.3125 2.2075 3.0625 2.2075 4 P 0 
L 3.0625 2.2075 3.0685 2.2015 4 P 0 
L 3.0685 2.2015 3.1485 2.2015 4 P 0 
L 3.1485 2.2015 3.185 2.165 4 P 0 
L 3.185 2.165 3.2815 2.165 4 P 0 
L 3.2815 2.165 3.334 2.2175 4 P 0 
L 3.334 2.2175 3.46343002 2.2175 4 P 0 
L 3.46343002 2.2175 3.4958 2.18513002 4 P 0 
L 3.4958 2.18513002 3.4958 2.15541998 4 P 0 
L 3.4958 2.15541998 3.51271998 2.1385 4 P 0 
L 3.51271998 2.1385 3.58971998 2.1385 4 P 0 
L 3.58971998 2.1385 3.60371998 2.1525 4 P 0 
L 3.60371998 2.1525 3.73006004 2.1525 4 P 0 
L 3.73006004 2.1525 3.77 2.11256004 4 P 0 
L 3.77 2.11256004 3.77 2.10666004 4 P 0 
L 3.77 2.10666004 3.84091004 2.03575 4 P 0 
L 3.84091004 2.03575 3.84091004 2.00091004 4 P 0 
P 3.84091004 2.00091004 10 P 0 8 0;1=0,3=1
P 0.99 1.885 10 P 0 8 0;1=2,3=1
L 3.87193002 2.09933002 3.87193002 2.12306998 4 P 0 
L 3.87193002 2.12306998 3.815 2.18 4 P 0 
L 3.815 2.18 3.815 2.28633996 4 P 0 
L 3.815 2.28633996 3.75641004 2.34493002 4 P 0 
L 3.75641004 2.34493002 3.59343002 2.34493002 4 P 0 
L 3.59343002 2.34493002 3.58086004 2.3575 4 P 0 
L 3.58086004 2.3575 3.55433002 2.3575 4 P 0 
L 3.55433002 2.3575 3.51933002 2.3925 4 P 0 
L 3.51933002 2.3925 3.50066998 2.3925 4 P 0 
L 3.50066998 2.3925 3.4875 2.37933002 4 P 0 
L 3.4875 2.37933002 3.4875 2.37 4 P 0 
L 3.4875 2.37 3.43 2.3125 4 P 0 
L 3.43 2.3125 3.32748996 2.3125 4 P 0 
L 3.32748996 2.3125 3.29498996 2.345 4 P 0 
L 3.29498996 2.345 3.26458996 2.345 4 P 0 
L 3.26458996 2.345 3.25458996 2.335 4 P 0 
L 3.25458996 2.335 3.2208 2.335 4 P 0 
L 3.2208 2.335 3.1893 2.3665 4 P 0 
L 3.1893 2.3665 3.03578002 2.3665 4 P 0 
L 3.03578002 2.3665 2.97978002 2.3105 4 P 0 
L 2.97978002 2.3105 1.2355 2.3105 4 P 0 
L 1.2355 2.3105 0.99 2.065 4 P 0 
P 3.87193002 2.09933002 9 P 0 8 0;1=5,3=1
P 0.99 2.065 10 P 0 8 0;1=2,3=1
L 3.9113 2.09933002 3.9113 2.16818002 4 P 0 
L 3.9113 2.16818002 3.865 2.21448002 4 P 0 
L 3.865 2.21448002 3.865 2.325 4 P 0 
L 3.865 2.325 3.845 2.345 4 P 0 
L 3.845 2.345 3.845 2.375 4 P 0 
L 3.845 2.375 3.825 2.395 4 P 0 
L 3.825 2.395 3.725 2.395 4 P 0 
L 3.725 2.395 3.70493002 2.37493002 4 P 0 
L 3.70493002 2.37493002 3.64943996 2.37493002 4 P 0 
L 3.64943996 2.37493002 3.61686998 2.4075 4 P 0 
L 3.61686998 2.4075 3.59568002 2.4075 4 P 0 
L 3.59568002 2.4075 3.5725 2.43068002 4 P 0 
L 3.5725 2.43068002 3.5725 2.43433002 4 P 0 
L 3.5725 2.43433002 3.55933002 2.4475 4 P 0 
L 3.55933002 2.4475 3.46971998 2.4475 4 P 0 
L 3.46971998 2.4475 3.43671998 2.4145 4 P 0 
L 3.43671998 2.4145 3.1795 2.4145 4 P 0 
L 3.1795 2.4145 3.1615 2.3965 4 P 0 
L 3.1615 2.3965 3.02333996 2.3965 4 P 0 
L 3.02333996 2.3965 2.96733996 2.3405 4 P 0 
L 2.96733996 2.3405 1.203 2.3405 4 P 0 
L 1.203 2.3405 1.0025 2.14 4 P 0 
L 1.0025 2.14 0.975 2.14 4 P 0 
P 3.9113 2.09933002 9 P 0 8 0;1=1,3=1
P 0.975 2.14 10 P 0 8 0;1=2,3=1
L 5.8 1.048 5.795 1.043 4 P 0 
L 5.795 1.043 5.472 1.043 4 P 0 
L 5.472 1.043 5.21 1.305 4 P 0 
L 5.21 1.305 5.21 1.575 4 P 0 
L 5.21 1.575 5.0425 1.7425 4 P 0 
L 5.0425 1.7425 5.0425 1.93651004 4 P 0 
L 5.0425 1.93651004 5.055 1.94901004 4 P 0 
L 5.055 1.94901004 5.055 2.08828996 4 P 0 
L 5.055 2.08828996 5.06 2.09328996 4 P 0 
L 5.06 2.09328996 5.06 2.18758996 4 P 0 
L 5.06 2.18758996 5.07541004 2.203 4 P 0 
L 5.07541004 2.203 5.12 2.203 4 P 0 
L 5.12 2.203 5.347 2.43 4 P 0 
L 5.347 2.43 5.38 2.43 4 P 0 
L 5.38 2.43 5.445 2.495 4 P 0 
L 5.445 2.495 5.642 2.495 4 P 0 
L 5.642 2.495 5.697 2.55 4 P 0 
L 5.697 2.55 5.697 2.633 4 P 0 
L 5.697 2.633 5.495 2.835 4 P 0 
L 5.495 2.835 5.495 2.94 4 P 0 
L 5.495 2.94 5.445 2.99 4 P 0 
L 5.445 2.99 5.285 2.99 4 P 0 
P 5.8 1.048 10 P 0 8 0;1=3,3=0
P 5.285 2.99 9 P 0 8 0;1=8,3=1
L 3.125 3.075 3.155 3.105 4 P 0 
L 3.155 3.105 3.41498996 3.105 4 P 0 
L 3.41498996 3.105 3.49998996 3.19 4 P 0 
L 3.49998996 3.19 3.854 3.19 4 P 0 
L 3.854 3.19 3.887 3.157 4 P 0 
L 3.887 3.157 3.99116998 3.157 4 P 0 
L 3.99116998 3.157 4.06816998 3.08 4 P 0 
L 4.06816998 3.08 4.088 3.08 4 P 0 
L 4.088 3.08 4.1075 3.0605 4 P 0 
L 4.1075 3.0605 4.1075 2.99566998 4 P 0 
L 4.1075 2.99566998 4.117 2.98616998 4 P 0 
L 4.117 2.98616998 4.117 2.805 4 P 0 
L 4.117 2.805 4.301 2.621 4 P 0 
L 4.301 2.621 4.301 2.45773996 4 P 0 
L 4.301 2.45773996 4.34436998 2.41436998 4 P 0 
L 4.34436998 2.41436998 4.34436998 2.17806998 4 P 0 
P 3.125 3.075 10 P 0 8 0;1=2,3=1
P 4.34436998 2.17806998 9 P 0 8 0;1=1,3=1
L 4.38373996 2.17806998 4.38373996 2.19673996 4 P 0 
L 4.38373996 2.19673996 4.39 2.203 4 P 0 
L 4.39 2.203 4.39 2.404 4 P 0 
L 4.39 2.404 4.3275 2.4665 4 P 0 
L 4.3275 2.4665 4.3275 2.62278996 4 P 0 
L 4.3275 2.62278996 4.168 2.78228996 4 P 0 
L 4.168 2.78228996 4.168 3.068 4 P 0 
L 4.168 3.068 4.096 3.14 4 P 0 
L 4.096 3.14 4.054 3.14 4 P 0 
L 4.054 3.14 4.017 3.177 4 P 0 
L 4.017 3.177 3.916 3.177 4 P 0 
L 3.916 3.177 3.8805 3.2125 4 P 0 
L 3.8805 3.2125 3.4925 3.2125 4 P 0 
L 3.4925 3.2125 3.405 3.125 4 P 0 
L 3.405 3.125 3.115 3.125 4 P 0 
L 3.115 3.125 3.085 3.095 4 P 0 
L 3.085 3.095 2.98 3.095 4 P 0 
L 2.98 3.095 2.97 3.105 4 P 0 
P 4.38373996 2.17806998 9 P 0 8 0;1=1,3=1
P 2.97 3.105 10 P 0 8 0;1=0,3=1
L 0.54 2.135 0.54 2.13 4 P 0 
L 0.54 2.13 0.536 2.126 4 P 0 
L 0.536 2.126 0.536 2.049 4 P 0 
L 0.536 2.049 0.564 2.021 4 P 0 
L 0.564 2.021 0.564 1.786 4 P 0 
L 0.564 1.786 0.61 1.74 4 P 0 
L 0.61 1.74 0.61 1.69206998 4 P 0 
L 0.61 1.69206998 0.64 1.66206998 4 P 0 
L 0.64 1.66206998 0.64 1.508 4 P 0 
L 0.64 1.508 0.59 1.458 4 P 0 
L 0.59 1.458 0.59 1.255 4 P 0 
L 0.59 1.255 0.6525 1.1925 4 P 0 
L 0.6525 1.1925 0.6525 1.1075 4 P 0 
L 0.6525 1.1075 0.67 1.09 4 P 0 
P 0.54 2.135 10 P 0 8 0;1=2,3=1
P 0.67 1.09 10 P 0 8 0;1=0,3=1
L 0.965 2.355 1.144 2.534 4 P 0 
L 1.144 2.534 1.99341004 2.534 4 P 0 
L 1.99341004 2.534 2.27 2.81058996 4 P 0 
L 2.27 2.81058996 2.27 3.15498996 4 P 0 
L 2.27 3.15498996 2.52251004 3.4075 4 P 0 
L 2.52251004 3.4075 3.3825 3.4075 4 P 0 
L 3.3825 3.4075 3.4325 3.4575 4 P 0 
L 3.4325 3.4575 3.5375 3.4575 4 P 0 
L 3.5375 3.4575 3.64 3.56 4 P 0 
L 3.64 3.56 3.82 3.56 4 P 0 
L 3.82 3.56 3.935 3.445 4 P 0 
L 3.935 3.445 4.23816998 3.445 4 P 0 
L 4.23816998 3.445 4.24566998 3.4375 4 P 0 
L 4.24566998 3.4375 4.31921004 3.4375 4 P 0 
L 4.31921004 3.4375 4.35171004 3.47 4 P 0 
L 4.35171004 3.47 4.415 3.47 4 P 0 
L 4.415 3.47 4.55 3.335 4 P 0 
L 4.55 3.335 4.59 3.335 4 P 0 
L 4.59 3.335 4.655 3.27 4 P 0 
L 4.655 3.27 4.655 3.18958002 4 P 0 
L 4.655 3.18958002 4.729 3.11558002 4 P 0 
L 4.729 3.11558002 4.729 2.881 4 P 0 
L 4.729 2.881 4.8635 2.7465 4 P 0 
L 4.8635 2.7465 4.8635 2.35568996 4 P 0 
L 4.8635 2.35568996 4.78 2.27218996 4 P 0 
L 4.78 2.27218996 4.78 2.245 4 P 0 
L 4.78 2.245 4.717 2.182 4 P 0 
L 4.717 2.182 4.717 2.11763002 4 P 0 
L 4.717 2.11763002 4.6987 2.09933002 4 P 0 
P 4.6987 2.09933002 9 P 0 8 0;1=1,3=1
P 0.965 2.355 10 P 0 8 0;1=0,3=1
L 0.48231998 2.6453 0.52 2.60761998 4 P 0 
L 0.52 2.60761998 0.52 2.53 4 P 0 
L 0.52 2.53 0.5645 2.4855 4 P 0 
L 0.5645 2.4855 0.5645 2.455 4 P 0 
L 0.5645 2.455 0.59 2.4295 4 P 0 
L 0.59 2.4295 0.59 2.2889 4 P 0 
L 0.59 2.2889 0.6025 2.2764 4 P 0 
L 0.6025 2.2764 0.6025 2.23883996 4 P 0 
L 0.6025 2.23883996 0.675 2.16633996 4 P 0 
L 0.675 2.16633996 0.675 2.07 4 P 0 
L 0.675 2.07 0.63 2.025 4 P 0 
L 0.63 2.025 0.6 2.025 4 P 0 
L 0.6 2.025 0.59 2.015 4 P 0 
L 0.59 2.015 0.59 1.86001004 4 P 0 
L 0.59 1.86001004 0.685 1.76501004 4 P 0 
L 0.685 1.76501004 0.685 1.52471004 4 P 0 
L 0.685 1.52471004 0.61 1.44971004 4 P 0 
L 0.61 1.44971004 0.61 1.27 4 P 0 
L 0.61 1.27 0.635 1.245 4 P 0 
L 0.635 1.245 0.67 1.245 4 P 0 
L 0.67 1.245 0.705 1.21 4 P 0 
L 0.705 1.21 0.705 1.155 4 P 0 
L 0.705 1.155 0.735 1.125 4 P 0 
P 0.735 1.125 10 P 0 8 0;1=0,3=1
P 0.48231998 2.6453 10 P 0 8 0;1=2,3=1
L 3.755 3.505 3.772 3.488 4 P 0 
L 3.772 3.488 3.862 3.488 4 P 0 
L 3.862 3.488 3.9275 3.4225 4 P 0 
L 3.9275 3.4225 4.11761998 3.4225 4 P 0 
L 4.11761998 3.4225 4.12511998 3.415 4 P 0 
L 4.12511998 3.415 4.325 3.415 4 P 0 
L 4.325 3.415 4.36 3.45 4 P 0 
L 4.36 3.45 4.4 3.45 4 P 0 
L 4.4 3.45 4.54 3.31 4 P 0 
L 4.54 3.31 4.585 3.31 4 P 0 
L 4.585 3.31 4.63 3.265 4 P 0 
L 4.63 3.265 4.63 3.18628996 4 P 0 
L 4.63 3.18628996 4.709 3.10728996 4 P 0 
L 4.709 3.10728996 4.709 2.866 4 P 0 
L 4.709 2.866 4.785 2.79 4 P 0 
L 4.785 2.79 4.785 2.708 4 P 0 
L 4.785 2.708 4.8375 2.6555 4 P 0 
L 4.8375 2.6555 4.8375 2.4025 4 P 0 
L 4.8375 2.4025 4.73 2.295 4 P 0 
L 4.73 2.295 4.73 2.24 4 P 0 
L 4.73 2.24 4.6832 2.1932 4 P 0 
L 4.6832 2.1932 4.6832 2.1542 4 P 0 
L 4.6832 2.1542 4.6987 2.1387 4 P 0 
P 3.755 3.505 9 P 0 8 0;1=8,3=1
P 4.6987 2.1387 9 P 0 8 0;1=1,3=1
P 2.078 0.8301 10 P 0 8 0;1=2,3=1
L 0.46 0.82 0.473 0.807 4 P 0 
L 0.473 0.807 0.473 0.75683002 4 P 0 
L 0.473 0.75683002 0.49521998 0.73461004 4 P 0 
L 0.49521998 0.73461004 0.49521998 0.72666998 4 P 0 
L 0.49521998 0.72666998 0.50838996 0.7135 4 P 0 
L 0.50838996 0.7135 0.51633002 0.7135 4 P 0 
L 0.51633002 0.7135 0.63983002 0.59 4 P 0 
L 0.63983002 0.59 0.8599 0.59 4 P 0 
L 0.8599 0.59 0.8905 0.6206 4 P 0 
L 0.8905 0.6206 1.1894 0.6206 4 P 0 
L 1.1894 0.6206 1.24 0.57 4 P 0 
L 1.24 0.57 1.45501004 0.57 4 P 0 
L 1.45501004 0.57 1.48501004 0.6 4 P 0 
L 1.48501004 0.6 1.515 0.6 4 P 0 
L 1.515 0.6 1.534 0.619 4 P 0 
L 1.534 0.619 1.559 0.619 4 P 0 
L 1.559 0.619 1.741 0.801 4 P 0 
L 1.741 0.801 2.0489 0.801 4 P 0 
L 2.0489 0.801 2.078 0.8301 4 P 0 
P 0.46 0.82 9 P 0 8 0;1=4,3=1
L 0.625 1.005 0.645 1.025 4 P 0 
L 0.645 1.025 0.645 1.05501004 4 P 0 
L 0.645 1.05501004 0.605 1.09501004 4 P 0 
L 0.605 1.09501004 0.605 1.145 4 P 0 
L 0.605 1.145 0.5599 1.1901 4 P 0 
L 0.5599 1.1901 0.5599 1.26933002 4 P 0 
L 0.5599 1.26933002 0.555 1.27423002 4 P 0 
L 0.555 1.27423002 0.555 1.33 4 P 0 
L 0.555 1.33 0.505 1.38 4 P 0 
L 0.505 1.38 0.505 1.4887 4 P 0 
L 0.505 1.4887 0.5413 1.525 4 P 0 
P 0.5413 1.525 10 P 0 8 0;1=0,3=1
P 0.625 1.005 10 P 0 8 0;1=2,3=1
L 4.14753002 1.86311004 4.12953996 1.8811 1 P 0 
L 4.12953996 1.8811 4.0794 1.8811 1 P 0 
L 4.0794 1.8811 4.07338996 1.88711004 1 P 0 
L 4.07338996 1.88711004 3.94068996 1.88711004 1 P 0 
L 3.94068996 1.88711004 3.9178 1.91 1 P 0 
L 3.9178 1.91 3.89 1.91 1 P 0 
L 3.89 1.91 3.84158002 1.91 4 P 0 
L 3.84158002 1.91 3.69848996 2.05308996 4 P 0 
L 3.69848996 2.05308996 3.60423002 2.05308996 4 P 0 
L 3.60423002 2.05308996 3.57881998 2.0785 4 P 0 
L 3.57881998 2.0785 3.22771998 2.0785 4 P 0 
L 3.22771998 2.0785 3.21371998 2.0925 4 P 0 
L 3.21371998 2.0925 3.0175 2.0925 4 P 0 
L 3.0175 2.0925 3 2.11 4 P 0 
L 3 2.11 2.59 2.11 4 P 0 
L 2.59 2.11 2.5725 2.0925 4 P 0 
L 2.5725 2.0925 2.47661998 2.0925 4 P 0 
L 2.47661998 2.0925 2.01903996 1.63491998 4 P 0 
L 2.01903996 1.63491998 1.06008002 1.63491998 4 P 0 
L 1.06008002 1.63491998 1.015 1.68 4 P 0 
L 1.015 1.68 0.975 1.68 4 P 0 
L 0.975 1.68 0.945 1.65 4 P 0 
L 0.945 1.65 0.945 1.63 4 P 0 
P 4.14753002 1.86311004 9 P 0 8 0;1=1,3=1
P 0.945 1.63 10 P 0 8 0;1=2,3=1
L 4.1869 1.86311004 4.165 1.88501004 1 P 0 
L 4.165 1.88501004 4.165 1.90858996 1 P 0 
L 4.165 1.90858996 4.14811004 1.92548002 1 P 0 
L 4.14811004 1.92548002 3.94561998 1.92548002 1 P 0 
L 3.94561998 1.92548002 3.9311 1.94 1 P 0 
L 3.9311 1.94 3.905 1.94 1 P 0 
L 3.905 1.94 3.865 1.98 4 P 0 
L 3.865 1.98 3.83523996 1.98 4 P 0 
L 3.83523996 1.98 3.71023996 2.105 4 P 0 
L 3.71023996 2.105 3.61598002 2.105 4 P 0 
L 3.61598002 2.105 3.59748002 2.1235 4 P 0 
L 3.59748002 2.1235 3.5065 2.1235 4 P 0 
L 3.5065 2.1235 3.4808 2.1492 4 P 0 
L 3.4808 2.1492 3.4808 2.17891004 4 P 0 
L 3.4808 2.17891004 3.45721004 2.2025 4 P 0 
L 3.45721004 2.2025 3.3425 2.2025 4 P 0 
L 3.3425 2.2025 3.2875 2.1475 4 P 0 
L 3.2875 2.1475 3.045 2.1475 4 P 0 
L 3.045 2.1475 3 2.1925 4 P 0 
L 3 2.1925 1.38751004 2.1925 4 P 0 
L 1.38751004 2.1925 0.9675 1.77248996 4 P 0 
L 0.9675 1.77248996 0.9675 1.7275 4 P 0 
L 0.9675 1.7275 0.975 1.72 4 P 0 
P 4.1869 1.86311004 9 P 0 8 0;1=1,3=1
P 0.975 1.72 10 P 0 8 0;1=2,3=1
L 0.835 1.885 0.78863002 1.93136998 4 P 0 
L 0.78863002 1.93136998 0.78863002 2.19 4 P 0 
L 0.78863002 2.19 0.67863002 2.3 4 P 0 
L 0.67863002 2.3 0.635 2.3 4 P 0 
L 0.635 2.3 0.625 2.31 4 P 0 
L 0.625 2.31 0.625 2.5001 4 P 0 
L 0.625 2.5001 0.6195 2.5056 4 P 0 
L 0.6195 2.5056 0.6195 2.5405 4 P 0 
L 0.6195 2.5405 0.5932 2.5668 4 P 0 
L 0.5932 2.5668 0.5932 2.76321004 4 P 0 
L 0.5932 2.76321004 0.61498996 2.785 4 P 0 
L 0.61498996 2.785 0.65878002 2.785 4 P 0 
L 0.65878002 2.785 0.73528002 2.8615 4 P 0 
L 0.73528002 2.8615 0.77013002 2.8615 4 P 0 
L 0.77013002 2.8615 0.78413002 2.8475 4 P 0 
L 0.78413002 2.8475 0.96993996 2.8475 4 P 0 
L 0.96993996 2.8475 0.99843996 2.876 4 P 0 
L 0.99843996 2.876 1.18701004 2.876 4 P 0 
L 1.18701004 2.876 1.19301004 2.882 4 P 0 
L 1.19301004 2.882 1.68576998 2.882 4 P 0 
L 1.68576998 2.882 1.955 3.15123002 4 P 0 
L 1.955 3.15123002 1.955 3.26708996 4 P 0 
L 1.955 3.26708996 2 3.31208996 4 P 0 
L 2 3.31208996 2 3.35105 4 P 0 
L 2 3.35105 2.0275 3.37855 4 P 0 
L 2.0275 3.37855 2.0275 3.39733002 4 P 0 
L 2.0275 3.39733002 2.04566998 3.4155 4 P 0 
L 2.04566998 3.4155 2.06445 3.4155 4 P 0 
L 2.06445 3.4155 2.18516004 3.53621004 4 P 0 
L 2.18516004 3.53621004 3.50621004 3.53621004 4 P 0 
L 3.50621004 3.53621004 3.745 3.775 4 P 0 
L 3.745 3.775 3.745 3.82621998 4 P 0 
L 3.745 3.82621998 3.85028002 3.9315 4 P 0 
L 3.85028002 3.9315 3.9135 3.9315 4 P 0 
L 3.9135 3.9315 3.935 3.91 4 P 0 
P 3.935 3.91 9 P 0 8 0;1=7,3=1
P 0.835 1.885 10 P 0 8 0;1=2,3=1
L 0.835 1.93 0.805 1.96 4 P 0 
L 0.805 1.96 0.805 2.2 4 P 0 
L 0.805 2.2 0.69 2.315 4 P 0 
L 0.69 2.315 0.67 2.315 4 P 0 
L 0.67 2.315 0.64 2.345 4 P 0 
L 0.64 2.345 0.64 2.425 4 P 0 
L 0.64 2.425 0.6745 2.4595 4 P 0 
L 0.6745 2.4595 0.6745 2.5284 4 P 0 
L 0.6745 2.5284 0.6584 2.5445 4 P 0 
L 0.6584 2.5445 0.64548996 2.5445 4 P 0 
L 0.64548996 2.5445 0.6118 2.57818996 4 P 0 
L 0.6118 2.57818996 0.6118 2.7568 4 P 0 
L 0.6118 2.7568 0.62 2.765 4 P 0 
L 0.62 2.765 0.66 2.765 4 P 0 
L 0.66 2.765 0.7415 2.8465 4 P 0 
L 0.7415 2.8465 0.76391004 2.8465 4 P 0 
L 0.76391004 2.8465 0.77791004 2.8325 4 P 0 
L 0.77791004 2.8325 0.97616004 2.8325 4 P 0 
L 0.97616004 2.8325 1.00466004 2.861 4 P 0 
L 1.00466004 2.861 1.19598996 2.861 4 P 0 
L 1.19598996 2.861 1.20198996 2.867 4 P 0 
L 1.20198996 2.867 1.69198996 2.867 4 P 0 
L 1.69198996 2.867 1.74848996 2.9235 4 P 0 
L 1.74848996 2.9235 1.86848996 2.9235 4 P 0 
L 1.86848996 2.9235 2.045 3.10001004 4 P 0 
L 2.045 3.10001004 2.045 3.33001004 4 P 0 
L 2.045 3.33001004 2.08 3.36501004 4 P 0 
L 2.08 3.36501004 2.08 3.40983002 4 P 0 
L 2.08 3.40983002 2.19138002 3.52121004 4 P 0 
L 2.19138002 3.52121004 3.51621004 3.52121004 4 P 0 
L 3.51621004 3.52121004 3.7725 3.7775 4 P 0 
L 3.7725 3.7775 3.7725 3.8225 4 P 0 
L 3.7725 3.8225 3.86 3.91 4 P 0 
L 3.86 3.91 3.885 3.91 4 P 0 
P 3.885 3.91 9 P 0 8 0;1=7,3=1
P 0.835 1.93 10 P 0 8 0;1=2,3=1
L 3.985 3.91 3.9485 3.9465 4 P 0 
L 3.9485 3.9465 3.84406004 3.9465 4 P 0 
L 3.84406004 3.9465 3.725 3.82743996 4 P 0 
L 3.725 3.82743996 3.725 3.77621998 4 P 0 
L 3.725 3.77621998 3.49998996 3.55121004 4 P 0 
L 3.49998996 3.55121004 2.24256998 3.55121004 4 P 0 
L 2.24256998 3.55121004 2.21878002 3.575 4 P 0 
L 2.21878002 3.575 2.04 3.575 4 P 0 
L 2.04 3.575 1.985 3.52 4 P 0 
L 1.985 3.52 1.985 3.31916998 4 P 0 
L 1.985 3.31916998 1.94 3.27416998 4 P 0 
L 1.94 3.27416998 1.94 3.16 4 P 0 
L 1.94 3.16 1.6925 2.9125 4 P 0 
L 1.6925 2.9125 1.42823002 2.9125 4 P 0 
L 1.42823002 2.9125 1.40823002 2.9325 4 P 0 
L 1.40823002 2.9325 1.38823002 2.9325 4 P 0 
L 1.38823002 2.9325 1.37273002 2.948 4 P 0 
L 1.37273002 2.948 1.207 2.948 4 P 0 
L 1.207 2.948 1.186 2.927 4 P 0 
L 1.186 2.927 1.002 2.927 4 P 0 
L 1.002 2.927 0.961 2.886 4 P 0 
L 0.961 2.886 0.87693002 2.886 4 P 0 
L 0.87693002 2.886 0.86691004 2.89601998 4 P 0 
L 0.86691004 2.89601998 0.84908996 2.89601998 4 P 0 
L 0.84908996 2.89601998 0.82956998 2.8765 4 P 0 
L 0.82956998 2.8765 0.72906004 2.8765 4 P 0 
L 0.72906004 2.8765 0.70506004 2.8525 4 P 0 
L 0.70506004 2.8525 0.66108996 2.8525 4 P 0 
L 0.66108996 2.8525 0.6485 2.83991004 4 P 0 
L 0.6485 2.83991004 0.6485 2.83973002 4 P 0 
L 0.6485 2.83973002 0.5782 2.76943002 4 P 0 
L 0.5782 2.76943002 0.5782 2.56058002 4 P 0 
L 0.5782 2.56058002 0.595 2.54378002 4 P 0 
L 0.595 2.54378002 0.595 2.50681998 4 P 0 
L 0.595 2.50681998 0.61 2.49181998 4 P 0 
L 0.61 2.49181998 0.61 2.29718996 4 P 0 
L 0.61 2.29718996 0.6225 2.28468996 4 P 0 
L 0.6225 2.28468996 0.6225 2.2475 4 P 0 
L 0.6225 2.2475 0.76843002 2.10156998 4 P 0 
L 0.76843002 2.10156998 0.76843002 1.84656998 4 P 0 
L 0.76843002 1.84656998 0.835 1.78 4 P 0 
P 3.985 3.91 9 P 0 8 0;1=7,3=1
P 0.835 1.78 10 P 0 8 0;1=2,3=1
L 0.955 1.92 0.97 1.935 4 P 0 
L 0.97 1.935 0.985 1.935 4 P 0 
L 0.985 1.935 1.3305 2.2805 4 P 0 
L 1.3305 2.2805 3.0645 2.2805 4 P 0 
L 3.0645 2.2805 3.1135 2.2315 4 P 0 
L 3.1135 2.2315 3.1415 2.2315 4 P 0 
L 3.1415 2.2315 3.15 2.24 4 P 0 
L 3.15 2.24 3.31406004 2.24 4 P 0 
L 3.31406004 2.24 3.32156004 2.2475 4 P 0 
L 3.32156004 2.2475 3.51431998 2.2475 4 P 0 
L 3.51431998 2.2475 3.54831998 2.2815 4 P 0 
L 3.54831998 2.2815 3.6435 2.2815 4 P 0 
L 3.6435 2.2815 3.78086004 2.14413996 4 P 0 
L 3.78086004 2.14413996 3.79193002 2.14413996 4 P 0 
L 3.79193002 2.14413996 3.83913996 2.09693002 4 P 0 
L 3.83913996 2.09693002 3.83913996 2.08586004 4 P 0 
L 3.83913996 2.08586004 3.872 2.053 4 P 0 
L 3.872 2.053 3.872 2.013 4 P 0 
L 3.872 2.013 3.91 1.975 4 P 0 
L 3.91 1.975 3.91878002 1.96621998 1 P 0 
L 3.91878002 1.96621998 4.07798002 1.96621998 1 P 0 
L 4.07798002 1.96621998 4.0843 1.9599 1 P 0 
L 4.0843 1.9599 4.1555 1.9599 1 P 0 
L 4.1555 1.9599 4.165 1.9504 1 P 0 
L 4.165 1.9504 4.165 1.92438002 1 P 0 
L 4.165 1.92438002 4.1869 1.90248002 1 P 0 
P 4.1869 1.90248002 9 P 0 8 0;1=1,3=1
P 0.955 1.92 10 P 0 8 0;1=2,3=1
L 0.99 1.755 0.99 1.77 4 P 0 
L 0.99 1.77 1.3975 2.1775 4 P 0 
L 1.3975 2.1775 2.99378002 2.1775 4 P 0 
L 2.99378002 2.1775 3.04878002 2.1225 4 P 0 
L 3.04878002 2.1225 3.22616004 2.1225 4 P 0 
L 3.22616004 2.1225 3.24016004 2.1085 4 P 0 
L 3.24016004 2.1085 3.3485 2.1085 4 P 0 
L 3.3485 2.1085 3.355 2.115 4 P 0 
L 3.355 2.115 3.355 2.145 4 P 0 
L 3.355 2.145 3.3875 2.1775 4 P 0 
L 3.3875 2.1775 3.41431998 2.1775 4 P 0 
L 3.41431998 2.1775 3.48331998 2.1085 4 P 0 
L 3.48331998 2.1085 3.59126004 2.1085 4 P 0 
L 3.59126004 2.1085 3.60976004 2.09 4 P 0 
L 3.60976004 2.09 3.70401998 2.09 4 P 0 
L 3.70401998 2.09 3.86401998 1.93 4 P 0 
L 3.86401998 1.93 3.9 1.93 4 P 0 
L 3.9 1.93 3.92878996 1.93 1 P 0 
L 3.92878996 1.93 3.94131004 1.91748002 1 P 0 
L 3.94131004 1.91748002 4.13253002 1.91748002 1 P 0 
L 4.13253002 1.91748002 4.14753002 1.90248002 1 P 0 
P 4.14753002 1.90248002 9 P 0 8 0;1=1,3=1
P 0.99 1.755 10 P 0 8 0;1=2,3=1
L 0.332 2.62508002 0.332 2.642 4 P 0 
L 0.332 2.642 0.375 2.685 4 P 0 
L 0.375 2.685 0.375 2.68621998 4 P 0 
L 0.375 2.68621998 0.50878002 2.82 4 P 0 
L 0.50878002 2.82 0.58615 2.82 4 P 0 
L 0.58615 2.82 0.64865 2.8825 4 P 0 
L 0.64865 2.8825 0.69261998 2.8825 4 P 0 
L 0.69261998 2.8825 0.71661998 2.9065 4 P 0 
L 0.71661998 2.9065 0.73966998 2.9065 4 P 0 
L 0.73966998 2.9065 0.77066998 2.9375 4 P 0 
L 0.77066998 2.9375 0.78933002 2.9375 4 P 0 
L 0.78933002 2.9375 0.79933002 2.9275 4 P 0 
L 0.79933002 2.9275 0.88648996 2.9275 4 P 0 
L 0.88648996 2.9275 0.91898996 2.96 4 P 0 
L 0.91898996 2.96 1.14643002 2.96 4 P 0 
L 1.14643002 2.96 1.16443002 2.978 4 P 0 
L 1.16443002 2.978 1.38516998 2.978 4 P 0 
L 1.38516998 2.978 1.40066998 2.9625 4 P 0 
L 1.40066998 2.9625 1.42066998 2.9625 4 P 0 
L 1.42066998 2.9625 1.44066998 2.9425 4 P 0 
L 1.44066998 2.9425 1.45933002 2.9425 4 P 0 
L 1.45933002 2.9425 1.46883002 2.952 4 P 0 
L 1.46883002 2.952 1.49005 2.952 4 P 0 
L 1.49005 2.952 1.51155 2.9735 4 P 0 
L 1.51155 2.9735 1.59166004 2.9735 4 P 0 
L 1.59166004 2.9735 1.62616004 3.008 4 P 0 
L 1.62616004 3.008 1.67801004 3.008 4 P 0 
L 1.67801004 3.008 1.69001004 3.02 4 P 0 
L 1.69001004 3.02 1.745 3.02 4 P 0 
L 1.745 3.02 1.865 3.14 4 P 0 
L 1.865 3.14 1.865 3.45708002 4 P 0 
L 1.865 3.45708002 2.02791998 3.62 4 P 0 
L 2.02791998 3.62 2.25621998 3.62 4 P 0 
L 2.25621998 3.62 2.29121998 3.585 4 P 0 
L 2.29121998 3.585 3.48801004 3.585 4 P 0 
L 3.48801004 3.585 3.685 3.78198996 4 P 0 
L 3.685 3.78198996 3.685 3.83498996 4 P 0 
L 3.685 3.83498996 3.87501004 4.025 4 P 0 
L 3.87501004 4.025 3.91 4.025 4 P 0 
L 3.91 4.025 3.935 4 4 P 0 
P 3.935 4 9 P 0 8 0;1=8,3=1
P 0.332 2.62508002 10 P 0 8 0;1=0,3=1
L 3.885 4 3.875 4 4 P 0 
L 3.875 4 3.705 3.83 4 P 0 
L 3.705 3.83 3.705 3.77743996 4 P 0 
L 3.705 3.77743996 3.49756004 3.57 4 P 0 
L 3.49756004 3.57 2.285 3.57 4 P 0 
L 2.285 3.57 2.26 3.595 4 P 0 
L 2.26 3.595 2.035 3.595 4 P 0 
L 2.035 3.595 1.925 3.485 4 P 0 
L 1.925 3.485 1.925 3.17121998 4 P 0 
L 1.925 3.17121998 1.71878002 2.965 4 P 0 
L 1.71878002 2.965 1.61283002 2.965 4 P 0 
L 1.61283002 2.965 1.57533002 2.9275 4 P 0 
L 1.57533002 2.9275 1.43445 2.9275 4 P 0 
L 1.43445 2.9275 1.41445 2.9475 4 P 0 
L 1.41445 2.9475 1.39445 2.9475 4 P 0 
L 1.39445 2.9475 1.37895 2.963 4 P 0 
L 1.37895 2.963 1.17065 2.963 4 P 0 
L 1.17065 2.963 1.15265 2.945 4 P 0 
L 1.15265 2.945 0.92521004 2.945 4 P 0 
L 0.92521004 2.945 0.89123002 2.91101998 4 P 0 
L 0.89123002 2.91101998 0.84286998 2.91101998 4 P 0 
L 0.84286998 2.91101998 0.82335 2.8915 4 P 0 
L 0.82335 2.8915 0.72283996 2.8915 4 P 0 
L 0.72283996 2.8915 0.69883996 2.8675 4 P 0 
L 0.69883996 2.8675 0.65486998 2.8675 4 P 0 
L 0.65486998 2.8675 0.59236998 2.805 4 P 0 
L 0.59236998 2.805 0.515 2.805 4 P 0 
L 0.515 2.805 0.39 2.68 4 P 0 
L 0.39 2.68 0.39 2.635 4 P 0 
L 0.39 2.635 0.405 2.62 4 P 0 
P 3.885 4 9 P 0 8 0;1=8,3=1
P 0.405 2.62 10 P 0 8 0;1=0,3=1
L 3.985 4 3.945 4.04 4 P 0 
L 3.945 4.04 3.86878996 4.04 4 P 0 
L 3.86878996 4.04 3.67 3.84121004 4 P 0 
L 3.67 3.84121004 3.67 3.78821004 4 P 0 
L 3.67 3.78821004 3.52178996 3.64 4 P 0 
L 3.52178996 3.64 3.3 3.64 4 P 0 
L 3.3 3.64 3.265 3.605 4 P 0 
L 3.265 3.605 2.29243996 3.605 4 P 0 
L 2.29243996 3.605 2.25743996 3.64 4 P 0 
L 2.25743996 3.64 2.02 3.64 4 P 0 
L 2.02 3.64 1.85 3.47 4 P 0 
L 1.85 3.47 1.85 3.26116998 4 P 0 
L 1.85 3.26116998 1.57733002 2.9885 4 P 0 
L 1.57733002 2.9885 1.54948996 2.9885 4 P 0 
L 1.54948996 2.9885 1.52198996 3.016 4 P 0 
L 1.52198996 3.016 1.304 3.016 4 P 0 
L 1.304 3.016 1.281 2.993 4 P 0 
L 1.281 2.993 1.15821004 2.993 4 P 0 
L 1.15821004 2.993 1.14021004 2.975 4 P 0 
L 1.14021004 2.975 0.9989 2.975 4 P 0 
L 0.9989 2.975 0.9564 3.0175 4 P 0 
L 0.9564 3.0175 0.9336 3.0175 4 P 0 
L 0.9336 3.0175 0.9301 3.014 4 P 0 
L 0.9301 3.014 0.92911998 3.014 4 P 0 
L 0.92911998 3.014 0.89761998 2.9825 4 P 0 
L 0.89761998 2.9825 0.8636 2.9825 4 P 0 
L 0.8636 2.9825 0.8361 2.955 4 P 0 
L 0.8361 2.955 0.765 2.955 4 P 0 
L 0.765 2.955 0.745 2.935 4 P 0 
L 0.745 2.935 0.6549 2.935 4 P 0 
L 0.6549 2.935 0.6474 2.9425 4 P 0 
L 0.6474 2.9425 0.59566998 2.9425 4 P 0 
L 0.59566998 2.9425 0.32316998 2.67 4 P 0 
L 0.32316998 2.67 0.245 2.67 4 P 0 
L 0.245 2.67 0.20008002 2.62508002 4 P 0 
L 0.20008002 2.62508002 0.19008002 2.62508002 4 P 0 
L 0.19008002 2.62508002 0.19 2.625 4 P 0 
P 3.985 4 9 P 0 8 0;1=8,3=1
P 0.19 2.625 10 P 0 8 0;1=0,3=1
L 0.75 1.417 0.705 1.462 4 P 0 
L 0.705 1.462 0.705 1.78 4 P 0 
L 0.705 1.78 0.62 1.865 4 P 0 
L 0.62 1.865 0.62 1.995 4 P 0 
P 0.62 1.995 10 P 0 8 0;1=3,3=0
P 0.75 1.417 10 P 0 8 0;1=2,3=1
L 4.26563996 1.82373996 4.24163996 1.79973996 1 P 0 
L 4.24163996 1.79973996 3.8681 1.79973996 1 P 0 
L 3.8681 1.79973996 3.86443996 1.8034 4 P 0 
L 3.86443996 1.8034 3.82085 1.8034 4 P 0 
L 3.82085 1.8034 3.66116004 1.96308996 4 P 0 
L 3.66116004 1.96308996 3.56691004 1.96308996 4 P 0 
L 3.56691004 1.96308996 3.5415 1.9885 4 P 0 
L 3.5415 1.9885 3.13366004 1.9885 4 P 0 
L 3.13366004 1.9885 3.11766004 1.9725 4 P 0 
L 3.11766004 1.9725 2.9825 1.9725 4 P 0 
L 2.9825 1.9725 2.94 2.015 4 P 0 
L 2.94 2.015 2.695 2.015 4 P 0 
L 2.695 2.015 2.67 1.99 4 P 0 
L 2.67 1.99 2.67 1.81 4 P 0 
L 2.67 1.81 2.37 1.51 4 P 0 
L 2.37 1.51 0.952 1.51 4 P 0 
P 4.26563996 1.82373996 9 P 0 8 0;1=1,3=1
P 0.952 1.51 10 P 0 8 0;1=0,3=1
L 4.22626998 1.82373996 4.21026998 1.80773996 1 P 0 
L 4.21026998 1.80773996 3.89056004 1.80773996 1 P 0 
L 3.89056004 1.80773996 3.8774 1.8209 1 P 0 
L 3.8774 1.8209 3.82456998 1.8209 4 P 0 
L 3.82456998 1.8209 3.66738002 1.97808996 4 P 0 
L 3.66738002 1.97808996 3.57313002 1.97808996 4 P 0 
L 3.57313002 1.97808996 3.54771998 2.0035 4 P 0 
L 3.54771998 2.0035 3.12743996 2.0035 4 P 0 
L 3.12743996 2.0035 3.11143996 1.9875 4 P 0 
L 3.11143996 1.9875 2.9975 1.9875 4 P 0 
L 2.9975 1.9875 2.95 2.035 4 P 0 
L 2.95 2.035 2.685 2.035 4 P 0 
L 2.685 2.035 2.65 2 4 P 0 
L 2.65 2 2.65 1.81251998 4 P 0 
L 2.65 1.81251998 2.37748002 1.54 4 P 0 
L 2.37748002 1.54 0.951 1.54 4 P 0 
L 0.951 1.54 0.939 1.552 4 P 0 
P 4.22626998 1.82373996 9 P 0 8 0;1=1,3=1
P 0.939 1.552 10 P 0 8 0;1=2,3=1
L 0.957 2.275 0.997 2.275 4 P 0 
L 0.997 2.275 1.156 2.434 4 P 0 
L 1.156 2.434 2.281 2.434 4 P 0 
L 2.281 2.434 2.309 2.462 4 P 0 
L 2.309 2.462 2.515 2.462 4 P 0 
L 2.515 2.462 2.5615 2.4155 4 P 0 
L 2.5615 2.4155 2.8465 2.4155 4 P 0 
L 2.8465 2.4155 3.035 2.604 4 P 0 
L 3.035 2.604 3.13 2.604 4 P 0 
L 3.13 2.604 3.1575 2.5765 4 P 0 
L 3.1575 2.5765 3.26566998 2.5765 4 P 0 
L 3.26566998 2.5765 3.27566998 2.5665 4 P 0 
L 3.27566998 2.5665 3.44433002 2.5665 4 P 0 
L 3.44433002 2.5665 3.46 2.58216998 4 P 0 
L 3.46 2.58216998 3.46 2.60683002 4 P 0 
L 3.46 2.60683002 3.47566998 2.6225 4 P 0 
L 3.47566998 2.6225 3.5325 2.6225 4 P 0 
L 3.5325 2.6225 3.56 2.65 4 P 0 
L 3.56 2.65 3.59501004 2.65 4 P 0 
L 3.59501004 2.65 3.61251004 2.6325 4 P 0 
L 3.61251004 2.6325 3.71261998 2.6325 4 P 0 
L 3.71261998 2.6325 3.72511998 2.645 4 P 0 
L 3.72511998 2.645 3.86328996 2.645 4 P 0 
L 3.86328996 2.645 4.0135 2.49478996 4 P 0 
L 4.0135 2.49478996 4.0135 2.42 4 P 0 
L 4.0135 2.42 4.07 2.3635 4 P 0 
L 4.07 2.3635 4.07 2.28681998 4 P 0 
L 4.07 2.28681998 4.13 2.22681998 4 P 0 
L 4.13 2.22681998 4.13 2.0485 4 P 0 
L 4.13 2.0485 4.1385 2.04 4 P 0 
L 4.1385 2.04 4.16 2.04 4 P 0 
L 4.16 2.04 4.17 2.03 4 P 0 
L 4.17 2.03 4.17 2.005 4 P 0 
L 4.17 2.005 4.175 2 4 P 0 
L 4.175 2 4.195 2 4 P 0 
L 4.195 2 4.205 1.99 4 P 0 
L 4.205 1.99 4.205 1.88438002 4 P 0 
L 4.205 1.88438002 4.22626998 1.86311004 4 P 0 
P 4.22626998 1.86311004 9 P 0 8 0;1=1,3=1
P 0.957 2.275 10 P 0 8 0;1=0,3=1
L 0.855 4.205 0.795 4.265 4 P 0 
L 0.795 4.265 0.6276 4.265 4 P 0 
L 0.6276 4.265 0.533 4.1704 4 P 0 
L 0.533 4.1704 0.533 3.693 4 P 0 
L 0.533 3.693 0.375 3.535 4 P 0 
L 0.375 3.535 0.135 3.535 4 P 0 
L 0.135 3.535 0.095 3.495 4 P 0 
L 0.095 3.495 0.095 2.89 4 P 0 
L 0.095 2.89 0.115 2.87 4 P 0 
L 0.115 2.87 0.115 2.825 4 P 0 
L 0.115 2.825 0.15 2.79 4 P 0 
P 0.855 4.205 9 P 0 8 0;1=8,3=1
P 0.15 2.79 10 P 0 8 0;1=0,3=1
L 0.9 4.205 0.825 4.28 4 P 0 
L 0.825 4.28 0.61138996 4.28 4 P 0 
L 0.61138996 4.28 0.518 4.18661004 4 P 0 
L 0.518 4.18661004 0.518 3.703 4 P 0 
L 0.518 3.703 0.37 3.555 4 P 0 
L 0.37 3.555 0.13 3.555 4 P 0 
L 0.13 3.555 0.08 3.505 4 P 0 
L 0.08 3.505 0.08 2.87 4 P 0 
L 0.08 2.87 0.09 2.86 4 P 0 
P 0.09 2.86 10 P 0 8 0;1=0,3=1
P 0.9 4.205 9 P 0 8 0;1=8,3=1
L 0.98 4.2 0.885 4.295 4 P 0 
L 0.885 4.295 0.5988 4.295 4 P 0 
L 0.5988 4.295 0.503 4.1992 4 P 0 
L 0.503 4.1992 0.503 3.718 4 P 0 
L 0.503 3.718 0.36 3.575 4 P 0 
L 0.36 3.575 0.125 3.575 4 P 0 
L 0.125 3.575 0.065 3.515 4 P 0 
L 0.065 3.515 0.065 2.815 4 P 0 
L 0.065 2.815 0.09 2.79 4 P 0 
P 0.09 2.79 10 P 0 8 0;1=0,3=1
P 0.98 4.2 9 P 0 8 0;1=8,3=1
L 4.10463002 3.83 4.07963002 3.805 4 P 0 
L 4.07963002 3.805 4.04 3.805 4 P 0 
L 4.04 3.805 4.03 3.815 4 P 0 
L 4.03 3.815 4.03 3.865 4 P 0 
L 4.03 3.865 4.04473996 3.87973996 4 P 0 
L 4.04473996 3.87973996 4.04473996 4.02025 4 P 0 
L 4.04473996 4.02025 3.98998996 4.075 4 P 0 
L 3.98998996 4.075 3.86135 4.075 4 P 0 
L 3.86135 4.075 3.635 3.84865 4 P 0 
L 3.635 3.84865 3.635 3.79565 4 P 0 
L 3.635 3.79565 3.50935 3.67 4 P 0 
L 3.50935 3.67 3.23695 3.67 4 P 0 
L 3.23695 3.67 3.20261004 3.63566004 4 P 0 
L 3.20261004 3.63566004 2.34933002 3.63566004 4 P 0 
L 2.34933002 3.63566004 2.30498996 3.68 4 P 0 
L 2.30498996 3.68 2.01 3.68 4 P 0 
L 2.01 3.68 1.81 3.48 4 P 0 
L 1.81 3.48 1.81 3.27 4 P 0 
L 1.81 3.27 1.594 3.054 4 P 0 
L 1.594 3.054 1.41783002 3.054 4 P 0 
L 1.41783002 3.054 1.41033002 3.0465 4 P 0 
L 1.41033002 3.0465 1.2885 3.0465 4 P 0 
L 1.2885 3.0465 1.267 3.025 4 P 0 
L 1.267 3.025 1.15183002 3.025 4 P 0 
L 1.15183002 3.025 1.09933002 3.0775 4 P 0 
L 1.09933002 3.0775 0.8925 3.0775 4 P 0 
L 0.8925 3.0775 0.8 2.985 4 P 0 
L 0.8 2.985 0.68055 2.985 4 P 0 
L 0.68055 2.985 0.66055 3.005 4 P 0 
L 0.66055 3.005 0.42 3.005 4 P 0 
L 0.42 3.005 0.3725 3.0525 4 P 0 
L 0.3725 3.0525 0.3725 3.1025 4 P 0 
L 0.3725 3.1025 0.33 3.145 4 P 0 
P 4.10463002 3.83 9 P 0 8 0;1=7,3=1
P 0.33 3.145 10 P 0 8 0;1=2,3=1
L 0.43 3.145 0.555 3.02 4 P 0 
L 0.555 3.02 0.6661 3.02 4 P 0 
L 0.6661 3.02 0.6861 3.04 4 P 0 
L 0.6861 3.04 0.83378002 3.04 4 P 0 
L 0.83378002 3.04 0.88628002 3.0925 4 P 0 
L 0.88628002 3.0925 1.4755 3.0925 4 P 0 
L 1.4755 3.0925 1.497 3.071 4 P 0 
L 1.497 3.071 1.581 3.071 4 P 0 
L 1.581 3.071 1.7 3.19 4 P 0 
L 1.7 3.19 1.7 3.235 4 P 0 
L 1.7 3.235 1.79 3.325 4 P 0 
L 1.79 3.325 1.79 3.485 4 P 0 
L 1.79 3.485 2 3.695 4 P 0 
L 2 3.695 2.33 3.695 4 P 0 
L 2.33 3.695 2.37433996 3.65066004 4 P 0 
L 2.37433996 3.65066004 3.19638996 3.65066004 4 P 0 
L 3.19638996 3.65066004 3.23073002 3.685 4 P 0 
L 3.23073002 3.685 3.50313002 3.685 4 P 0 
L 3.50313002 3.685 3.62 3.80186998 4 P 0 
L 3.62 3.80186998 3.62 3.85486998 4 P 0 
L 3.62 3.85486998 3.85513002 4.09 4 P 0 
L 3.85513002 4.09 3.99998002 4.09 4 P 0 
L 3.99998002 4.09 4.06241004 4.02756998 4 P 0 
L 4.06241004 4.02756998 4.06241004 3.83778002 4 P 0 
L 4.06241004 3.83778002 4.05463002 3.83 4 P 0 
P 4.05463002 3.83 9 P 0 8 0;1=7,3=1
P 0.43 3.145 10 P 0 8 0;1=2,3=1
L 4.15463002 3.83 4.11463002 3.79 4 P 0 
L 4.11463002 3.79 4.03 3.79 4 P 0 
L 4.03 3.79 4.005 3.815 4 P 0 
L 4.005 3.815 4.005 3.87 4 P 0 
L 4.005 3.87 4.02 3.885 4 P 0 
L 4.02 3.885 4.02 4.01 4 P 0 
L 4.02 4.01 3.97 4.06 4 P 0 
L 3.97 4.06 3.86756998 4.06 4 P 0 
L 3.86756998 4.06 3.655 3.84743002 4 P 0 
L 3.655 3.84743002 3.655 3.79443002 4 P 0 
L 3.655 3.79443002 3.51556998 3.655 4 P 0 
L 3.51556998 3.655 3.24316998 3.655 4 P 0 
L 3.24316998 3.655 3.20883002 3.62066004 4 P 0 
L 3.20883002 3.62066004 2.31933996 3.62066004 4 P 0 
L 2.31933996 3.62066004 2.28 3.66 4 P 0 
L 2.28 3.66 2.015 3.66 4 P 0 
L 2.015 3.66 1.83 3.475 4 P 0 
L 1.83 3.475 1.83 3.265 4 P 0 
L 1.83 3.265 1.603 3.038 4 P 0 
L 1.603 3.038 1.42305 3.038 4 P 0 
L 1.42305 3.038 1.41655 3.0315 4 P 0 
L 1.41655 3.0315 1.29471998 3.0315 4 P 0 
L 1.29471998 3.0315 1.27321998 3.01 4 P 0 
L 1.27321998 3.01 1.15398996 3.01 4 P 0 
L 1.15398996 3.01 1.13398996 2.99 4 P 0 
L 1.13398996 2.99 1.015 2.99 4 P 0 
L 1.015 2.99 0.965 3.04 4 P 0 
L 0.965 3.04 0.9339 3.04 4 P 0 
L 0.9339 3.04 0.8964 3.0025 4 P 0 
L 0.8964 3.0025 0.84248996 3.0025 4 P 0 
L 0.84248996 3.0025 0.80998996 2.97 4 P 0 
L 0.80998996 2.97 0.67433002 2.97 4 P 0 
L 0.67433002 2.97 0.65433002 2.99 4 P 0 
L 0.65433002 2.99 0.35 2.99 4 P 0 
L 0.35 2.99 0.28 3.06 4 P 0 
L 0.28 3.06 0.24 3.06 4 P 0 
L 0.24 3.06 0.18 3.12 4 P 0 
L 0.18 3.12 0.18 3.145 4 P 0 
P 4.15463002 3.83 9 P 0 8 0;1=7,3=1
P 0.18 3.145 10 P 0 8 0;1=2,3=1
P 0.736 2.525 9 P 0 8 0;1=8,3=1
L 0.714 2.329 0.744 2.359 8 P 0 
L 0.744 2.359 0.744 2.517 8 P 0 
L 0.744 2.517 0.736 2.525 8 P 0 
P 0.714 2.329 10 P 0 8 0;1=2,3=1
L 0.959 2.789 0.945 2.775 4 P 0 
L 0.945 2.775 0.945 2.603 4 P 0 
L 0.945 2.603 0.87 2.528 4 P 0 
L 0.87 2.528 0.87 2.465 4 P 0 
L 0.87 2.465 0.826 2.421 4 P 0 
L 0.826 2.421 0.826 2.352 4 P 0 
L 0.826 2.352 0.845 2.333 4 P 0 
L 0.845 2.333 0.845 2.31541004 4 P 0 
L 0.845 2.31541004 0.8465 2.31391004 4 P 0 
L 0.8465 2.31391004 0.8465 2.29608996 4 P 0 
L 0.8465 2.29608996 0.845 2.29458996 4 P 0 
L 0.845 2.29458996 0.845 2.18 4 P 0 
P 0.959 2.789 10 P 0 8 0;1=2,3=1
P 0.845 2.18 10 P 0 8 0;1=0,3=1
L 3.18 2.685 3.264 2.769 4 P 0 
L 3.264 2.769 3.494 2.769 4 P 0 
L 3.494 2.769 3.56 2.835 4 P 0 
L 3.56 2.835 3.775 2.835 4 P 0 
L 3.775 2.835 3.7765 2.8335 4 P 0 
L 3.7765 2.8335 3.90333002 2.8335 4 P 0 
L 3.90333002 2.8335 3.9165 2.82033002 4 P 0 
L 3.9165 2.82033002 3.9165 2.80348996 4 P 0 
L 3.9165 2.80348996 3.96748996 2.7525 4 P 0 
L 3.96748996 2.7525 4.015 2.7525 4 P 0 
L 4.015 2.7525 4.055 2.7125 4 P 0 
L 4.055 2.7125 4.1225 2.7125 4 P 0 
L 4.1225 2.7125 4.239 2.596 4 P 0 
L 4.239 2.596 4.239 2.416 4 P 0 
L 4.239 2.416 4.28 2.375 4 P 0 
L 4.28 2.375 4.28 2.22 4 P 0 
L 4.28 2.22 4.2875 2.2125 4 P 0 
L 4.2875 2.2125 4.2875 2.1325 4 P 0 
L 4.2875 2.1325 4.305 2.115 4 P 0 
L 4.305 2.115 4.305 1.96 4 P 0 
L 4.305 1.96 4.32315 1.94185 4 P 0 
L 4.32315 1.94185 4.34436998 1.94185 4 P 0 
P 4.34436998 1.94185 9 P 0 8 0;1=1,3=1
P 3.18 2.685 9 P 0 8 0;1=4,3=1
L 4.65933002 1.58753002 4.6678 1.596 4 P 0 
L 4.6678 1.596 4.77 1.596 4 P 0 
L 4.77 1.596 4.777 1.603 4 P 0 
L 4.777 1.603 4.93395 1.603 4 P 0 
L 4.93395 1.603 4.96445 1.5725 4 P 0 
L 4.96445 1.5725 4.9814 1.5725 4 P 0 
L 4.9814 1.5725 5.0025 1.5514 4 P 0 
L 5.0025 1.5514 5.0025 1.5225 4 P 0 
L 5.0025 1.5225 5.035 1.49 4 P 0 
P 5.035 1.49 10 P 0 8 0;1=3,3=0
P 4.65933002 1.58753002 9 P 0 8 0;1=1,3=1
L 4.58058996 1.6269 4.59748996 1.61 4 P 0 
L 4.59748996 1.61 4.758 1.61 4 P 0 
L 4.758 1.61 4.768 1.62 4 P 0 
L 4.768 1.62 4.93816998 1.62 4 P 0 
L 4.93816998 1.62 4.95066998 1.6075 4 P 0 
L 4.95066998 1.6075 4.9725 1.6075 4 P 0 
L 4.9725 1.6075 5.03 1.55 4 P 0 
P 5.03 1.55 10 P 0 8 0;1=3,3=0
P 4.58058996 1.6269 9 P 0 8 0;1=1,3=1
L 5.83 2.97 5.8505 2.9495 4 P 0 
L 5.8505 2.9495 5.8505 2.54481004 4 P 0 
L 5.8505 2.54481004 5.85763996 2.53766998 4 P 0 
L 5.85763996 2.53766998 5.85763996 2.42236998 4 P 0 
L 5.85763996 2.42236998 5.89953002 2.38048002 4 P 0 
L 5.89953002 2.38048002 5.89953002 2.366 4 P 0 
P 5.83 2.97 10 P 0 8 0;1=2,3=1
P 5.89953002 2.366 9 P 0 8 0;1=7,3=1
L 3.61123996 3.49876004 3.65248002 3.54 4 P 0 
L 3.65248002 3.54 3.675 3.54 4 P 0 
L 3.675 3.54 3.775 3.44 4 P 0 
L 3.775 3.44 3.87683002 3.44 4 P 0 
L 3.87683002 3.44 3.91433002 3.4025 4 P 0 
L 3.91433002 3.4025 4.10933002 3.4025 4 P 0 
L 4.10933002 3.4025 4.11683002 3.395 4 P 0 
L 4.11683002 3.395 4.25683002 3.395 4 P 0 
L 4.25683002 3.395 4.46683002 3.185 4 P 0 
L 4.46683002 3.185 4.53841998 3.185 4 P 0 
L 4.53841998 3.185 4.5925 3.13091998 4 P 0 
L 4.5925 3.13091998 4.5925 3.10066998 4 P 0 
L 4.5925 3.10066998 4.60158002 3.09158996 4 P 0 
L 4.60158002 3.09158996 4.60158002 3.05158002 4 P 0 
L 4.60158002 3.05158002 4.575 3.025 4 P 0 
L 4.575 3.025 4.575 2.83 4 P 0 
L 4.575 2.83 4.663 2.742 4 P 0 
L 4.663 2.742 4.683 2.742 4 P 0 
L 4.683 2.742 4.715 2.71 4 P 0 
L 4.715 2.71 4.715 2.635 4 P 0 
L 4.715 2.635 4.6785 2.5985 4 P 0 
L 4.6785 2.5985 4.6785 2.48351004 4 P 0 
L 4.6785 2.48351004 4.635 2.44001004 4 P 0 
L 4.635 2.44001004 4.635 2.29001004 4 P 0 
L 4.635 2.29001004 4.601 2.25601004 4 P 0 
L 4.601 2.25601004 4.601 1.971 4 P 0 
L 4.601 1.971 4.59 1.96 4 P 0 
L 4.59 1.96 4.57001004 1.96 4 P 0 
L 4.57001004 1.96 4.55186004 1.94185 4 P 0 
L 4.55186004 1.94185 4.54121998 1.94185 4 P 0 
P 3.61123996 3.49876004 9 P 0 8 0;1=4,3=1
P 4.54121998 1.94185 9 P 0 8 0;1=1,3=1
L 3.12 2.565 3.168 2.517 4 P 0 
L 3.168 2.517 3.24341998 2.517 4 P 0 
L 3.24341998 2.517 3.27291998 2.5465 4 P 0 
L 3.27291998 2.5465 3.45261998 2.5465 4 P 0 
L 3.45261998 2.5465 3.48111998 2.575 4 P 0 
L 3.48111998 2.575 3.6233 2.575 4 P 0 
L 3.6233 2.575 3.6608 2.6125 4 P 0 
L 3.6608 2.6125 3.72091004 2.6125 4 P 0 
L 3.72091004 2.6125 3.73341004 2.625 4 P 0 
L 3.73341004 2.625 3.79068996 2.625 4 P 0 
L 3.79068996 2.625 3.84593996 2.56975 4 P 0 
L 3.84593996 2.56975 3.91025 2.56975 4 P 0 
L 3.91025 2.56975 4 2.48 4 P 0 
L 4 2.48 4 2.395 4 P 0 
L 4 2.395 4.0325 2.3625 4 P 0 
L 4.0325 2.3625 4.0325 2.26068002 4 P 0 
L 4.0325 2.26068002 4.09166004 2.20151998 4 P 0 
L 4.09166004 2.20151998 4.09166004 2.00863996 4 P 0 
L 4.09166004 2.00863996 4.0989 2.0014 4 P 0 
L 4.0989 2.0014 4.1536 2.0014 4 P 0 
L 4.1536 2.0014 4.17378002 1.98121998 4 P 0 
L 4.17378002 1.98121998 4.1869 1.98121998 4 P 0 
P 4.1869 1.98121998 9 P 0 8 0;1=1,3=1
P 3.12 2.565 10 P 0 8 0;1=2,3=1
L 3.385 2.59 3.405 2.61 4 P 0 
L 3.405 2.61 3.405 2.66 4 P 0 
L 3.405 2.66 3.4275 2.6825 4 P 0 
L 3.4275 2.6825 3.5327 2.6825 4 P 0 
L 3.5327 2.6825 3.5452 2.67 4 P 0 
L 3.5452 2.67 3.6033 2.67 4 P 0 
L 3.6033 2.67 3.6208 2.6525 4 P 0 
L 3.6208 2.6525 3.70433002 2.6525 4 P 0 
L 3.70433002 2.6525 3.71683002 2.665 4 P 0 
L 3.71683002 2.665 3.8725 2.665 4 P 0 
L 3.8725 2.665 3.9975 2.54 4 P 0 
L 3.9975 2.54 4.0239 2.54 4 P 0 
L 4.0239 2.54 4.0575 2.5064 4 P 0 
L 4.0575 2.5064 4.0575 2.415 4 P 0 
L 4.0575 2.415 4.09 2.3825 4 P 0 
L 4.09 2.3825 4.09 2.29511004 4 P 0 
L 4.09 2.29511004 4.17 2.21511004 4 P 0 
L 4.17 2.21511004 4.17 2.085 4 P 0 
L 4.17 2.085 4.175 2.08 4 P 0 
L 4.175 2.08 4.2025 2.08 4 P 0 
L 4.2025 2.08 4.2075 2.075 4 P 0 
L 4.2075 2.075 4.2075 2.0125 4 P 0 
L 4.2075 2.0125 4.22 2 4 P 0 
L 4.22 2 4.23311998 2 4 P 0 
L 4.23311998 2 4.24811998 1.985 4 P 0 
L 4.24811998 1.985 4.24811998 1.92 4 P 0 
L 4.24811998 1.92 4.26563996 1.90248002 4 P 0 
P 4.26563996 1.90248002 9 P 0 8 0;1=1,3=1
P 3.385 2.59 10 P 0 8 0;1=0,3=1
L 5.155 2.01 5.155 2 4 P 0 
L 5.155 2 5.165 1.99 4 P 0 
L 5.165 1.99 5.165 1.865 4 P 0 
L 5.165 1.865 5.395 1.635 4 P 0 
L 5.395 1.635 5.45 1.635 4 P 0 
L 5.45 1.635 5.505 1.58 4 P 0 
L 5.505 1.58 5.815 1.58 4 P 0 
L 5.815 1.58 5.875 1.64 4 P 0 
L 5.875 1.64 5.875 1.78 4 P 0 
L 5.875 1.78 5.915 1.82 4 P 0 
L 5.915 1.82 6.015 1.82 4 P 0 
L 6.015 1.82 6.025 1.83 4 P 0 
P 5.155 2.01 10 P 0 8 0;1=2,3=1
P 6.025 1.83 10 P 0 8 0;1=0,3=1
L 2.554 2.901 2.675 2.78 4 P 0 
L 2.675 2.78 3.065 2.78 4 P 0 
L 3.065 2.78 3.15 2.695 4 P 0 
L 3.15 2.695 3.15 2.68 4 P 0 
L 3.15 2.68 3.17 2.66 4 P 0 
L 3.17 2.66 3.18541004 2.66 4 P 0 
L 3.18541004 2.66 3.26791004 2.7425 4 P 0 
L 3.26791004 2.7425 3.4975 2.7425 4 P 0 
L 3.4975 2.7425 3.54 2.785 4 P 0 
L 3.54 2.785 3.61903002 2.785 4 P 0 
L 3.61903002 2.785 3.64153002 2.7625 4 P 0 
L 3.64153002 2.7625 3.66846998 2.7625 4 P 0 
L 3.66846998 2.7625 3.69096998 2.785 4 P 0 
L 3.69096998 2.785 3.9067 2.785 4 P 0 
L 3.9067 2.785 3.9667 2.725 4 P 0 
L 3.9667 2.725 4.0075 2.725 4 P 0 
L 4.0075 2.725 4.1894 2.5431 4 P 0 
L 4.1894 2.5431 4.1894 2.4381 4 P 0 
L 4.1894 2.4381 4.25771004 2.36978996 4 P 0 
L 4.25771004 2.36978996 4.25771004 2.33271004 4 P 0 
L 4.25771004 2.33271004 4.235 2.31 4 P 0 
L 4.235 2.31 4.235 2.225 4 P 0 
L 4.235 2.225 4.2425 2.2175 4 P 0 
L 4.2425 2.2175 4.2425 2.1375 4 P 0 
L 4.2425 2.1375 4.25 2.13 4 P 0 
L 4.25 2.13 4.27113996 2.13 4 P 0 
L 4.27113996 2.13 4.29113996 2.11 4 P 0 
L 4.29113996 2.11 4.29113996 1.95571004 4 P 0 
L 4.29113996 1.95571004 4.34436998 1.90248002 4 P 0 
P 4.34436998 1.90248002 9 P 0 8 0;1=1,3=1
P 2.554 2.901 10 P 0 8 0;1=0,3=1
P 3.205 1.7 10 P 0 8 0;1=0,3=1
L 4.775 1.705 4.755 1.685 4 P 0 
L 4.755 1.685 3.82101004 1.685 4 P 0 
L 3.82101004 1.685 3.80301004 1.703 4 P 0 
L 3.80301004 1.703 3.703 1.703 4 P 0 
L 3.703 1.703 3.685 1.721 4 P 0 
L 3.685 1.721 3.494 1.721 4 P 0 
L 3.494 1.721 3.49 1.717 4 P 0 
L 3.49 1.717 3.222 1.717 4 P 0 
L 3.222 1.717 3.205 1.7 4 P 0 
P 4.775 1.705 10 P 0 8 0;1=2,3=1
L 4.58058996 1.82373996 4.59186004 1.82373996 4 P 0 
L 4.59186004 1.82373996 4.6106 1.805 4 P 0 
L 4.6106 1.805 4.745 1.805 4 P 0 
L 4.745 1.805 4.78266004 1.84266004 4 P 0 
L 4.78266004 1.84266004 4.82266004 1.84266004 4 P 0 
L 4.82266004 1.84266004 4.835 1.855 4 P 0 
L 4.835 1.855 4.84 1.855 4 P 0 
P 4.84 1.855 10 P 0 8 0;1=0,3=1
P 4.58058996 1.82373996 9 P 0 8 0;1=1,3=1
L 4.815 1.93 4.82 1.93 4 P 0 
L 4.82 1.93 4.875 1.985 4 P 0 
L 4.875 1.985 4.875 2.08451998 4 P 0 
L 4.875 2.08451998 4.8875 2.09701998 4 P 0 
L 4.8875 2.09701998 4.8875 2.15298002 4 P 0 
L 4.8875 2.15298002 4.87 2.17048002 4 P 0 
L 4.87 2.17048002 4.87 2.24388996 4 P 0 
L 4.87 2.24388996 5.01061004 2.3845 4 P 0 
L 5.01061004 2.3845 5.03133002 2.3845 4 P 0 
L 5.03133002 2.3845 5.0445 2.39766998 4 P 0 
L 5.0445 2.39766998 5.0445 2.41633002 4 P 0 
L 5.0445 2.41633002 5.035 2.42583002 4 P 0 
L 5.035 2.42583002 5.035 2.825 4 P 0 
L 5.035 2.825 5.112 2.902 4 P 0 
L 5.112 2.902 5.112 2.90211004 4 P 0 
L 5.112 2.90211004 5.118 2.90811004 4 P 0 
L 5.118 2.90811004 5.118 3.30016998 4 P 0 
L 5.118 3.30016998 5.03816998 3.38 4 P 0 
L 5.03816998 3.38 4.965 3.38 4 P 0 
L 4.965 3.38 4.885 3.46 4 P 0 
P 4.815 1.93 10 P 0 8 0;1=0,3=1
P 4.885 3.46 10 P 0 8 0;1=2,3=1
L 4.61996004 1.86311004 4.61996004 1.87295 4 P 0 
L 4.61996004 1.87295 4.64 1.89298996 4 P 0 
L 4.64 1.89298996 4.64 1.915 4 P 0 
L 4.64 1.915 4.65 1.925 4 P 0 
L 4.65 1.925 4.75681998 1.925 4 P 0 
L 4.75681998 1.925 4.805 1.97318002 4 P 0 
L 4.805 1.97318002 4.805 2 4 P 0 
L 4.805 2 4.8275 2.0225 4 P 0 
L 4.8275 2.0225 4.8275 2.06531004 4 P 0 
L 4.8275 2.06531004 4.8675 2.10531004 4 P 0 
L 4.8675 2.10531004 4.8675 2.14468996 4 P 0 
L 4.8675 2.14468996 4.85 2.16218996 4 P 0 
L 4.85 2.16218996 4.85 2.25218002 4 P 0 
L 4.85 2.25218002 4.9945 2.39668002 4 P 0 
L 4.9945 2.39668002 4.9945 2.5305 4 P 0 
L 4.9945 2.5305 4.9785 2.5465 4 P 0 
L 4.9785 2.5465 4.9785 2.7969 4 P 0 
L 4.9785 2.7969 5.098 2.9164 4 P 0 
L 5.098 2.9164 5.098 3.29188002 4 P 0 
L 5.098 3.29188002 5.03488002 3.355 4 P 0 
L 5.03488002 3.355 4.94001004 3.355 4 P 0 
L 4.94001004 3.355 4.83501004 3.46 4 P 0 
P 4.61996004 1.86311004 9 P 0 8 0;1=1,3=1
P 4.83501004 3.46 10 P 0 8 0;1=0,3=1
L 4.26563996 1.86311004 4.28213996 1.87961004 4 P 0 
L 4.28213996 1.87961004 4.28213996 1.99 4 P 0 
L 4.28213996 1.99 4.27353996 1.9986 4 P 0 
L 4.27353996 1.9986 4.2614 1.9986 4 P 0 
L 4.2614 1.9986 4.2469 2.0131 4 P 0 
L 4.2469 2.0131 4.2469 2.1131 4 P 0 
L 4.2469 2.1131 4.21833002 2.14166998 4 P 0 
L 4.21833002 2.14166998 4.21833002 2.22333002 4 P 0 
L 4.21833002 2.22333002 4.175 2.26666004 4 P 0 
L 4.175 2.26666004 4.175 2.315 4 P 0 
L 4.175 2.315 4.19 2.33 4 P 0 
L 4.19 2.33 4.19 2.375 4 P 0 
L 4.19 2.375 4.169 2.396 4 P 0 
L 4.169 2.396 4.169 2.531 4 P 0 
L 4.169 2.531 3.995 2.705 4 P 0 
L 3.995 2.705 3.95841004 2.705 4 P 0 
L 3.95841004 2.705 3.94091004 2.7225 4 P 0 
L 3.94091004 2.7225 3.79933002 2.7225 4 P 0 
L 3.79933002 2.7225 3.78933002 2.7125 4 P 0 
L 3.78933002 2.7125 3.77066998 2.7125 4 P 0 
L 3.77066998 2.7125 3.76066998 2.7225 4 P 0 
L 3.76066998 2.7225 3.65323996 2.7225 4 P 0 
L 3.65323996 2.7225 3.62643996 2.7493 4 P 0 
L 3.62643996 2.7493 3.57338996 2.7493 4 P 0 
L 3.57338996 2.7493 3.54658996 2.7225 4 P 0 
L 3.54658996 2.7225 3.2762 2.7225 4 P 0 
L 3.2762 2.7225 3.1972 2.6435 4 P 0 
L 3.1972 2.6435 3.19678996 2.6435 4 P 0 
L 3.19678996 2.6435 3.18933002 2.63603996 4 P 0 
L 3.18933002 2.63603996 3.16566998 2.63603996 4 P 0 
L 3.16566998 2.63603996 3.12 2.68171004 4 P 0 
L 3.12 2.68171004 3.12 2.69 4 P 0 
P 4.26563996 1.86311004 9 P 0 8 0;1=5,3=1
P 3.12 2.69 10 P 0 8 0;1=2,3=1
L 4.54121998 1.78436998 4.60345 1.72213996 4 P 0 
L 4.60345 1.72213996 4.74213996 1.72213996 4 P 0 
L 4.74213996 1.72213996 4.76933996 1.74933996 4 P 0 
L 4.76933996 1.74933996 4.85033002 1.74933996 4 P 0 
L 4.85033002 1.74933996 4.89466998 1.705 4 P 0 
L 4.89466998 1.705 4.99828996 1.705 4 P 0 
L 4.99828996 1.705 5.1225 1.58078996 4 P 0 
L 5.1225 1.58078996 5.1225 1.2875 4 P 0 
L 5.1225 1.2875 5.365 1.045 4 P 0 
L 5.365 1.045 5.365 1.005 4 P 0 
L 5.365 1.005 5.41 0.96 4 P 0 
P 5.41 0.96 10 P 0 8 0;1=3,3=0
P 4.85033002 1.74933996 10 P 0 8 0;1=2,3=1
P 4.54121998 1.78436998 9 P 0 8 0;1=1,3=1
L 3.625 0.92 3.62965 0.91535 6 P 0 
A 3.62965 0.91535 3.6345 0.90363996 3.61793848 0.90363996 6 P 0 Y
L 3.6345 0.90363996 3.6345 0.85678996 6 P 0 
A 3.6345 0.85678996 3.66551998 0.78188002 3.74045561 0.85678819 6 P 0 N
L 3.66551998 0.78188002 3.73216004 0.71523996 6 P 0 
A 3.73216004 0.71523996 3.80543996 0.6849 3.80542697 0.78853494 6 P 0 N
L 3.80543996 0.6849 4.69241998 0.6849 6 P 0 
A 4.69241998 0.6849 4.7842 0.7229 4.69244537 0.814675 6 P 0 N
L 4.7842 0.7229 4.94043002 0.87913996 6 P 0 
A 4.94043002 0.87913996 5.02096004 0.9125 5.02095512 0.79863327 6 P 0 Y
L 5.02096004 0.9125 5.73456998 0.9125 6 P 0 
A 5.73456998 0.9125 5.74273996 0.91313002 5.73456752 0.96581959 6 P 0 N
A 5.74273996 0.91313002 5.7957 0.94 5.72809557 1.00762008 6 P 0 N
L 5.7957 0.94 5.92108002 1.06538002 6 P 0 
A 5.92108002 1.06538002 5.947 1.12793996 5.85851909 1.1279499 6 P 0 N
L 5.947 1.12793996 5.947 1.17386004 6 P 0 
A 5.947 1.17386004 5.97071998 1.23111004 6.02796683 1.17385246 6 P 0 Y
L 5.97071998 1.23111004 5.9929 1.2533 6 P 0 
A 5.9929 1.2533 6.0465 1.3827 5.8634998 1.38270108 6 P 0 N
L 6.0465 1.3827 6.0465 1.66991004 6 P 0 
A 6.0465 1.66991004 6.07196998 1.73136998 6.1334189 1.66989695 6 P 0 Y
L 6.07196998 1.73136998 6.21408996 1.87346998 6 P 0 
A 6.21408996 1.87346998 6.2339 1.92131998 6.16623681 1.92130699 6 P 0 N
L 6.2339 1.92131998 6.2339 2.17343996 6 P 0 
A 6.2339 2.17343996 6.23621004 2.17901004 6.24179409 2.17343012 6 P 0 Y
L 6.23621004 2.17901004 6.24255 2.18535 6 P 0 
A 6.24255 2.18535 6.2542 2.2135 6.21439685 2.21348691 6 P 0 N
L 6.2542 2.2135 6.2542 2.24115 6 P 0 
A 6.2542 2.24115 6.22811004 2.26723996 6.22811004 2.24115 6 P 0 N
L 6.22811004 2.26723996 6.22191004 2.26723996 6 P 0 
A 6.22191004 2.26723996 6.20006004 2.27628996 6.22191004 2.29814193 6 P 0 Y
L 6.20006004 2.27628996 6.19961004 2.27673996 6 P 0 
P 3.625 0.92 9 P 0 8 0;1=9,3=1
P 6.19961004 2.27673996 9 P 0 8 0;1=9,3=1
L 6.19961004 2.24473996 6.20006004 2.24518996 6 P 0 
A 6.20006004 2.24518996 6.22191004 2.25423996 6.22190994 2.22333809 6 P 0 Y
L 6.22191004 2.25423996 6.22811004 2.25423996 6 P 0 
A 6.22811004 2.25423996 6.2412 2.24115 6.22811004 2.24115 6 P 0 Y
L 6.2412 2.24115 6.2412 2.2135 6 P 0 
A 6.2412 2.2135 6.23335 2.19455 6.21440226 2.2134999 6 P 0 Y
L 6.23335 2.19455 6.22701004 2.18821004 6 P 0 
A 6.22701004 2.18821004 6.2209 2.17343002 6.24179951 2.17344311 6 P 0 N
L 6.2209 2.17343002 6.2209 2.10061998 6 P 0 
A 6.2209 2.10061998 6.21765 2.09736998 6.21765 2.10061998 6 P 0 Y
A 6.21765 2.09736998 6.2144 2.09411998 6.21765 2.09411998 6 P 0 N
L 6.2144 2.09411998 6.2144 2.07581998 6 P 0 
A 6.2144 2.07581998 6.21765 2.07256998 6.21765 2.07581998 6 P 0 N
A 6.21765 2.07256998 6.2209 2.06931998 6.21765 2.06931998 6 P 0 Y
L 6.2209 2.06931998 6.2209 2.05101998 6 P 0 
A 6.2209 2.05101998 6.21765 2.04776998 6.21765 2.05101998 6 P 0 Y
A 6.21765 2.04776998 6.2144 2.04451998 6.21765 2.04451998 6 P 0 N
L 6.2144 2.04451998 6.2144 2.02621998 6 P 0 
A 6.2144 2.02621998 6.21765 2.02296998 6.21765 2.02621998 6 P 0 N
A 6.21765 2.02296998 6.2209 2.01971998 6.21765 2.01971998 6 P 0 Y
L 6.2209 2.01971998 6.2209 2.00141998 6 P 0 
A 6.2209 2.00141998 6.21765 1.99816998 6.21765 2.00141998 6 P 0 Y
A 6.21765 1.99816998 6.2144 1.99491998 6.21765 1.99491998 6 P 0 N
L 6.2144 1.99491998 6.2144 1.97661998 6 P 0 
A 6.2144 1.97661998 6.21765 1.97336998 6.21765 1.97661998 6 P 0 N
A 6.21765 1.97336998 6.2209 1.97011998 6.21765 1.97011998 6 P 0 Y
L 6.2209 1.97011998 6.2209 1.92131998 6 P 0 
A 6.2209 1.92131998 6.20488996 1.88266998 6.16624222 1.92131998 6 P 0 Y
L 6.20488996 1.88266998 6.18036998 1.85816004 6 P 0 
A 6.18036998 1.85816004 6.17553002 1.85816004 6.17795 1.86058002 6 P 0 Y
A 6.17553002 1.85816004 6.17068996 1.85816004 6.17310994 1.85573996 6 P 0 N
L 6.17068996 1.85816004 6.15798996 1.84546004 6 P 0 
A 6.15798996 1.84546004 6.15798996 1.84061998 6.16041004 1.84303996 6 P 0 N
A 6.15798996 1.84061998 6.15798996 1.83578002 6.15556998 1.8382 6 P 0 Y
L 6.15798996 1.83578002 6.14528996 1.82308002 6 P 0 
A 6.14528996 1.82308002 6.14045 1.82308002 6.14286998 1.8255 6 P 0 Y
A 6.14045 1.82308002 6.13561004 1.82308002 6.13803002 1.82066004 6 P 0 N
L 6.13561004 1.82308002 6.12291004 1.81038002 6 P 0 
A 6.12291004 1.81038002 6.12291004 1.80553996 6.12533002 1.80795994 6 P 0 N
A 6.12291004 1.80553996 6.12291004 1.8007 6.12048996 1.80311998 6 P 0 Y
L 6.12291004 1.8007 6.11021004 1.788 6 P 0 
A 6.11021004 1.788 6.10536998 1.788 6.10778996 1.79041998 6 P 0 Y
A 6.10536998 1.788 6.10053002 1.788 6.10295 1.78558002 6 P 0 N
L 6.10053002 1.788 6.08783002 1.7753 6 P 0 
A 6.08783002 1.7753 6.08783002 1.77046004 6.09025 1.77288002 6 P 0 N
A 6.08783002 1.77046004 6.08783002 1.76561998 6.08541004 1.76803996 6 P 0 Y
L 6.08783002 1.76561998 6.06276998 1.74056998 6 P 0 
A 6.06276998 1.74056998 6.0335 1.66991004 6.13342431 1.66990994 6 P 0 N
L 6.0335 1.66991004 6.0335 1.59351998 6 P 0 
A 6.0335 1.59351998 6.03015 1.59016998 6.03015 1.59351998 6 P 0 Y
A 6.03015 1.59016998 6.0268 1.58681998 6.03015 1.58681998 6 P 0 N
L 6.0268 1.58681998 6.0268 1.56871998 6 P 0 
A 6.0268 1.56871998 6.03015 1.56536998 6.03015 1.56871998 6 P 0 N
A 6.03015 1.56536998 6.0335 1.56201998 6.03015 1.56201998 6 P 0 Y
L 6.0335 1.56201998 6.0335 1.54391998 6 P 0 
A 6.0335 1.54391998 6.03015 1.54056998 6.03015 1.54391998 6 P 0 Y
A 6.03015 1.54056998 6.0268 1.53721998 6.03015 1.53721998 6 P 0 N
L 6.0268 1.53721998 6.0268 1.51911998 6 P 0 
A 6.0268 1.51911998 6.03015 1.51576998 6.03015 1.51911998 6 P 0 N
A 6.03015 1.51576998 6.0335 1.51241998 6.03015 1.51241998 6 P 0 Y
L 6.0335 1.51241998 6.0335 1.49431998 6 P 0 
A 6.0335 1.49431998 6.03015 1.49096998 6.03015 1.49431998 6 P 0 Y
A 6.03015 1.49096998 6.0268 1.48761998 6.03015 1.48761998 6 P 0 N
L 6.0268 1.48761998 6.0268 1.46951998 6 P 0 
A 6.0268 1.46951998 6.03015 1.46616998 6.03015 1.46951998 6 P 0 N
A 6.03015 1.46616998 6.0335 1.46281998 6.03015 1.46281998 6 P 0 Y
L 6.0335 1.46281998 6.0335 1.38271004 6 P 0 
A 6.0335 1.38271004 5.9837 1.2625 5.86350522 1.38271407 6 P 0 Y
L 5.9837 1.2625 5.96151998 1.24031004 6 P 0 
A 5.96151998 1.24031004 5.934 1.17386998 6.02797224 1.17386545 6 P 0 N
L 5.934 1.17386998 5.934 1.12795 6 P 0 
A 5.934 1.12795 5.91188002 1.07458002 5.85852441 1.12796299 6 P 0 Y
L 5.91188002 1.07458002 5.7865 0.9492 6 P 0 
A 5.7865 0.9492 5.74073996 0.92598002 5.72808563 1.00761811 6 P 0 Y
A 5.74073996 0.92598002 5.73456004 0.9255 5.73453691 0.96581801 6 P 0 Y
L 5.73456004 0.9255 5.02095 0.9255 6 P 0 
A 5.02095 0.9255 4.93123996 0.88833996 5.02095039 0.79863199 6 P 0 N
L 4.93123996 0.88833996 4.775 0.7321 6 P 0 
A 4.775 0.7321 4.69243002 0.6979 4.69243238 0.81466959 6 P 0 Y
L 4.69243002 0.6979 3.80543996 0.6979 6 P 0 
A 3.80543996 0.6979 3.74136004 0.72443996 3.80543996 0.78852963 6 P 0 Y
L 3.74136004 0.72443996 3.67471998 0.79108002 6 P 0 
A 3.67471998 0.79108002 3.6475 0.8568 3.7404502 0.85680118 6 P 0 Y
L 3.6475 0.8568 3.6475 0.90586998 6 P 0 
A 3.6475 0.90586998 3.65076998 0.91376998 3.65867785 0.90586998 6 P 0 Y
L 3.65076998 0.91376998 3.657 0.92 6 P 0 
P 3.657 0.92 9 P 0 8 0;1=9,3=1
P 6.19961004 2.24473996 9 P 0 8 0;1=9,3=1
L 3.222 3.385 3.141 3.385 8 P 0 
L 3.141 3.385 3.106 3.35 8 P 0 
P 3.222 3.385 9 P 0 8 0;1=8,3=1
P 3.106 3.35 9 P 0 8 0;1=8,3=1
P 3.55 3.37 10 P 0 8 0;1=2,3=1
P 3.55 3.28 9 P 0 8 0;1=8,3=1
L 3.55 3.28 3.52 3.31 8 P 0 
L 3.52 3.31 3.52 3.355 8 P 0 
L 3.52 3.355 3.535 3.37 8 P 0 
L 3.535 3.37 3.55 3.37 8 P 0 
L 3.735 2.47 3.735 2.529 8 P 0 
L 3.735 2.529 3.758 2.552 8 P 0 
P 3.758 2.552 10 P 0 8 0;1=2,3=1
P 3.735 2.47 10 P 0 8 0;1=2,3=1
L 5.0395 1.335 5.0395 1.3395 8 P 0 
L 5.0395 1.3395 5.075 1.375 8 P 0 
L 5.075 1.375 5.075 1.6 8 P 0 
L 5.075 1.6 5.0175 1.6575 8 P 0 
L 5.0175 1.6575 4.9856 1.6575 8 P 0 
L 4.9856 1.6575 4.96 1.6319 8 P 0 
L 4.96 1.6319 4.96 1.63 8 P 0 
P 5.0395 1.335 10 P 0 8 0;1=2,3=1
P 4.96 1.63 10 P 0 8 0;1=2,3=1
P 5.221 4.165 10 P 0 8 0;1=2,3=1
L 5.84 4.219 5.975 4.219 8 P 0 
P 5.975 4.219 10 P 0 8 0;1=2,3=1
P 5.84 4.219 10 P 0 8 0;1=2,3=1
L 5.84 4.219 5.369 4.219 8 P 0 
L 5.369 4.219 5.315 4.165 8 P 0 
L 5.315 4.165 5.221 4.165 8 P 0 
P 6.145 3.98 10 P 0 8 0;1=2,3=1
L 5.975 4.219 5.975 4.185 8 P 0 
L 5.975 4.185 6.095 4.065 8 P 0 
L 6.095 4.065 6.095 4.03 8 P 0 
L 6.095 4.03 6.145 3.98 8 P 0 
P 4.655 0.785 10 P 0 8 0;1=2,3=1
P 4.635 0.92 10 P 0 8 0;1=2,3=1
P 5.249 0.99 10 P 0 8 0;1=2,3=1
L 4.635 0.92 4.635 0.905 8 P 0 
L 4.635 0.905 4.67438996 0.86561004 8 P 0 
L 4.67438996 0.86561004 4.67438996 0.84438996 8 P 0 
L 4.67438996 0.84438996 4.655 0.825 8 P 0 
L 4.655 0.825 4.655 0.785 8 P 0 
L 4.635 0.92 4.6417 0.9267 8 P 0 
L 4.6417 0.9267 4.7067 0.9267 8 P 0 
L 4.7067 0.9267 4.765 0.985 8 P 0 
L 4.765 0.985 4.935 0.985 8 P 0 
L 4.935 0.985 4.975 1.025 8 P 0 
L 4.975 1.025 5.06 1.025 8 P 0 
L 5.06 1.025 5.095 0.99 8 P 0 
L 5.095 0.99 5.249 0.99 8 P 0 
S P 0
OB 1.705 0.92 I
OS 2.24 0.92
OS 2.31 0.85
OS 2.31 0.745019980315
OC 2.28168996063 0.725 2.309999901575 0.714993602362 N
OS 2.265 0.725
OS 2.135 0.855
OS 2.094769980315 0.855
OC 2.061230019685 0.855 2.078 0.830095866142 N
OS 2.045 0.855
OS 2.015 0.825
OS 1.74 0.825
OS 1.738369980315 0.823369980315
OS 1.737719980315 0.823269980315
OC 1.725080019685 0.816919980315 1.740994685039 0.800996259843 N
OS 1.60816003937 0.7
OS 1.596519980315 0.7
OS 1.596519980315 0.726
OC 1.59 0.74183996063 1.574002755906 0.725993405512 N
OS 1.59 0.805
OS 1.705 0.92
OE
SE
P 2.0477 0.6778 10 P 0 8 0;1=2,3=1
P 2.285 0.79 10 P 0 8 0;1=2,3=1
P 2.285 0.755 10 P 0 8 0;1=2,3=1
L 1.5327 0.584 1.563 0.584 8 P 0 
L 1.563 0.584 1.716 0.737 8 P 0 
L 1.716 0.737 1.8474 0.737 8 P 0 
L 1.8474 0.737 1.9039 0.6805 8 P 0 
L 1.9039 0.6805 2.045 0.6805 8 P 0 
L 2.045 0.6805 2.0477 0.6778 8 P 0 
P 1.605 0.715 10 P 0 8 0;1=2,3=1
P 1.605 0.755 10 P 0 8 0;1=2,3=1
L 1.826 2.895 1.778 2.847 8 P 0 
L 1.778 2.847 1.234 2.847 8 P 0 
L 1.234 2.847 1.022 2.635 8 P 0 
L 1.022 2.635 1.022 2.515 8 P 0 
L 1.022 2.515 0.872 2.365 8 P 0 
L 0.872 2.365 0.857 2.365 8 P 0 
P 1.826 2.895 10 P 0 8 0;1=2,3=1
P 0.857 2.365 10 P 0 8 0;1=2,3=1
P 1.5327 0.584 10 P 0 8 0;1=2,3=1
L 3.105 3.21 3.13 3.21 8 P 0 
L 3.13 3.21 3.18 3.16 8 P 0 
L 3.18 3.16 3.335 3.16 8 P 0 
L 3.335 3.16 3.3525 3.1775 8 P 0 
L 3.3525 3.1775 3.4125 3.1775 8 P 0 
L 3.4125 3.1775 3.46 3.225 8 P 0 
L 3.46 3.225 3.46 3.335 8 P 0 
L 3.46 3.335 3.585 3.46 8 P 0 
L 3.585 3.46 3.6115 3.46 8 P 0 
L 3.6115 3.46 3.66 3.5085 8 P 0 
P 3.66 3.5085 10 P 0 8 0;1=2,3=1
P 3.105 3.21 10 P 0 8 0;1=2,3=1
L 5.31 2.855 5.31 2.776 4 P 0 
L 5.31 2.776 5.36 2.726 4 P 0 
L 5.36 2.726 5.36 2.715 4 P 0 
L 5.36 2.715 5.474 2.601 4 P 0 
L 5.474 2.601 5.474 2.55408002 4 P 0 
L 5.474 2.55408002 5.45496004 2.53503996 4 P 0 
L 5.45496004 2.53503996 5.42503996 2.53503996 4 P 0 
L 5.42503996 2.53503996 5.37 2.48 4 P 0 
L 5.37 2.48 5.29583002 2.48 4 P 0 
L 5.29583002 2.48 5.02 2.20416998 4 P 0 
L 5.02 2.20416998 5.02 2.11158996 4 P 0 
L 5.02 2.11158996 5.0025 2.09408996 4 P 0 
L 5.0025 2.09408996 5.0025 2.03738002 4 P 0 
L 5.0025 2.03738002 4.99 2.02488002 4 P 0 
L 4.99 2.02488002 4.99 1.9075 4 P 0 
L 4.99 1.9075 5.005 1.8925 4 P 0 
L 5.005 1.8925 5.005 1.75 4 P 0 
L 5.005 1.75 5.19 1.565 4 P 0 
L 5.19 1.565 5.19 1.26818002 4 P 0 
L 5.19 1.26818002 5.47818002 0.98 4 P 0 
L 5.47818002 0.98 5.765 0.98 4 P 0 
P 5.765 0.98 10 P 0 8 0;1=3,3=0
P 5.31 2.855 10 P 0 8 0;1=2,3=1
L 4.2136 3.5997 4.2297 3.5997 4 P 0 
L 4.2297 3.5997 4.265 3.635 4 P 0 
L 4.265 3.635 4.35 3.635 4 P 0 
L 4.35 3.635 4.43 3.555 4 P 0 
L 4.43 3.555 4.495 3.555 4 P 0 
L 4.495 3.555 4.53 3.52 4 P 0 
L 4.53 3.52 4.75341998 3.52 4 P 0 
L 4.75341998 3.52 4.75841998 3.525 4 P 0 
L 4.75841998 3.525 4.97658002 3.525 4 P 0 
L 4.97658002 3.525 5.05408002 3.4475 4 P 0 
L 5.05408002 3.4475 5.0909 3.4475 4 P 0 
L 5.0909 3.4475 5.138 3.4004 4 P 0 
L 5.138 3.4004 5.138 3.072 4 P 0 
L 5.138 3.072 5.1985 3.0115 4 P 0 
L 5.1985 3.0115 5.4535 3.0115 4 P 0 
L 5.4535 3.0115 5.53 2.935 4 P 0 
L 5.53 2.935 5.53 2.83501004 4 P 0 
L 5.53 2.83501004 5.7215 2.64351004 4 P 0 
L 5.7215 2.64351004 5.7215 2.5035 4 P 0 
L 5.7215 2.5035 5.76 2.465 4 P 0 
P 5.76 2.465 10 P 0 8 0;1=3,3=0
P 4.2136 3.5997 9 P 0 8 0;1=4,3=1
L 5.4352 1.7497 5.4352 1.7798 8 P 0 
L 5.4352 1.7798 5.335 1.88 8 P 0 
L 5.335 1.88 5.335 2.07 8 P 0 
L 5.335 2.07 5.251 2.154 8 P 0 
L 5.251 2.154 5.251 2.295 8 P 0 
L 5.251 2.295 5.361 2.405 8 P 0 
L 5.361 2.405 5.41 2.405 8 P 0 
L 5.41 2.405 5.452 2.447 8 P 0 
L 5.452 2.447 5.654 2.447 8 P 0 
P 5.4352 1.7497 10 P 0 8 0;1=2,3=1
P 5.654 2.447 10 P 0 8 0;1=2,3=1
L 0.7595 1.642 0.7675 1.65 4 P 0 
L 0.7675 1.65 0.82828996 1.65 4 P 0 
L 0.82828996 1.65 0.88 1.70171004 4 P 0 
L 0.88 1.70171004 0.88 1.735 4 P 0 
L 0.88 1.735 0.905 1.76 4 P 0 
L 0.905 1.76 0.905 1.785 4 P 0 
L 0.905 1.785 0.8775 1.8125 4 P 0 
L 0.8775 1.8125 0.8775 1.99748996 4 P 0 
L 0.8775 1.99748996 0.9 2.01998996 4 P 0 
L 0.9 2.01998996 0.9 2.21351998 4 P 0 
L 0.9 2.21351998 0.9345 2.24801998 4 P 0 
L 0.9345 2.24801998 0.9345 2.3 4 P 0 
L 0.9345 2.3 0.9395 2.305 4 P 0 
L 0.9395 2.305 0.986 2.305 4 P 0 
L 0.986 2.305 1.175 2.494 4 P 0 
L 1.175 2.494 2.03558002 2.494 4 P 0 
L 2.03558002 2.494 2.31 2.76841998 4 P 0 
L 2.31 2.76841998 2.31 3.13841004 4 P 0 
L 2.31 3.13841004 2.47158996 3.3 4 P 0 
L 2.47158996 3.3 2.69341004 3.3 4 P 0 
L 2.69341004 3.3 2.7692 3.22421004 4 P 0 
L 2.7692 3.22421004 2.78855 3.22421004 4 P 0 
L 2.78855 3.22421004 2.79355 3.21921004 4 P 0 
L 2.79355 3.21921004 2.79355 3.2027 4 P 0 
L 2.79355 3.2027 2.79855 3.1977 4 P 0 
L 2.79855 3.1977 2.81355 3.1977 4 P 0 
L 2.81355 3.1977 2.81855 3.2027 4 P 0 
L 2.81855 3.2027 2.81855 3.21921004 4 P 0 
L 2.81855 3.21921004 2.82355 3.22421004 4 P 0 
L 2.82355 3.22421004 2.83855 3.22421004 4 P 0 
L 2.83855 3.22421004 2.84355 3.21921004 4 P 0 
L 2.84355 3.21921004 2.84355 3.1971 4 P 0 
L 2.84355 3.1971 2.84855 3.1921 4 P 0 
L 2.84855 3.1921 2.86355 3.1921 4 P 0 
L 2.86355 3.1921 2.86855 3.1971 4 P 0 
L 2.86855 3.1971 2.86855 3.21921004 4 P 0 
L 2.86855 3.21921004 2.87355 3.22421004 4 P 0 
L 2.87355 3.22421004 2.88855 3.22421004 4 P 0 
L 2.88855 3.22421004 2.89355 3.21921004 4 P 0 
L 2.89355 3.21921004 2.89355 3.1971 4 P 0 
L 2.89355 3.1971 2.89855 3.1921 4 P 0 
L 2.89855 3.1921 2.91355 3.1921 4 P 0 
L 2.91355 3.1921 2.91855 3.1971 4 P 0 
L 2.91855 3.1971 2.91855 3.21921004 4 P 0 
L 2.91855 3.21921004 2.92355 3.22421004 4 P 0 
L 2.92355 3.22421004 2.97621004 3.22421004 4 P 0 
L 2.97621004 3.22421004 2.987 3.235 4 P 0 
P 2.987 3.235 9 P 0 8 0;1=8,3=1
P 0.7595 1.642 9 P 0 8 0;1=7,3=1
L 0.761 1.544 0.759 1.544 4 P 0 
L 0.759 1.544 0.728 1.575 4 P 0 
L 0.728 1.575 0.728 1.643 4 P 0 
L 0.728 1.643 0.755 1.67 4 P 0 
L 0.755 1.67 0.82 1.67 4 P 0 
L 0.82 1.67 0.8575 1.7075 4 P 0 
L 0.8575 1.7075 0.8575 1.9825 4 P 0 
L 0.8575 1.9825 0.835 2.005 4 P 0 
L 0.835 2.005 0.835 2.055 4 P 0 
L 0.835 2.055 0.88 2.1 4 P 0 
L 0.88 2.1 0.88 2.22181004 4 P 0 
L 0.88 2.22181004 0.9145 2.25631004 4 P 0 
L 0.9145 2.25631004 0.9145 2.30828996 4 P 0 
L 0.9145 2.30828996 0.93121004 2.325 4 P 0 
L 0.93121004 2.325 0.975 2.325 4 P 0 
L 0.975 2.325 1.164 2.514 4 P 0 
L 1.164 2.514 2.02728996 2.514 4 P 0 
L 2.02728996 2.514 2.29 2.77671004 4 P 0 
L 2.29 2.77671004 2.29 3.1467 4 P 0 
L 2.29 3.1467 2.4633 3.32 4 P 0 
L 2.4633 3.32 2.7017 3.32 4 P 0 
L 2.7017 3.32 2.77085 3.25085 4 P 0 
L 2.77085 3.25085 2.96785 3.25085 4 P 0 
L 2.96785 3.25085 2.987 3.27 4 P 0 
P 2.987 3.27 9 P 0 8 0;1=8,3=1
P 0.761 1.544 9 P 0 8 0;1=7,3=1
L 4.79246004 1.78463996 4.76168002 1.78463996 4 P 0 
L 4.76168002 1.78463996 4.73703996 1.76 4 P 0 
L 4.73703996 1.76 4.6187 1.76 4 P 0 
L 4.6187 1.76 4.6013 1.7774 4 P 0 
L 4.6013 1.7774 4.6013 1.791 4 P 0 
L 4.6013 1.791 4.5884 1.8039 4 P 0 
L 4.5884 1.8039 4.56106004 1.8039 4 P 0 
L 4.56106004 1.8039 4.54121998 1.82373996 4 P 0 
P 4.54121998 1.82373996 9 P 0 8 0;1=1,3=1
P 4.79246004 1.78463996 10 P 0 8 0;1=0,3=1
L 1.512 0.75191004 1.512 0.7715 4 P 0 
L 1.512 0.7715 1.4235 0.86 4 P 0 
L 1.4235 0.86 1.2965 0.86 4 P 0 
L 1.2965 0.86 1.095 1.0615 4 P 0 
L 1.095 1.0615 1.095 1.34998996 4 P 0 
L 1.095 1.34998996 0.98998996 1.455 4 P 0 
L 0.98998996 1.455 0.955 1.455 4 P 0 
P 0.955 1.455 10 P 0 8 0;1=0,3=1
P 1.512 0.75191004 10 P 0 8 0;1=2,3=1
L 1.459 0.752 1.459 0.779 4 P 0 
L 1.459 0.779 1.398 0.84 4 P 0 
L 1.398 0.84 1.252 0.84 4 P 0 
L 1.252 0.84 1.07 1.022 4 P 0 
L 1.07 1.022 1.07 1.34001004 4 P 0 
L 1.07 1.34001004 0.98501004 1.425 4 P 0 
L 0.98501004 1.425 0.925 1.425 4 P 0 
L 0.925 1.425 0.905 1.445 4 P 0 
P 1.459 0.752 9 P 0 8 0;1=8,3=1
P 0.905 1.445 10 P 0 8 0;1=2,3=1
P 2.40508002 0.731 9 P 0 8 0;1=8,3=1
L 4.06878996 1.66626998 4.05848996 1.66626998 0 P 0 
A 4.05848996 1.66626998 4.05485 1.66476004 4.05848986 1.66112776 0 P 0 N
L 4.05485 1.66476004 4.05436998 1.66428002 0 P 0 
A 4.05436998 1.66428002 4.05286004 1.66063996 4.05800226 1.66064006 0 P 0 N
L 4.05286004 1.66063996 4.05286004 1.65781998 0 P 0 
A 4.05286004 1.65781998 4.03786004 1.64281998 4.03786004 1.65781998 0 P 0 Y
L 4.03786004 1.64281998 3.8515 1.64281998 0 P 0 
L 3.8515 1.64281998 3.849 1.64031998 0 P 0 
L 3.849 1.64031998 3.84813002 1.64031998 0 P 0 
L 3.84813002 1.64031998 3.34966998 1.64031998 3 P 0 
A 3.34966998 1.64031998 3.27345 1.60875 3.34966988 1.53252539 3 P 0 N
L 3.27345 1.60875 3.19008996 1.52538996 3 P 0 
A 3.19008996 1.52538996 3.17708002 1.52 3.17709606 1.53835748 3 P 0 Y
L 3.17708002 1.52 2.77935 1.52 3 P 0 
A 2.77935 1.52 2.77191998 1.51691998 2.77935 1.50949813 3 P 0 N
L 2.77191998 1.51691998 2.37608002 1.12108002 3 P 0 
A 2.37608002 1.12108002 2.373 1.11365 2.38350187 1.1136499 3 P 0 N
L 2.373 1.11365 2.373 0.85953002 3 P 0 
A 2.373 0.85953002 2.3761 0.85643002 2.3761 0.85953002 3 P 0 N
A 2.3761 0.85643002 2.3809 0.85163002 2.3761 0.85163002 3 P 0 Y
L 2.3809 0.85163002 2.3809 0.84283002 3 P 0 
A 2.3809 0.84283002 2.3761 0.83803002 2.3761 0.84283002 3 P 0 Y
A 2.3761 0.83803002 2.373 0.83493002 2.3761 0.83493002 3 P 0 N
L 2.373 0.83493002 2.373 0.729 3 P 0 
A 2.373 0.729 2.38075 0.72125 2.38075 0.729 3 P 0 N
L 2.38075 0.72125 2.38888996 0.72125 3 P 0 
A 2.38888996 0.72125 2.39988002 0.7258 2.38888996 0.73679754 3 P 0 N
L 2.39988002 0.7258 2.40508002 0.731 3 P 0 
P 4.06878996 1.66626998 9 P 0 8 0;1=11,3=1
P 2.40508002 0.699 9 P 0 8 0;1=8,3=1
L 4.02941998 1.66626998 4.03973002 1.66626998 0 P 0 
A 4.03973002 1.66626998 4.04336998 1.66476004 4.03973002 1.66112776 0 P 0 Y
L 4.04336998 1.66476004 4.04385 1.66428002 0 P 0 
A 4.04385 1.66428002 4.04536004 1.66063996 4.04021772 1.66063996 0 P 0 Y
L 4.04536004 1.66063996 4.04536004 1.65781998 0 P 0 
A 4.04536004 1.65781998 4.03786004 1.65031998 4.03786004 1.65781998 0 P 0 Y
L 4.03786004 1.65031998 3.8515 1.65031998 0 P 0 
L 3.8515 1.65031998 3.849 1.65281998 0 P 0 
L 3.849 1.65281998 3.84813002 1.65281998 0 P 0 
L 3.84813002 1.65281998 3.34966998 1.65281998 3 P 0 
A 3.34966998 1.65281998 3.26461004 1.61758996 3.34966998 1.53251978 3 P 0 N
L 3.26461004 1.61758996 3.18123996 1.53421998 3 P 0 
A 3.18123996 1.53421998 3.17708996 1.5325 3.1770939 1.53835689 3 P 0 Y
L 3.17708996 1.5325 2.77935 1.5325 3 P 0 
A 2.77935 1.5325 2.76308002 1.52576004 2.7793499 1.50949252 3 P 0 N
L 2.76308002 1.52576004 2.36723996 1.12991998 3 P 0 
A 2.36723996 1.12991998 2.3605 1.11365 2.38350748 1.11365 3 P 0 N
L 2.3605 1.11365 2.3605 0.729 3 P 0 
A 2.3605 0.729 2.38075 0.70875 2.38075 0.729 3 P 0 N
L 2.38075 0.70875 2.38888996 0.70875 3 P 0 
A 2.38888996 0.70875 2.39988002 0.7042 2.38888996 0.69320246 3 P 0 Y
L 2.39988002 0.7042 2.40508002 0.699 3 P 0 
P 4.02941998 1.66626998 9 P 0 8 0;1=11,3=1
L 4.4085 1.16598996 4.40401998 1.17048002 3 P 0 
A 4.40401998 1.17048002 4.398 1.185 4.41852087 1.185 3 P 0 Y
L 4.398 1.185 4.398 1.19421004 3 P 0 
A 4.398 1.19421004 4.402 1.19821004 4.402 1.19421004 3 P 0 Y
A 4.402 1.19821004 4.406 1.20221004 4.402 1.20221004 3 P 0 N
L 4.406 1.20221004 4.406 1.21261004 3 P 0 
A 4.406 1.21261004 4.402 1.21661004 4.402 1.21261004 3 P 0 N
A 4.402 1.21661004 4.398 1.22061004 4.402 1.22061004 3 P 0 Y
L 4.398 1.22061004 4.398 1.23121004 3 P 0 
A 4.398 1.23121004 4.40136998 1.23935 4.40951585 1.23120994 3 P 0 Y
L 4.40136998 1.23935 4.42031998 1.25831004 3 P 0 
A 4.42031998 1.25831004 4.43 1.28171004 4.39690236 1.28169951 3 P 0 N
L 4.43 1.28171004 4.43 1.29811004 3 P 0 
A 4.43 1.29811004 4.4356 1.30371004 4.4356 1.29811004 3 P 0 Y
A 4.4356 1.30371004 4.4412 1.30931004 4.4356 1.30931004 3 P 0 N
L 4.4412 1.30931004 4.4412 1.31651004 3 P 0 
A 4.4412 1.31651004 4.4356 1.32211004 4.4356 1.31651004 3 P 0 N
A 4.4356 1.32211004 4.43 1.32771004 4.4356 1.32771004 3 P 0 Y
L 4.43 1.32771004 4.43 1.34313002 3 P 0 
L 4.43 1.34313002 4.43 1.344 0 P 0 
L 4.43 1.344 4.4275 1.3465 0 P 0 
L 4.4275 1.3465 4.4275 1.35501004 0 P 0 
A 4.4275 1.35501004 4.42248002 1.36713996 4.41033661 1.35501063 0 P 0 N
L 4.42248002 1.36713996 4.41981004 1.36981004 0 P 0 
L 4.41981004 1.36981004 4.4198 1.3698 0 P 0 
L 4.4198 1.3698 4.41201998 1.37758996 0 P 0 
A 4.41201998 1.37758996 4.407 1.38971004 4.42413996 1.38970945 0 P 0 Y
L 4.407 1.38971004 4.407 1.4424 0 P 0 
A 4.407 1.4424 4.4106 1.446 4.4106 1.4424 0 P 0 Y
L 4.4106 1.446 4.47481998 1.446 0 P 0 
A 4.47481998 1.446 4.47841998 1.4424 4.47481998 1.4424 0 P 0 Y
L 4.47841998 1.4424 4.47841998 1.43355 0 P 0 
A 4.47841998 1.43355 4.47491998 1.43005 4.47491998 1.43355 0 P 0 Y
L 4.47491998 1.43005 4.46248002 1.43005 0 P 0 
P 4.4085 1.16598996 9 P 0 8 0;1=8,3=1
P 4.46248002 1.43005 9 P 0 8 0;1=11,3=1
A 4.3765 1.16598996 4.3855 1.18771998 4.35476988 1.1877187 3 P 0 N
L 4.3855 1.18771998 4.3855 1.23121004 3 P 0 
A 4.3855 1.23121004 4.39253002 1.24818996 4.40952146 1.23120984 3 P 0 Y
L 4.39253002 1.24818996 4.41146998 1.26715 3 P 0 
A 4.41146998 1.26715 4.4175 1.28171004 4.39690679 1.28170994 3 P 0 N
L 4.4175 1.28171004 4.4175 1.34313002 3 P 0 
L 4.4175 1.34313002 4.4175 1.344 0 P 0 
L 4.4175 1.344 4.42 1.3465 0 P 0 
L 4.42 1.3465 4.42 1.355 0 P 0 
A 4.42 1.355 4.41716998 1.36183002 4.41033976 1.35499852 0 P 0 N
L 4.41716998 1.36183002 4.40671004 1.37228002 0 P 0 
L 4.40671004 1.37228002 4.40671998 1.37228002 0 P 0 
A 4.40671998 1.37228002 4.3995 1.38971004 4.42414075 1.3897065 0 P 0 Y
L 4.3995 1.38971004 4.3995 1.4424 0 P 0 
A 4.3995 1.4424 4.4106 1.4535 4.4106 1.4424 0 P 0 Y
L 4.4106 1.4535 4.47481998 1.4535 0 P 0 
A 4.47481998 1.4535 4.48591998 1.4424 4.47481998 1.4424 0 P 0 Y
L 4.48591998 1.4424 4.48591998 1.43355 0 P 0 
A 4.48591998 1.43355 4.48941998 1.43005 4.48941998 1.43355 0 P 0 N
L 4.48941998 1.43005 4.50185 1.43005 0 P 0 
P 4.3765 1.16598996 9 P 0 8 0;1=8,3=1
P 4.50185 1.43005 9 P 0 8 0;1=11,3=1
P 4.0485 1.16098996 9 P 0 8 0;1=8,3=1
L 4.06878996 1.50878996 4.06048002 1.50878996 0 P 0 
A 4.06048002 1.50878996 4.05286004 1.50116998 4.06048002 1.50116998 0 P 0 N
L 4.05286004 1.50116998 4.05286004 1.38511998 0 P 0 
A 4.05286004 1.38511998 4.04773002 1.37273002 4.03533868 1.38511762 0 P 0 Y
L 4.04773002 1.37273002 4.04093002 1.36593002 0 P 0 
A 4.04093002 1.36593002 4.038 1.35885 4.048019 1.3588499 0 P 0 N
L 4.038 1.35885 4.038 1.35336998 0 P 0 
L 4.038 1.35336998 4.0405 1.35086998 0 P 0 
L 4.0405 1.35086998 4.0405 1.35 0 P 0 
L 4.0405 1.35 4.0405 1.17418996 3 P 0 
A 4.0405 1.17418996 4.04418002 1.16531004 4.05305394 1.17419006 3 P 0 N
L 4.04418002 1.16531004 4.0485 1.16098996 3 P 0 
P 4.06878996 1.50878996 9 P 0 8 0;1=11,3=1
P 4.0165 1.16098996 9 P 0 8 0;1=8,3=1
L 4.02941998 1.50878996 4.03773996 1.50878996 0 P 0 
A 4.03773996 1.50878996 4.04536004 1.50116998 4.03773996 1.50116998 0 P 0 Y
L 4.04536004 1.50116998 4.04536004 1.38511998 0 P 0 
A 4.04536004 1.38511998 4.04243002 1.37803996 4.03534104 1.38511998 0 P 0 Y
L 4.04243002 1.37803996 4.03563002 1.37123996 0 P 0 
A 4.03563002 1.37123996 4.0305 1.35885 4.04802136 1.35885226 0 P 0 N
L 4.0305 1.35885 4.0305 1.35336998 0 P 0 
L 4.0305 1.35336998 4.028 1.35086998 0 P 0 
L 4.028 1.35086998 4.028 1.35 0 P 0 
L 4.028 1.35 4.028 1.17973996 3 P 0 
A 4.028 1.17973996 4.02286998 1.16736004 4.01049695 1.17974006 3 P 0 Y
L 4.02286998 1.16736004 4.0165 1.16098996 3 P 0 
P 4.02941998 1.50878996 9 P 0 8 0;1=11,3=1
L 4.82 2.125 4.7775 2.0825 4 P 0 
L 4.7775 2.0825 4.7775 2.0675 4 P 0 
L 4.7775 2.0675 4.73 2.02 4 P 0 
L 4.73 2.02 4.68998996 2.02 4 P 0 
L 4.68998996 2.02 4.66998996 2 4 P 0 
L 4.66998996 2 4.6517 2 4 P 0 
L 4.6517 2 4.64 1.9883 4 P 0 
L 4.64 1.9883 4.64 1.965 4 P 0 
L 4.64 1.965 4.635 1.96 4 P 0 
L 4.635 1.96 4.61 1.96 4 P 0 
L 4.61 1.96 4.6 1.95 4 P 0 
L 4.6 1.95 4.6 1.93391004 4 P 0 
L 4.6 1.93391004 4.59108996 1.925 4 P 0 
L 4.59108996 1.925 4.57 1.925 4 P 0 
L 4.57 1.925 4.56 1.915 4 P 0 
L 4.56 1.915 4.56 1.89216998 4 P 0 
L 4.56 1.89216998 4.55283002 1.885 4 P 0 
L 4.55283002 1.885 4.37223996 1.885 4 P 0 
L 4.37223996 1.885 4.36723996 1.88 4 P 0 
L 4.36723996 1.88 4.36723996 1.80776004 4 P 0 
L 4.36723996 1.80776004 4.38373996 1.79126004 4 P 0 
L 4.38373996 1.79126004 4.38373996 1.78436998 4 P 0 
P 4.82 2.125 10 P 0 8 0;1=3,3=0
P 4.38373996 1.78436998 9 P 0 8 0;1=1,3=1
P 3.54663996 1.04706998 9 P 0 8 0;1=8,3=1
L 4.6987 1.46941998 4.71113002 1.46941998 0 P 0 
A 4.71113002 1.46941998 4.71463002 1.46591998 4.71113002 1.46591998 0 P 0 Y
L 4.71463002 1.46591998 4.71463002 1.46096998 0 P 0 
A 4.71463002 1.46096998 4.7291 1.4465 4.7291 1.46096998 0 P 0 N
L 4.7291 1.4465 4.76461004 1.4465 0 P 0 
L 4.76461004 1.4465 4.76711004 1.444 0 P 0 
L 4.76711004 1.444 4.76798002 1.444 0 P 0 
L 4.76798002 1.444 4.79125 1.444 3 P 0 
A 4.79125 1.444 4.79478996 1.44253002 4.7912499 1.43900256 3 P 0 Y
L 4.79478996 1.44253002 4.83133002 1.40598996 3 P 0 
A 4.83133002 1.40598996 4.83133002 1.40183002 4.82925 1.40390994 3 P 0 Y
A 4.83133002 1.40183002 4.83133002 1.39766998 4.83341004 1.39975 3 P 0 N
L 4.83133002 1.39766998 4.84018996 1.38881004 3 P 0 
A 4.84018996 1.38881004 4.84435 1.38881004 4.84226998 1.39088996 3 P 0 N
A 4.84435 1.38881004 4.84851004 1.38881004 4.84643002 1.38673002 3 P 0 Y
L 4.84851004 1.38881004 4.85603002 1.38128996 3 P 0 
A 4.85603002 1.38128996 4.8575 1.37775 4.85250256 1.3777499 3 P 0 Y
L 4.8575 1.37775 4.8575 1.22566998 3 P 0 
A 4.8575 1.22566998 4.84818002 1.20318002 4.82570482 1.22566998 3 P 0 Y
L 4.84818002 1.20318002 4.8414 1.1964 3 P 0 
A 4.8414 1.1964 4.83626004 1.19546004 4.8381498 1.19964921 3 P 0 Y
A 4.83626004 1.19546004 4.83111998 1.19451004 4.83437815 1.19126171 3 P 0 N
L 4.83111998 1.19451004 4.8243 1.18768996 3 P 0 
A 4.8243 1.18768996 4.82335 1.18255 4.82754665 1.18443209 3 P 0 N
A 4.82335 1.18255 4.82241004 1.17741004 4.81915817 1.18066063 3 P 0 Y
L 4.82241004 1.17741004 4.73941998 1.09441998 3 P 0 
A 4.73941998 1.09441998 4.73481998 1.09441998 4.73711998 1.09671998 3 P 0 Y
A 4.73481998 1.09441998 4.73021998 1.09441998 4.73251998 1.09211998 3 P 0 N
L 4.73021998 1.09441998 4.7218 1.086 3 P 0 
A 4.7218 1.086 4.7218 1.0814 4.7241 1.0837 3 P 0 N
A 4.7218 1.0814 4.7218 1.0768 4.7195 1.0791 3 P 0 Y
L 4.7218 1.0768 4.71375 1.06875 3 P 0 
A 4.71375 1.06875 4.485 0.974 4.48500197 1.2974997 3 P 0 Y
L 4.485 0.974 3.68426004 0.974 3 P 0 
A 3.68426004 0.974 3.68126004 0.977 3.68426004 0.977 3 P 0 Y
A 3.68126004 0.977 3.67826004 0.98 3.67826004 0.977 3 P 0 N
L 3.67826004 0.98 3.66586004 0.98 3 P 0 
A 3.66586004 0.98 3.66286004 0.977 3.66586004 0.977 3 P 0 N
A 3.66286004 0.977 3.65986004 0.974 3.65986004 0.977 3 P 0 Y
L 3.65986004 0.974 3.59303996 0.974 3 P 0 
A 3.59303996 0.974 3.55541004 0.98958996 3.59303356 1.0271939 3 P 0 Y
L 3.55541004 0.98958996 3.53836004 1.00663996 3 P 0 
A 3.53836004 1.00663996 3.53688996 1.01018002 3.5418874 1.01018002 3 P 0 Y
L 3.53688996 1.01018002 3.53688996 1.03086004 3 P 0 
A 3.53688996 1.03086004 3.54145 1.04186998 3.55246171 1.03085984 3 P 0 Y
L 3.54145 1.04186998 3.54663996 1.04706004 3 P 0 
L 3.54663996 1.04706004 3.54663996 1.04706998 3 P 0 
P 4.6987 1.46941998 9 P 0 8 0;1=11,3=1
P 3.51463996 1.04706998 9 P 0 8 0;1=8,3=1
L 4.73806998 1.46941998 4.72563002 1.46941998 0 P 0 
A 4.72563002 1.46941998 4.72213002 1.46591998 4.72563002 1.46591998 0 P 0 N
L 4.72213002 1.46591998 4.72213002 1.46096998 0 P 0 
A 4.72213002 1.46096998 4.7291 1.454 4.7291 1.46096998 0 P 0 N
L 4.7291 1.454 4.76461004 1.454 0 P 0 
L 4.76461004 1.454 4.76711004 1.4565 0 P 0 
L 4.76711004 1.4565 4.76798002 1.4565 0 P 0 
L 4.76798002 1.4565 4.79125 1.4565 3 P 0 
A 4.79125 1.4565 4.80363002 1.45136998 4.7912499 1.43899695 3 P 0 Y
L 4.80363002 1.45136998 4.86486998 1.39013002 3 P 0 
A 4.86486998 1.39013002 4.87 1.37775 4.85249695 1.3777499 3 P 0 Y
L 4.87 1.37775 4.87 1.22566998 3 P 0 
A 4.87 1.22566998 4.85701998 1.19433996 4.82569921 1.22566988 3 P 0 Y
L 4.85701998 1.19433996 4.72258996 1.05991004 3 P 0 
A 4.72258996 1.05991004 4.48498996 0.9615 4.48500404 1.2975002 3 P 0 Y
L 4.48498996 0.9615 3.59303002 0.9615 3 P 0 
A 3.59303002 0.9615 3.54656998 0.98075 3.5930314 1.02719439 3 P 0 Y
L 3.54656998 0.98075 3.52951998 0.9978 3 P 0 
A 3.52951998 0.9978 3.52438996 1.01018002 3.54189301 1.01018002 3 P 0 Y
L 3.52438996 1.01018002 3.52438996 1.03088002 3 P 0 
A 3.52438996 1.03088002 3.52263002 1.03806998 3.50884144 1.03088445 3 P 0 N
A 3.52263002 1.03806998 3.51983996 1.04186998 3.50884695 1.03087431 3 P 0 N
L 3.51983996 1.04186998 3.51463996 1.04706998 3 P 0 
P 4.73806998 1.46941998 9 P 0 8 0;1=11,3=1
P 3.44998996 1.085 9 P 0 8 0;1=8,3=1
L 4.73806998 1.39066998 4.74548996 1.38325 3 P 0 
A 4.74548996 1.38325 4.76001004 1.37723002 4.76001663 1.39776722 3 P 0 N
L 4.76001004 1.37723002 4.76046998 1.37723002 3 P 0 
A 4.76046998 1.37723002 4.77673996 1.37048996 4.76046988 1.35422254 3 P 0 Y
L 4.77673996 1.37048996 4.78326004 1.36396998 3 P 0 
A 4.78326004 1.36396998 4.79 1.3477 4.76699252 1.3477 3 P 0 Y
L 4.79 1.3477 4.79 1.28685 3 P 0 
A 4.79 1.28685 4.78326004 1.27058002 4.76699252 1.2868499 3 P 0 Y
L 4.78326004 1.27058002 4.56383996 1.05116004 3 P 0 
A 4.56383996 1.05116004 4.50621998 1.0273 4.50623652 1.10876378 3 P 0 Y
L 4.50621998 1.0273 3.88711004 1.0273 3 P 0 
A 3.88711004 1.0273 3.87501004 1.03231004 3.88710778 1.04441142 3 P 0 Y
L 3.87501004 1.03231004 3.85866004 1.04866004 3 P 0 
A 3.85866004 1.04866004 3.84335 1.055 3.84335 1.03334449 3 P 0 N
L 3.84335 1.055 3.66185 1.055 3 P 0 
A 3.66185 1.055 3.64558002 1.06173996 3.6618499 1.07800748 3 P 0 Y
L 3.64558002 1.06173996 3.5929 1.11441998 3 P 0 
A 3.5929 1.11441998 3.58546998 1.1175 3.58546988 1.10699813 3 P 0 N
L 3.58546998 1.1175 3.4475 1.1175 3 P 0 
A 3.4475 1.1175 3.44023996 1.11023996 3.4475 1.11023996 3 P 0 N
L 3.44023996 1.11023996 3.44023996 1.10121004 3 P 0 
A 3.44023996 1.10121004 3.4448 1.0902 3.45581171 1.10121004 3 P 0 N
L 3.4448 1.0902 3.44998996 1.08501004 3 P 0 
L 3.44998996 1.08501004 3.44998996 1.085 3 P 0 
P 4.73806998 1.39066998 9 P 0 8 0;1=11,3=1
P 3.41798996 1.085 9 P 0 8 0;1=8,3=1
L 4.73806998 1.3513 4.74711004 1.36033996 3 P 0 
A 4.74711004 1.36033996 4.7577 1.36473002 4.7577 1.34976191 3 P 0 Y
L 4.7577 1.36473002 4.76046998 1.36473002 3 P 0 
A 4.76046998 1.36473002 4.7679 1.36165 4.76046988 1.35422815 3 P 0 Y
L 4.7679 1.36165 4.77441998 1.35513002 3 P 0 
A 4.77441998 1.35513002 4.7775 1.3477 4.76699813 1.3476999 3 P 0 Y
L 4.7775 1.3477 4.7775 1.28685 3 P 0 
A 4.7775 1.28685 4.77441998 1.27941998 4.76699813 1.28685 3 P 0 Y
L 4.77441998 1.27941998 4.75893996 1.26393996 3 P 0 
A 4.75893996 1.26393996 4.75423996 1.26393996 4.75658996 1.26628996 3 P 0 Y
A 4.75423996 1.26393996 4.74833996 1.26393996 4.75128996 1.26098996 3 P 0 N
L 4.74833996 1.26393996 4.74121998 1.25681998 3 P 0 
A 4.74121998 1.25681998 4.74121998 1.25091998 4.74416998 1.25386998 3 P 0 N
A 4.74121998 1.25091998 4.74121998 1.24621998 4.73886998 1.24856998 3 P 0 Y
L 4.74121998 1.24621998 4.59081004 1.09581004 3 P 0 
A 4.59081004 1.09581004 4.58615 1.09576004 4.58845453 1.09815817 3 P 0 Y
A 4.58615 1.09576004 4.5797 1.0957 4.58295541 1.09245374 3 P 0 N
L 4.5797 1.0957 4.5732 1.0892 3 P 0 
A 4.5732 1.0892 4.57313996 1.08275 4.57644272 1.08594449 3 P 0 N
A 4.57313996 1.08275 4.57308996 1.07808996 4.57074183 1.08044537 3 P 0 Y
L 4.57308996 1.07808996 4.555 1.06 3 P 0 
A 4.555 1.06 4.50623002 1.0398 4.50623445 1.10876319 3 P 0 Y
L 4.50623002 1.0398 3.88711004 1.0398 3 P 0 
A 3.88711004 1.0398 3.88385 1.04115 3.88710984 1.04441083 3 P 0 Y
L 3.88385 1.04115 3.8675 1.0575 3 P 0 
A 3.8675 1.0575 3.84335 1.0675 3.84335 1.03333888 3 P 0 N
L 3.84335 1.0675 3.74456998 1.0675 3 P 0 
A 3.74456998 1.0675 3.74051998 1.07155 3.74456998 1.07155 3 P 0 Y
A 3.74051998 1.07155 3.73646998 1.0756 3.73646998 1.07155 3 P 0 N
L 3.73646998 1.0756 3.72616998 1.0756 3 P 0 
A 3.72616998 1.0756 3.72211998 1.07155 3.72616998 1.07155 3 P 0 N
A 3.72211998 1.07155 3.71806998 1.0675 3.71806998 1.07155 3 P 0 Y
L 3.71806998 1.0675 3.66185 1.0675 3 P 0 
A 3.66185 1.0675 3.65441998 1.07058002 3.66185 1.07800187 3 P 0 Y
L 3.65441998 1.07058002 3.60173996 1.12326004 3 P 0 
A 3.60173996 1.12326004 3.58546998 1.13 3.58546998 1.10699252 3 P 0 N
L 3.58546998 1.13 3.4475 1.13 3 P 0 
A 3.4475 1.13 3.42773996 1.11023996 3.4475 1.11023996 3 P 0 N
L 3.42773996 1.11023996 3.42773996 1.10118996 3 P 0 
A 3.42773996 1.10118996 3.42318996 1.0902 3.41219242 1.10118996 3 P 0 Y
L 3.42318996 1.0902 3.41798996 1.085 3 P 0 
P 4.73806998 1.3513 9 P 0 8 0;1=11,3=1
L 4.785 3.46 4.772 3.447 4 P 0 
L 4.772 3.447 4.772 2.95701004 4 P 0 
L 4.772 2.95701004 4.955 2.77401004 4 P 0 
L 4.955 2.77401004 4.955 2.595 4 P 0 
L 4.955 2.595 4.9455 2.5855 4 P 0 
L 4.9455 2.5855 4.9455 2.38 4 P 0 
L 4.9455 2.38 4.83 2.2645 4 P 0 
L 4.83 2.2645 4.83 2.1539 4 P 0 
L 4.83 2.1539 4.8475 2.1364 4 P 0 
L 4.8475 2.1364 4.8475 2.1136 4 P 0 
L 4.8475 2.1136 4.7364 2.0025 4 P 0 
L 4.7364 2.0025 4.69361004 2.0025 4 P 0 
L 4.69361004 2.0025 4.68 1.98888996 4 P 0 
L 4.68 1.98888996 4.68 1.96251998 4 P 0 
L 4.68 1.96251998 4.65933002 1.94185 4 P 0 
P 4.65933002 1.94185 9 P 0 8 0;1=1,3=1
P 4.785 3.46 10 P 0 8 0;1=0,3=1
L 4.84 1.66 4.815 1.685 4 P 0 
L 4.815 1.685 4.77873002 1.685 4 P 0 
L 4.77873002 1.685 4.7435 1.64976998 4 P 0 
L 4.7435 1.64976998 4.55771998 1.64976998 4 P 0 
L 4.55771998 1.64976998 4.54121998 1.66626998 4 P 0 
P 4.54121998 1.66626998 9 P 0 8 0;1=1,3=1
P 4.84 1.66 10 P 0 8 0;1=0,3=1
P 3.375 1.194 9 P 0 8 0;1=8,3=1
L 4.5413 1.22166998 4.54861998 1.21435 3 P 0 
A 4.54861998 1.21435 4.55105 1.20848002 4.54274508 1.20847992 3 P 0 Y
L 4.55105 1.20848002 4.55105 1.19116004 3 P 0 
A 4.55105 1.19116004 4.54933002 1.18701004 4.54519311 1.191156 3 P 0 Y
L 4.54933002 1.18701004 4.53556004 1.17323996 3 P 0 
A 4.53556004 1.17323996 4.53016004 1.17323996 4.53286004 1.17593996 3 P 0 Y
L 4.53016004 1.17323996 4.53015 1.17325 3 P 0 
A 4.53015 1.17325 4.52475 1.17325 4.52745 1.17055 3 P 0 N
L 4.52475 1.17325 4.51713002 1.16563002 3 P 0 
A 4.51713002 1.16563002 4.51713002 1.16023002 4.51983002 1.16293002 3 P 0 N
L 4.51713002 1.16023002 4.51713996 1.16021998 3 P 0 
A 4.51713996 1.16021998 4.51713996 1.15481998 4.51443996 1.15751998 3 P 0 Y
L 4.51713996 1.15481998 4.50316004 1.14083996 3 P 0 
A 4.50316004 1.14083996 4.49948002 1.13806004 4.49141083 1.15256762 3 P 0 Y
A 4.49948002 1.13806004 4.48766998 1.135 4.48767657 1.15929439 3 P 0 Y
L 4.48766998 1.135 4.13486998 1.135 3 P 0 
A 4.13486998 1.135 4.12383002 1.13186004 4.13484094 1.11412402 3 P 0 N
A 4.12383002 1.13186004 4.11418002 1.12418002 4.1524185 1.08603563 3 P 0 N
L 4.11418002 1.12418002 4.09713996 1.10713996 3 P 0 
A 4.09713996 1.10713996 4.06783996 1.095 4.06783986 1.13642815 3 P 0 Y
L 4.06783996 1.095 3.99181004 1.095 3 P 0 
A 3.99181004 1.095 3.95773996 1.10911004 3.99180994 1.1431877 3 P 0 Y
L 3.95773996 1.10911004 3.94686004 1.11998996 3 P 0 
A 3.94686004 1.11998996 3.89856004 1.14 3.89855994 1.07170187 3 P 0 N
L 3.89856004 1.14 3.72276004 1.14 3 P 0 
A 3.72276004 1.14 3.71891004 1.14385 3.72276004 1.14385 3 P 0 Y
A 3.71891004 1.14385 3.71506004 1.1477 3.71506004 1.14385 3 P 0 N
L 3.71506004 1.1477 3.70436004 1.1477 3 P 0 
A 3.70436004 1.1477 3.70051004 1.14385 3.70436004 1.14385 3 P 0 N
A 3.70051004 1.14385 3.69666004 1.14 3.69666004 1.14385 3 P 0 Y
L 3.69666004 1.14 3.67863002 1.14 3 P 0 
A 3.67863002 1.14 3.6712 1.14308002 3.67863002 1.15050187 3 P 0 Y
L 3.6712 1.14308002 3.63891998 1.17536004 3 P 0 
A 3.63891998 1.17536004 3.62265 1.1821 3.62265 1.15909252 3 P 0 N
L 3.62265 1.1821 3.39485 1.1821 3 P 0 
A 3.39485 1.1821 3.384 1.18546004 3.39485 1.20129823 3 P 0 Y
A 3.384 1.18546004 3.38126998 1.18773002 3.39485344 1.20128976 3 P 0 Y
L 3.38126998 1.18773002 3.375 1.194 3 P 0 
L 4.5413 1.22166998 4.54771998 1.22808002 3 P 0 
A 4.54771998 1.22808002 4.55058002 1.235 4.54079685 1.23499232 3 P 0 N
L 4.55058002 1.235 4.55058002 1.24 3 P 0 
A 4.55058002 1.24 4.57858002 1.268 4.57858002 1.24 3 P 0 Y
L 4.57858002 1.268 4.6164 1.268 3 P 0 
A 4.6164 1.268 4.6334 1.285 4.6164 1.285 3 P 0 N
L 4.6334 1.285 4.6334 1.30733002 3 P 0 
A 4.6334 1.30733002 4.6288 1.31193002 4.6288 1.30733002 3 P 0 N
L 4.6288 1.31193002 4.61996004 1.31193002 3 P 0 
P 4.5413 1.22166998 9 P 0 8 0;1=8,3=1
P 4.61996004 1.31193002 9 P 0 8 0;1=11,3=1
P 3.375 1.162 9 P 0 8 0;1=8,3=1
L 4.5733 1.22166998 4.56598002 1.21433996 3 P 0 
A 4.56598002 1.21433996 4.56355 1.20848996 4.57182657 1.20848159 3 P 0 N
L 4.56355 1.20848996 4.56355 1.19116998 3 P 0 
A 4.56355 1.19116998 4.55816998 1.17816998 4.54519252 1.19115384 3 P 0 Y
L 4.55816998 1.17816998 4.512 1.132 3 P 0 
A 4.512 1.132 4.50633996 1.12758002 4.49139409 1.15255295 3 P 0 Y
A 4.50633996 1.12758002 4.48766998 1.1225 4.48768406 1.15929577 3 P 0 Y
L 4.48766998 1.1225 4.13486998 1.1225 3 P 0 
A 4.13486998 1.1225 4.13043996 1.12123996 4.13485728 1.11412707 3 P 0 N
A 4.13043996 1.12123996 4.12301998 1.11533996 4.15239301 1.08601545 3 P 0 N
L 4.12301998 1.11533996 4.10598002 1.0983 3 P 0 
A 4.10598002 1.0983 4.06785 1.0825 4.06784193 1.13642874 3 P 0 Y
L 4.06785 1.0825 3.99181004 1.0825 3 P 0 
A 3.99181004 1.0825 3.9489 1.10026998 3.99180994 1.14319331 3 P 0 Y
L 3.9489 1.10026998 3.93801998 1.11115 3 P 0 
A 3.93801998 1.11115 3.89856004 1.1275 3.89855994 1.07170748 3 P 0 N
L 3.89856004 1.1275 3.67863002 1.1275 3 P 0 
A 3.67863002 1.1275 3.66236004 1.13423996 3.67862992 1.15050748 3 P 0 Y
L 3.66236004 1.13423996 3.63008002 1.16651998 3 P 0 
A 3.63008002 1.16651998 3.62265 1.1696 3.6226499 1.15909813 3 P 0 N
L 3.62265 1.1696 3.38751998 1.1696 3 P 0 
A 3.38751998 1.1696 3.37911998 1.16611998 3.38751998 1.15772205 3 P 0 N
L 3.37911998 1.16611998 3.375 1.162 3 P 0 
L 4.5733 1.22166998 4.56528002 1.22968996 3 P 0 
A 4.56528002 1.22968996 4.56308002 1.235 4.57058819 1.2349999 3 P 0 Y
L 4.56308002 1.235 4.56308002 1.24 3 P 0 
A 4.56308002 1.24 4.57858002 1.2555 4.57858002 1.24 3 P 0 Y
L 4.57858002 1.2555 4.6164 1.2555 3 P 0 
A 4.6164 1.2555 4.6459 1.285 4.6164 1.285 3 P 0 N
L 4.6459 1.285 4.6459 1.30733002 3 P 0 
A 4.6459 1.30733002 4.6505 1.31193002 4.6505 1.30733002 3 P 0 Y
L 4.6505 1.31193002 4.65933002 1.31193002 3 P 0 
P 4.5733 1.22166998 9 P 0 8 0;1=8,3=1
P 4.65933002 1.31193002 9 P 0 8 0;1=11,3=1
L 4.38373996 2.02058996 4.4029 2.03975 4 P 0 
L 4.4029 2.03975 4.4029 2.1452 4 P 0 
L 4.4029 2.1452 4.3904 2.1577 4 P 0 
L 4.3904 2.1577 4.3723 2.1577 4 P 0 
L 4.3723 2.1577 4.365 2.165 4 P 0 
L 4.365 2.165 4.365 2.33 4 P 0 
P 4.365 2.33 10 P 0 8 0;1=2,3=1
P 4.38373996 2.02058996 9 P 0 8 0;1=5,3=1
L 3.44 1.03 3.44 1.005 4 P 0 
L 3.44 1.005 3.585 0.86 4 P 0 
L 3.585 0.86 3.585 0.773 4 P 0 
L 3.585 0.773 3.7239 0.6341 4 P 0 
L 3.7239 0.6341 4.7701 0.6341 4 P 0 
L 4.7701 0.6341 4.8659 0.7299 4 P 0 
L 4.8659 0.7299 5.497 0.7299 4 P 0 
L 5.497 0.7299 5.5455 0.6814 4 P 0 
L 5.5455 0.6814 5.6514 0.6814 4 P 0 
L 5.6514 0.6814 5.7885 0.8185 4 P 0 
L 5.7885 0.8185 6.2685 0.8185 4 P 0 
L 6.2685 0.8185 6.405 0.955 4 P 0 
L 6.405 0.955 6.405 1.64 4 P 0 
L 6.405 1.64 6.285 1.76 4 P 0 
L 6.285 1.76 6.285 1.895 4 P 0 
P 3.44 1.03 10 P 0 8 0;1=0,3=1
P 6.285 1.895 10 P 0 8 0;1=2,3=1
S P 0
OB 1.425 4.195 I
OS 1.565 4.195
OS 1.578 4.182
OS 1.5778 4.18081003937
OS 1.577780019685 4.18073996063
OC 1.576980019685 4.174 1.605997440945 4.173973228346 N
OC 1.58406003937 4.15501003937 1.6059875 4.174 N
OC 1.575480019685 4.134 1.605493799213 4.134 N
OC 1.580919980315 4.116769980315 1.605486122047 4.133999901575 N
OC 1.5758 4.1 1.605824114173 4.1 N
OC 1.59848996063 4.07088996063 1.605818208661 4.099999901575 N
OS 1.6 4.07051003937
OS 1.6 4
OS 1.58 3.98
OS 1.552769980315 3.98
OC 1.548919980315 3.98508996063 1.552768700787 3.984000098425 Y
OC 1.550019980315 3.993 1.521000590551 3.993004035433 N
OC 1.491980019685 3.993 1.521 3.993 N
OC 1.493080019685 3.98508996063 1.520999409449 3.993004035433 N
OC 1.489230019685 3.98 1.489231299213 3.984000098425 Y
OS 1.419030019685 3.98
OC 1.401 3.986019980315 1.401000098425 3.956009940945 N
OC 1.395669980315 3.98553996063 1.401016830709 3.956001476378 N
OS 1.39463996063 3.98536003937
OS 1.385 3.995
OS 1.385 4.155
OS 1.425 4.195
OE
OB 1.496430019685 4.08505 H
OC 1.486280019685 4.063 1.515305905512 4.063 N
OC 1.544319980315 4.063 1.5153 4.063 N
OC 1.535619980315 4.083719980315 1.515296555118 4.063 N
OC 1.5359 4.089680019685 1.538422047244 4.086574901575 Y
OC 1.547019980315 4.113 1.51700757874 4.113 N
OC 1.486980019685 4.113 1.517 4.113 N
OC 1.49656003937 4.091019980315 1.516997637795 4.113005511811 N
OC 1.496430019685 4.08505 1.493832874016 4.088093011811 Y
OE
SE
P 1.585 4.052 10 P 0 8 0;1=2,3=1
P 1.435 4.18 10 P 0 8 0;1=2,3=1
P 1.522 4.163 9 P 0 8 0;1=7,3=1
P 1.4 4.01 10 P 0 8 0;1=2,3=1
P 5.18 3.825 10 P 0 8 0;1=2,3=1
P 5.675 4.03 10 P 0 8 0;1=2,3=1
L 5.18 3.825 5.18 3.935 8 P 0 
L 5.18 3.935 5.2625 4.0175 8 P 0 
L 5.2625 4.0175 5.3725 4.0175 8 P 0 
L 5.3725 4.0175 5.405 4.05 8 P 0 
L 5.405 4.05 5.655 4.05 8 P 0 
L 5.655 4.05 5.675 4.03 8 P 0 
L 2.165 3.96 2.165 4.014 8 P 0 
L 2.165 4.014 1.929 4.25 8 P 0 
L 1.929 4.25 1.43 4.25 8 P 0 
L 1.43 4.25 1.35 4.17 8 P 0 
L 1.35 4.17 1.35 4.127 8 P 0 
L 1.35 4.127 1.351 4.126 8 P 0 
P 1.351 4.126 10 P 0 8 0;1=2,3=1
P 2.165 3.96 10 P 0 8 0;1=2,3=1
L 3.745 4.185 3.835 4.275 4 P 0 
L 3.835 4.275 4.475 4.275 4 P 0 
L 4.475 4.275 4.9325 3.8175 4 P 0 
L 4.9325 3.8175 5.0675 3.8175 4 P 0 
L 5.0675 3.8175 5.11 3.775 4 P 0 
L 5.11 3.775 5.11 3.6546 4 P 0 
L 5.11 3.6546 5.2319 3.5327 4 P 0 
L 5.2319 3.5327 5.5871 3.5327 4 P 0 
L 5.5871 3.5327 5.6208 3.499 4 P 0 
L 5.6208 3.499 5.6728 3.499 4 P 0 
L 5.6728 3.499 5.694 3.4778 4 P 0 
L 5.694 3.4778 5.694 3.156 4 P 0 
L 5.694 3.156 5.7637 3.0863 4 P 0 
L 5.7637 3.0863 5.7887 3.0863 4 P 0 
L 5.7887 3.0863 5.8447 3.0303 4 P 0 
L 5.8447 3.0303 5.8447 2.995 4 P 0 
L 5.8447 2.995 5.88 2.9597 4 P 0 
L 5.88 2.9597 5.88 2.4833 4 P 0 
L 5.88 2.4833 5.9065 2.4568 4 P 0 
P 5.9065 2.4568 10 P 0 8 0;1=2,3=1
P 3.745 4.185 10 P 0 8 0;1=3,3=0
L 3.69 4.135 3.665 4.16 4 P 0 
L 3.665 4.16 3.63 4.16 4 P 0 
L 3.63 4.16 3.6 4.13 4 P 0 
L 3.6 4.13 3.55601004 4.13 4 P 0 
L 3.55601004 4.13 3.48278996 4.05678002 4 P 0 
P 3.69 4.135 10 P 0 8 0;1=3,3=0
P 3.48278996 4.05678002 10 P 0 8 0;1=2,3=1
S P 0
OB 3.50605 3.98948996063 I
OS 3.60778996063 3.98948996063
OS 3.617430019685 3.97985
OS 3.617430019685 3.915569980315
OS 3.50013996063 3.798280019685
OS 3.4606 3.798280019685
OS 3.422780019685 3.8361
OS 3.422869980315 3.83703996063
OC 3.423019980315 3.84 3.393001870079 3.84003730315 N
OC 3.41663996063 3.8585 3.393007874016 3.84 N
OC 3.423019980315 3.877 3.393007874016 3.877 N
OC 3.39311003937 3.907019980315 3.39299980315 3.877 N
OS 3.39311003937 3.953169980315
OS 3.429430019685 3.98948996063
OS 3.44595 3.98948996063
OS 3.445980019685 3.987519980315
OC 3.506019980315 3.987519980315 3.476 3.988003937008 N
OS 3.50605 3.98948996063
OE
OB 3.500019980315 3.912 H
OC 3.500019980315 3.912 3.47 3.912 N
OE
SE
P 3.598 3.977 10 P 0 8 0;1=2,3=1
P 3.477 3.816 10 P 0 8 0;1=0,3=1
P 3.405 3.916 10 P 0 8 0;1=2,3=1
P 1.98135 0.365 9 P 0 8 0;1=8,3=1
L 1.98135 0.365 1.93 0.365 4 P 0 
L 1.93 0.365 1.89 0.405 4 P 0 
L 1.89 0.405 1.89 0.465 4 P 0 
L 1.89 0.465 1.76 0.595 4 P 0 
L 1.76 0.595 1.76 0.6801 4 P 0 
L 1.76 0.6801 1.7317 0.7084 4 P 0 
P 1.7317 0.7084 10 P 0 8 0;1=0,3=1
P 1.91535 0.412 9 P 0 8 0;1=8,3=1
L 1.8039 0.7072 1.7876 0.6909 4 P 0 
L 1.7876 0.6909 1.7876 0.62498996 4 P 0 
L 1.7876 0.62498996 1.80018996 0.6124 4 P 0 
L 1.80018996 0.6124 1.81361004 0.6124 4 P 0 
L 1.81361004 0.6124 1.82518002 0.60083002 4 P 0 
L 1.82518002 0.60083002 1.83226004 0.60083002 4 P 0 
L 1.83226004 0.60083002 1.85416998 0.62273996 4 P 0 
L 1.85416998 0.62273996 1.86125 0.62273996 4 P 0 
L 1.86125 0.62273996 1.87185 0.61213996 4 P 0 
L 1.87185 0.61213996 1.87185 0.60506004 4 P 0 
L 1.87185 0.60506004 1.84993996 0.58315 4 P 0 
L 1.84993996 0.58315 1.84993996 0.57606998 4 P 0 
L 1.84993996 0.57606998 1.86056004 0.56545 4 P 0 
L 1.86056004 0.56545 1.86056004 0.53945 4 P 0 
L 1.86056004 0.53945 1.91535 0.48466004 4 P 0 
L 1.91535 0.48466004 1.91535 0.412 4 P 0 
P 1.8039 0.7072 9 P 0 8 0;1=7,3=1
P 2.235 0.5825 10 P 0 8 0;1=2,3=1
L 3.405 0.635 3.405 0.6101 8 P 0 
L 3.405 0.6101 3.37 0.5751 8 P 0 
L 3.37 0.5751 3.1491 0.5751 8 P 0 
L 3.1491 0.5751 3.097 0.523 8 P 0 
L 3.097 0.523 2.898 0.523 8 P 0 
L 2.898 0.523 2.85 0.475 8 P 0 
L 2.85 0.475 2.502 0.475 8 P 0 
L 2.502 0.475 2.446 0.531 8 P 0 
L 2.446 0.531 2.2865 0.531 8 P 0 
L 2.2865 0.531 2.235 0.5825 8 P 0 
P 3.405 0.635 10 P 0 8 0;1=2,3=1
L 5.295 0.605 5.335 0.645 8 P 0 
L 5.335 0.645 5.44023996 0.645 8 P 0 
L 5.44023996 0.645 5.45773996 0.6625 8 P 0 
L 5.45773996 0.6625 5.5014 0.6625 8 P 0 
L 5.5014 0.6625 5.57043002 0.59346998 8 P 0 
L 5.57043002 0.59346998 5.67798002 0.59346998 8 P 0 
L 5.67798002 0.59346998 5.72451004 0.64 8 P 0 
L 5.72451004 0.64 5.7325 0.64 8 P 0 
L 5.7325 0.64 5.7875 0.695 8 P 0 
L 5.7875 0.695 6.18501004 0.695 8 P 0 
L 6.18501004 0.695 6.435 0.94498996 8 P 0 
L 6.435 0.94498996 6.435 1.80501004 8 P 0 
L 6.435 1.80501004 6.3025 1.93751004 8 P 0 
L 6.3025 1.93751004 6.3025 2.43748996 8 P 0 
L 6.3025 2.43748996 6.38818996 2.52318002 8 P 0 
L 6.38818996 2.52318002 6.38818996 3.05681998 8 P 0 
L 6.38818996 3.05681998 6.37181998 3.07318996 8 P 0 
L 6.37181998 3.07318996 5.88181998 3.07318996 8 P 0 
L 5.88181998 3.07318996 5.735 3.22001004 8 P 0 
L 5.735 3.22001004 5.735 3.515 8 P 0 
L 5.735 3.515 5.7095 3.5405 8 P 0 
L 5.7095 3.5405 5.66901998 3.5405 8 P 0 
L 5.66901998 3.5405 5.645 3.56451998 8 P 0 
L 5.645 3.56451998 5.645 3.74 8 P 0 
L 5.645 3.74 5.6175 3.7675 8 P 0 
L 5.6175 3.7675 5.6175 3.8175 8 P 0 
L 5.6175 3.8175 5.6475 3.8475 8 P 0 
L 5.6475 3.8475 5.6475 3.8764 8 P 0 
L 5.6475 3.8764 5.6711 3.9 8 P 0 
L 5.6711 3.9 5.70603996 3.9 8 P 0 
L 5.70603996 3.9 5.78285 3.97681004 8 P 0 
L 5.78285 3.97681004 5.86181004 3.97681004 8 P 0 
L 5.86181004 3.97681004 5.91 4.025 8 P 0 
L 5.91 4.025 5.91 4.04 8 P 0 
P 5.295 0.605 10 P 0 8 0;1=0,3=1
P 5.91 4.04 10 P 0 8 0;1=0,3=1
L 5.215 0.6 5.24653002 0.56846998 8 P 0 
L 5.24653002 0.56846998 5.84506004 0.56846998 8 P 0 
L 5.84506004 0.56846998 5.87658996 0.6 8 P 0 
L 5.87658996 0.6 6.135 0.6 8 P 0 
L 6.135 0.6 6.505 0.97 8 P 0 
L 6.505 0.97 6.505 1.78 8 P 0 
L 6.505 1.78 6.3625 1.9225 8 P 0 
L 6.3625 1.9225 6.3625 1.98013996 8 P 0 
L 6.3625 1.98013996 6.35351998 1.98911998 8 P 0 
L 6.35351998 1.98911998 6.35351998 2.0401 8 P 0 
L 6.35351998 2.0401 6.3615 2.04808002 8 P 0 
L 6.3615 2.04808002 6.3615 2.1085 8 P 0 
L 6.3615 2.1085 6.33 2.14 8 P 0 
L 6.33 2.14 6.33 2.42 8 P 0 
L 6.33 2.42 6.42 2.51 8 P 0 
L 6.42 2.51 6.42 3.07 8 P 0 
L 6.42 3.07 6.385 3.105 8 P 0 
L 6.385 3.105 5.9 3.105 8 P 0 
L 5.9 3.105 5.795 3.21 8 P 0 
L 5.795 3.21 5.795 3.51 8 P 0 
L 5.795 3.51 5.735 3.57 8 P 0 
L 5.735 3.57 5.735 3.885 8 P 0 
L 5.735 3.885 5.795 3.945 8 P 0 
L 5.795 3.945 5.875 3.945 8 P 0 
L 5.875 3.945 5.97 4.04 8 P 0 
L 5.97 4.04 6.025 4.04 8 P 0 
P 5.215 0.6 10 P 0 8 0;1=0,3=1
P 6.025 4.04 10 P 0 8 0;1=0,3=1
L 2.38 3.45 2.304 3.374 8 P 0 
L 2.304 3.374 2.249 3.374 8 P 0 
L 2.249 3.374 2.19 3.315 8 P 0 
L 2.19 3.315 2.19 3.195 8 P 0 
L 2.19 3.195 1.806 2.811 8 P 0 
L 1.806 2.811 1.245 2.811 8 P 0 
L 1.245 2.811 1.047 2.613 8 P 0 
L 1.047 2.613 1.047 2.497 8 P 0 
L 1.047 2.497 0.96 2.41 8 P 0 
P 0.96 2.41 10 P 0 8 0;1=2,3=1
P 2.38 3.45 10 P 0 8 0;1=2,3=1
L 2.527 0.44 2.527 0.35726998 4 P 0 
L 2.527 0.35726998 2.54526998 0.339 4 P 0 
P 2.54526998 0.339 9 P 0 8 0;1=8,3=1
P 2.527 0.44 9 P 0 8 0;1=4,3=1
L 5.875 1.9 5.865 1.89 4 P 0 
L 5.865 1.89 5.81001004 1.89 4 P 0 
L 5.81001004 1.89 5.7825 1.91751004 4 P 0 
L 5.7825 1.91751004 5.7825 2.1392 4 P 0 
L 5.7825 2.1392 5.79 2.1467 4 P 0 
L 5.79 2.1467 5.79 2.23671004 4 P 0 
L 5.79 2.23671004 5.8275 2.27421004 4 P 0 
L 5.8275 2.27421004 5.8275 2.27433002 4 P 0 
L 5.8275 2.27433002 5.83763996 2.28446998 4 P 0 
L 5.83763996 2.28446998 5.83763996 2.52938002 4 P 0 
L 5.83763996 2.52938002 5.7675 2.59951998 4 P 0 
L 5.7675 2.59951998 5.7675 2.665 4 P 0 
L 5.7675 2.665 5.59 2.8425 4 P 0 
L 5.59 2.8425 5.59 2.94001004 4 P 0 
L 5.59 2.94001004 5.44501004 3.085 4 P 0 
L 5.44501004 3.085 5.2433 3.085 4 P 0 
L 5.2433 3.085 5.178 3.1503 4 P 0 
L 5.178 3.1503 5.178 3.41698002 4 P 0 
L 5.178 3.41698002 5.10748002 3.4875 4 P 0 
L 5.10748002 3.4875 5.10748002 3.51251998 4 P 0 
L 5.10748002 3.51251998 5.055 3.565 4 P 0 
L 5.055 3.565 5.05498996 3.565 4 P 0 
L 5.05498996 3.565 5.05248996 3.5675 4 P 0 
L 5.05248996 3.5675 4.98748996 3.5675 4 P 0 
L 4.98748996 3.5675 4.98498996 3.565 4 P 0 
L 4.98498996 3.565 4.745 3.565 4 P 0 
L 4.745 3.565 4.7 3.61 4 P 0 
L 4.7 3.61 4.68616004 3.61 4 P 0 
L 4.68616004 3.61 4.68116004 3.615 4 P 0 
L 4.68116004 3.615 4.68116004 3.6362 4 P 0 
L 4.68116004 3.6362 4.67616004 3.6412 4 P 0 
L 4.67616004 3.6412 4.66116004 3.6412 4 P 0 
L 4.66116004 3.6412 4.65616004 3.6362 4 P 0 
L 4.65616004 3.6362 4.65616004 3.615 4 P 0 
L 4.65616004 3.615 4.65116004 3.61 4 P 0 
L 4.65116004 3.61 4.63616004 3.61 4 P 0 
L 4.63616004 3.61 4.63116004 3.615 4 P 0 
L 4.63116004 3.615 4.63116004 3.6362 4 P 0 
L 4.63116004 3.6362 4.62616004 3.6412 4 P 0 
L 4.62616004 3.6412 4.61116004 3.6412 4 P 0 
L 4.61116004 3.6412 4.60616004 3.6362 4 P 0 
L 4.60616004 3.6362 4.60616004 3.615 4 P 0 
L 4.60616004 3.615 4.60116004 3.61 4 P 0 
L 4.60116004 3.61 4.58616004 3.61 4 P 0 
L 4.58616004 3.61 4.58116004 3.615 4 P 0 
L 4.58116004 3.615 4.58116004 3.6362 4 P 0 
L 4.58116004 3.6362 4.57616004 3.6412 4 P 0 
L 4.57616004 3.6412 4.56116004 3.6412 4 P 0 
L 4.56116004 3.6412 4.55616004 3.6362 4 P 0 
L 4.55616004 3.6362 4.55616004 3.615 4 P 0 
L 4.55616004 3.615 4.55116004 3.61 4 P 0 
L 4.55116004 3.61 4.53616004 3.61 4 P 0 
L 4.53616004 3.61 4.53116004 3.615 4 P 0 
L 4.53116004 3.615 4.53116004 3.6362 4 P 0 
L 4.53116004 3.6362 4.52616004 3.6412 4 P 0 
L 4.52616004 3.6412 4.51116004 3.6412 4 P 0 
L 4.51116004 3.6412 4.50616004 3.6362 4 P 0 
L 4.50616004 3.6362 4.50616004 3.615 4 P 0 
L 4.50616004 3.615 4.50116004 3.61 4 P 0 
L 4.50116004 3.61 4.485 3.61 4 P 0 
L 4.485 3.61 4.3475 3.7475 4 P 0 
L 4.3475 3.7475 4.2725 3.7475 4 P 0 
L 4.2725 3.7475 4.215 3.69 4 P 0 
L 4.215 3.69 4.15 3.69 4 P 0 
L 4.15 3.69 4.135 3.675 4 P 0 
L 4.135 3.675 3.935 3.675 4 P 0 
L 3.935 3.675 3.91 3.65 4 P 0 
L 3.91 3.65 3.865 3.65 4 P 0 
P 5.875 1.9 10 P 0 8 0;1=0,3=1
P 3.865 3.65 10 P 0 8 0;1=2,3=1
L 6.06901998 1.86 6.01501004 1.86 4 P 0 
L 6.01501004 1.86 6.00001004 1.845 4 P 0 
L 6.00001004 1.845 5.9332 1.845 4 P 0 
L 5.9332 1.845 5.9082 1.87 4 P 0 
L 5.9082 1.87 5.80171998 1.87 4 P 0 
L 5.80171998 1.87 5.75986004 1.91186004 4 P 0 
L 5.75986004 1.91186004 5.75986004 2.14486004 4 P 0 
L 5.75986004 2.14486004 5.74 2.16471998 4 P 0 
L 5.74 2.16471998 5.74 2.215 4 P 0 
L 5.74 2.215 5.8115 2.2865 4 P 0 
L 5.8115 2.2865 5.8115 2.5235 4 P 0 
L 5.8115 2.5235 5.745 2.59 4 P 0 
L 5.745 2.59 5.745 2.655 4 P 0 
L 5.745 2.655 5.555 2.845 4 P 0 
L 5.555 2.845 5.555 2.945 4 P 0 
L 5.555 2.945 5.435 3.065 4 P 0 
L 5.435 3.065 5.23501004 3.065 4 P 0 
L 5.23501004 3.065 5.158 3.14201004 4 P 0 
L 5.158 3.14201004 5.158 3.40868996 4 P 0 
L 5.158 3.40868996 5.09918996 3.4675 4 P 0 
L 5.09918996 3.4675 5.06236998 3.4675 4 P 0 
L 5.06236998 3.4675 4.98486998 3.545 4 P 0 
L 4.98486998 3.545 4.73141998 3.545 4 P 0 
L 4.73141998 3.545 4.69321004 3.58321004 4 P 0 
L 4.69321004 3.58321004 4.48178996 3.58321004 4 P 0 
L 4.48178996 3.58321004 4.355 3.71 4 P 0 
L 4.355 3.71 4.295 3.71 4 P 0 
L 4.295 3.71 4.22 3.635 4 P 0 
L 4.22 3.635 4.14 3.635 4 P 0 
L 4.14 3.635 4.12 3.655 4 P 0 
L 4.12 3.655 3.945 3.655 4 P 0 
L 3.945 3.655 3.91 3.62 4 P 0 
L 3.91 3.62 3.84 3.62 4 P 0 
L 3.84 3.62 3.81 3.65 4 P 0 
P 6.06901998 1.86 10 P 0 8 0;1=0,3=1
P 3.81 3.65 10 P 0 8 0;1=2,3=1
L 2.0816 0.7399 2.0816 0.7184 4 P 0 
L 2.0816 0.7184 2.164 0.636 4 P 0 
L 2.164 0.636 2.235 0.636 4 P 0 
L 2.235 0.636 2.315 0.556 4 P 0 
L 2.315 0.556 2.535 0.556 4 P 0 
L 2.535 0.556 2.591 0.5 4 P 0 
L 2.591 0.5 2.83 0.5 4 P 0 
L 2.83 0.5 2.886 0.556 4 P 0 
L 2.886 0.556 3.04563996 0.556 4 P 0 
L 3.04563996 0.556 3.06863996 0.579 4 P 0 
L 3.06863996 0.579 3.11763996 0.579 4 P 0 
L 3.11763996 0.579 3.13873996 0.6001 4 P 0 
L 3.13873996 0.6001 3.3176 0.6001 4 P 0 
L 3.3176 0.6001 3.3815 0.664 4 P 0 
L 3.3815 0.664 3.486 0.664 4 P 0 
L 3.486 0.664 3.507 0.643 4 P 0 
L 3.507 0.643 3.632 0.643 4 P 0 
L 3.632 0.643 3.6614 0.6136 4 P 0 
L 3.6614 0.6136 4.7816 0.6136 4 P 0 
L 4.7816 0.6136 4.872 0.704 4 P 0 
L 4.872 0.704 5.088 0.704 4 P 0 
L 5.088 0.704 5.132 0.66 4 P 0 
P 5.132 0.66 10 P 0 8 0;1=2,3=1
P 2.0816 0.7399 10 P 0 8 0;1=2,3=1
L 4.42311004 1.86311004 4.43455 1.86311004 2 P 0 
A 4.43455 1.86311004 4.43905 1.85861004 4.43455 1.85861004 2 P 0 Y
L 4.43905 1.85861004 4.43905 1.77283002 2 P 0 
A 4.43905 1.77283002 4.43463996 1.76221004 4.42403602 1.77283898 2 P 0 Y
L 4.43463996 1.76221004 4.42443996 1.75201004 2 P 0 
A 4.42443996 1.75201004 4.4073 1.7449 4.40729537 1.76912549 2 P 0 Y
L 4.4073 1.7449 4.40018996 1.7449 2 P 0 
A 4.40018996 1.7449 4.39701004 1.74621998 4.40018996 1.74939045 2 P 0 Y
L 4.39701004 1.74621998 4.39558002 1.74765 2 P 0 
L 4.39558002 1.74765 4.39446004 1.74765 2 P 0 
L 4.39446004 1.74765 4.35436004 1.74765 6 P 0 
A 4.35436004 1.74765 4.35083996 1.75116998 4.35435994 1.75116998 6 P 0 Y
L 4.35083996 1.75116998 4.35083996 1.75118002 6 P 0 
A 4.35083996 1.75118002 4.34731998 1.7547 4.34731998 1.75118002 6 P 0 N
L 4.34731998 1.7547 4.32956004 1.7547 6 P 0 
A 4.32956004 1.7547 4.32603996 1.75118002 4.32955994 1.75118002 6 P 0 N
L 4.32603996 1.75118002 4.32603996 1.75116998 6 P 0 
A 4.32603996 1.75116998 4.32251998 1.74765 4.32251998 1.75116998 6 P 0 Y
L 4.32251998 1.74765 4.30476004 1.74765 6 P 0 
A 4.30476004 1.74765 4.30123996 1.75116998 4.30475994 1.75116998 6 P 0 Y
L 4.30123996 1.75116998 4.30123996 1.75118002 6 P 0 
A 4.30123996 1.75118002 4.29771998 1.7547 4.29771998 1.75118002 6 P 0 N
L 4.29771998 1.7547 4.27996004 1.7547 6 P 0 
A 4.27996004 1.7547 4.27643996 1.75118002 4.27995994 1.75118002 6 P 0 N
L 4.27643996 1.75118002 4.27643996 1.75116998 6 P 0 
A 4.27643996 1.75116998 4.27291998 1.74765 4.27291998 1.75116998 6 P 0 Y
L 4.27291998 1.74765 3.97125 1.74765 6 P 0 
A 3.97125 1.74765 3.96788002 1.75101998 3.97125 1.75101998 6 P 0 Y
L 3.96788002 1.75101998 3.96788002 1.75103002 6 P 0 
A 3.96788002 1.75103002 3.96451004 1.7544 3.96451004 1.75103002 6 P 0 N
L 3.96451004 1.7544 3.94645 1.7544 6 P 0 
A 3.94645 1.7544 3.94308002 1.75103002 3.94645 1.75103002 6 P 0 N
L 3.94308002 1.75103002 3.94308002 1.75101998 6 P 0 
A 3.94308002 1.75101998 3.93971004 1.74765 3.93971004 1.75101998 6 P 0 Y
L 3.93971004 1.74765 3.90925 1.74765 6 P 0 
A 3.90925 1.74765 3.90598002 1.75091998 3.90925 1.75091998 6 P 0 Y
L 3.90598002 1.75091998 3.90598002 1.75093002 6 P 0 
A 3.90598002 1.75093002 3.90271004 1.7542 3.90271004 1.75093002 6 P 0 N
L 3.90271004 1.7542 3.88445 1.7542 6 P 0 
A 3.88445 1.7542 3.88118002 1.75093002 3.88445 1.75093002 6 P 0 N
L 3.88118002 1.75093002 3.88118002 1.75091998 6 P 0 
A 3.88118002 1.75091998 3.87791004 1.74765 3.87791004 1.75091998 6 P 0 Y
L 3.87791004 1.74765 3.85965 1.74765 6 P 0 
A 3.85965 1.74765 3.85638002 1.75091998 3.85965 1.75091998 6 P 0 Y
L 3.85638002 1.75091998 3.85638002 1.75093002 6 P 0 
A 3.85638002 1.75093002 3.85311004 1.7542 3.85311004 1.75093002 6 P 0 N
L 3.85311004 1.7542 3.83485 1.7542 6 P 0 
A 3.83485 1.7542 3.83158002 1.75093002 3.83485 1.75093002 6 P 0 N
L 3.83158002 1.75093002 3.83158002 1.75091998 6 P 0 
A 3.83158002 1.75091998 3.82831004 1.74765 3.82831004 1.75091998 6 P 0 Y
L 3.82831004 1.74765 3.73983002 1.74765 6 P 0 
A 3.73983002 1.74765 3.7105 1.7598 3.73983159 1.78913022 6 P 0 Y
L 3.7105 1.7598 3.70255 1.76775 6 P 0 
A 3.70255 1.76775 3.70255 1.77218996 3.70476998 1.76996998 6 P 0 Y
L 3.70255 1.77218996 3.70256004 1.7722 6 P 0 
A 3.70256004 1.7722 3.70256004 1.77663996 3.70033996 1.77441998 6 P 0 N
L 3.70256004 1.77663996 3.68946004 1.78973996 6 P 0 
A 3.68946004 1.78973996 3.68501998 1.78973996 3.68723996 1.78751998 6 P 0 N
L 3.68501998 1.78973996 3.68501004 1.78973002 6 P 0 
A 3.68501004 1.78973002 3.68056998 1.78973002 3.68278996 1.79195 6 P 0 Y
L 3.68056998 1.78973002 3.66746998 1.80283002 6 P 0 
A 3.66746998 1.80283002 3.66746998 1.80726998 3.66968996 1.80505 6 P 0 Y
L 3.66746998 1.80726998 3.66748002 1.80728002 6 P 0 
A 3.66748002 1.80728002 3.66748002 1.81171998 3.66526004 1.8095 6 P 0 N
L 3.66748002 1.81171998 3.65438002 1.82481998 6 P 0 
A 3.65438002 1.82481998 3.64993996 1.82481998 3.65215994 1.8226 6 P 0 N
L 3.64993996 1.82481998 3.64993002 1.82481004 6 P 0 
A 3.64993002 1.82481004 3.64548996 1.82481004 3.64770994 1.82703002 6 P 0 Y
L 3.64548996 1.82481004 3.62171004 1.84858996 6 P 0 
A 3.62171004 1.84858996 3.61631004 1.8616 3.63471348 1.86161289 6 P 0 Y
L 3.61631004 1.8616 3.61631004 1.88688996 6 P 0 
A 3.61631004 1.88688996 3.62251004 1.89308996 3.62251004 1.88688996 6 P 0 Y
L 3.62251004 1.89308996 3.63661004 1.89308996 6 P 0 
A 3.63661004 1.89308996 3.64496998 1.88963002 3.63661004 1.88126033 6 P 0 Y
L 3.64496998 1.88963002 3.65101004 1.88358996 6 P 0 
P 4.42311004 1.86311004 9 P 0 8 0;1=11,3=1
P 3.65101004 1.88358996 9 P 0 8 0;1=9,3=1
L 3.65101004 1.91558996 3.64481998 1.9094 6 P 0 
A 3.64481998 1.9094 3.63683996 1.90608996 3.63683435 1.91737776 6 P 0 Y
L 3.63683996 1.90608996 3.62251004 1.90608996 6 P 0 
A 3.62251004 1.90608996 3.60331004 1.88688996 3.62251004 1.88688996 6 P 0 N
L 3.60331004 1.88688996 3.60331004 1.8616 6 P 0 
A 3.60331004 1.8616 3.61251004 1.83938996 3.6347189 1.8615999 6 P 0 N
L 3.61251004 1.83938996 3.7013 1.7506 6 P 0 
A 3.7013 1.7506 3.73981998 1.73465 3.7398186 1.78913563 6 P 0 N
L 3.73981998 1.73465 4.39446004 1.73465 6 P 0 
L 4.39446004 1.73465 4.39558002 1.73465 2 P 0 
L 4.39558002 1.73465 4.39701004 1.73608002 2 P 0 
A 4.39701004 1.73608002 4.40018996 1.7374 4.40018996 1.73290955 2 P 0 Y
L 4.40018996 1.7374 4.40731004 1.7374 2 P 0 
A 4.40731004 1.7374 4.42975 1.7467 4.40730748 1.76912874 2 P 0 N
L 4.42975 1.7467 4.43995 1.7569 2 P 0 
A 4.43995 1.7569 4.44655 1.77281998 4.42403287 1.77282687 2 P 0 N
L 4.44655 1.77281998 4.44655 1.85861004 2 P 0 
A 4.44655 1.85861004 4.45105 1.86311004 4.45105 1.85861004 2 P 0 Y
L 4.45105 1.86311004 4.46248002 1.86311004 2 P 0 
P 4.46248002 1.86311004 9 P 0 8 0;1=11,3=1
P 3.65101004 1.91558996 9 P 0 8 0;1=9,3=1
L 4.65933002 1.54816004 4.67266004 1.54816004 4 P 0 
L 4.67266004 1.54816004 4.6925 1.568 4 P 0 
L 4.6925 1.568 4.8609 1.568 4 P 0 
L 4.8609 1.568 4.8825 1.5464 4 P 0 
L 4.8825 1.5464 4.8825 1.5175 4 P 0 
L 4.8825 1.5175 4.915 1.485 4 P 0 
P 4.915 1.485 10 P 0 8 0;1=3,3=0
P 4.65933002 1.54816004 9 P 0 8 0;1=1,3=1
L 4.58058996 1.58753002 4.59881998 1.5693 1 P 0 
L 4.59881998 1.5693 4.6686 1.5693 1 P 0 
L 4.6686 1.5693 4.6813 1.582 1 P 0 
L 4.6813 1.582 4.774 1.582 1 P 0 
L 4.774 1.582 4.777 1.585 4 P 0 
L 4.777 1.585 4.92001004 1.585 4 P 0 
L 4.92001004 1.585 4.94 1.56501004 4 P 0 
L 4.94 1.56501004 4.94 1.52 4 P 0 
L 4.94 1.52 4.975 1.485 4 P 0 
P 4.975 1.485 10 P 0 8 0;1=3,3=0
P 4.58058996 1.58753002 9 P 0 8 0;1=1,3=1
L 5.395 2.92 5.394 2.921 4 P 0 
L 5.394 2.921 5.37836004 2.921 4 P 0 
L 5.37836004 2.921 5.37336004 2.916 4 P 0 
L 5.37336004 2.916 5.37336004 2.88 4 P 0 
L 5.37336004 2.88 5.36536004 2.872 4 P 0 
L 5.36536004 2.872 5.35636004 2.872 4 P 0 
L 5.35636004 2.872 5.34836004 2.88 4 P 0 
L 5.34836004 2.88 5.34836004 2.92 4 P 0 
L 5.34836004 2.92 5.34336004 2.925 4 P 0 
L 5.34336004 2.925 5.316 2.925 4 P 0 
L 5.316 2.925 5.165 2.774 4 P 0 
L 5.165 2.774 5.165 2.41 4 P 0 
L 5.165 2.41 4.9475 2.1925 4 P 0 
L 4.9475 2.1925 4.9475 2.14988002 4 P 0 
L 4.9475 2.14988002 4.9275 2.12988002 4 P 0 
L 4.9275 2.12988002 4.9275 2.07753002 4 P 0 
L 4.9275 2.07753002 4.915 2.06498996 4 P 0 
L 4.915 2.06498996 4.915 1.94 4 P 0 
L 4.915 1.94 4.85663996 1.88163996 4 P 0 
L 4.85663996 1.88163996 4.79335 1.88163996 4 P 0 
L 4.79335 1.88163996 4.75825 1.84653996 4 P 0 
L 4.75825 1.84653996 4.65153996 1.84653996 4 P 0 
L 4.65153996 1.84653996 4.64411004 1.83911004 1 P 0 
L 4.64411004 1.83911004 4.51721998 1.83911004 1 P 0 
L 4.51721998 1.83911004 4.50185 1.82373996 1 P 0 
P 4.50185 1.82373996 9 P 0 8 0;1=1,3=1
P 5.395 2.92 10 P 0 8 0;1=0,3=1
L 5.39976998 2.75123996 5.42276998 2.75123996 4 P 0 
L 5.42276998 2.75123996 5.43618002 2.73783002 4 P 0 
L 5.43618002 2.73783002 5.43618002 2.66711004 4 P 0 
L 5.43618002 2.66711004 5.494 2.60928996 4 P 0 
L 5.494 2.60928996 5.494 2.54578996 4 P 0 
L 5.494 2.54578996 5.46325 2.51503996 4 P 0 
L 5.46325 2.51503996 5.43675 2.51503996 4 P 0 
L 5.43675 2.51503996 5.38171004 2.46 4 P 0 
L 5.38171004 2.46 5.30411998 2.46 4 P 0 
L 5.30411998 2.46 5.04 2.19588002 4 P 0 
L 5.04 2.19588002 5.04 2.1033 4 P 0 
L 5.04 2.1033 5.0225 2.0858 4 P 0 
L 5.0225 2.0858 5.0225 2.02908996 4 P 0 
L 5.0225 2.02908996 5.015 2.02158996 4 P 0 
L 5.015 2.02158996 5.015 1.925 4 P 0 
P 5.015 1.925 10 P 0 8 0;1=2,3=1
P 5.39976998 2.75123996 9 P 0 8 0;1=7,3=1
L 4.46248002 1.82373996 4.48585 1.84711004 1 P 0 
L 4.48585 1.84711004 4.6299 1.84711004 1 P 0 
L 4.6299 1.84711004 4.64 1.85721004 1 P 0 
L 4.64 1.85721004 4.64 1.86871004 1 P 0 
L 4.64 1.86871004 4.65128996 1.88 4 P 0 
L 4.65128996 1.88 4.74011998 1.88 4 P 0 
L 4.74011998 1.88 4.76511998 1.905 4 P 0 
L 4.76511998 1.905 4.82598996 1.905 4 P 0 
L 4.82598996 1.905 4.895 1.97401004 4 P 0 
L 4.895 1.97401004 4.895 2.07623002 4 P 0 
L 4.895 2.07623002 4.90305 2.08428002 4 P 0 
L 4.90305 2.08428002 4.9075 2.08875 4 P 0 
L 4.9075 2.08875 4.9075 2.13816998 4 P 0 
L 4.9075 2.13816998 4.9275 2.15816998 4 P 0 
L 4.9275 2.15816998 4.9275 2.21751004 4 P 0 
L 4.9275 2.21751004 4.95 2.24001004 4 P 0 
L 4.95 2.24001004 4.95 2.272 4 P 0 
L 4.95 2.272 4.992 2.314 4 P 0 
L 4.992 2.314 5.00983002 2.314 4 P 0 
L 5.00983002 2.314 5.0935 2.39766998 4 P 0 
L 5.0935 2.39766998 5.0935 2.41633002 4 P 0 
L 5.0935 2.41633002 5.09 2.41983002 4 P 0 
L 5.09 2.41983002 5.09 2.68601004 4 P 0 
L 5.09 2.68601004 5.1415 2.73751004 4 P 0 
L 5.1415 2.73751004 5.1415 2.78151004 4 P 0 
L 5.1415 2.78151004 5.32606004 2.96606998 4 P 0 
L 5.32606004 2.96606998 5.375 2.96606998 4 P 0 
P 4.46248002 1.82373996 9 P 0 8 0;1=1,3=1
P 5.375 2.96606998 9 P 0 8 0;1=7,3=1
L 4.58058996 1.78436998 4.58058996 1.77351004 4 P 0 
L 4.58058996 1.77351004 4.61196004 1.74213996 4 P 0 
L 4.61196004 1.74213996 4.73191998 1.74213996 4 P 0 
L 4.73191998 1.74213996 4.75478002 1.765 4 P 0 
L 4.75478002 1.765 4.805 1.765 4 P 0 
L 4.805 1.765 4.84133996 1.80133996 4 P 0 
L 4.84133996 1.80133996 4.84841998 1.80133996 4 P 0 
L 4.84841998 1.80133996 4.91083996 1.73891998 4 P 0 
L 4.91083996 1.73891998 4.91791998 1.73891998 4 P 0 
L 4.91791998 1.73891998 4.92851998 1.74951998 4 P 0 
L 4.92851998 1.74951998 4.92851998 1.7566 4 P 0 
L 4.92851998 1.7566 4.8661 1.81901998 4 P 0 
L 4.8661 1.81901998 4.8661 1.8261 4 P 0 
L 4.8661 1.8261 4.8767 1.8367 4 P 0 
L 4.8767 1.8367 4.88378002 1.8367 4 P 0 
L 4.88378002 1.8367 4.9232 1.79728002 4 P 0 
L 4.9232 1.79728002 4.93028002 1.79728002 4 P 0 
L 4.93028002 1.79728002 4.94088002 1.80788002 4 P 0 
L 4.94088002 1.80788002 4.94088002 1.81496004 4 P 0 
L 4.94088002 1.81496004 4.90146004 1.85438002 4 P 0 
L 4.90146004 1.85438002 4.90146004 1.86146004 4 P 0 
L 4.90146004 1.86146004 4.935 1.895 4 P 0 
L 4.935 1.895 4.935 1.99816998 4 P 0 
L 4.935 1.99816998 4.9825 2.04566998 4 P 0 
L 4.9825 2.04566998 4.9825 2.10238002 4 P 0 
L 4.9825 2.10238002 5 2.11988002 4 P 0 
L 5 2.11988002 5 2.21671004 4 P 0 
L 5 2.21671004 5.185 2.40171004 4 P 0 
L 5.185 2.40171004 5.185 2.48 4 P 0 
L 5.185 2.48 5.205 2.5 4 P 0 
L 5.205 2.5 5.36 2.5 4 P 0 
L 5.36 2.5 5.423 2.563 4 P 0 
L 5.423 2.563 5.4525 2.563 4 P 0 
P 4.58058996 1.78436998 9 P 0 8 0;1=1,3=1
P 5.4525 2.563 9 P 0 8 0;1=7,3=1
P 3.545 0.6092 10 P 0 8 0;1=2,3=1
L 5.085 0.645 5.055 0.675 4 P 0 
L 5.055 0.675 4.875 0.675 4 P 0 
L 4.875 0.675 4.787 0.587 4 P 0 
L 4.787 0.587 3.563 0.587 4 P 0 
L 3.563 0.587 3.545 0.605 4 P 0 
L 3.545 0.605 3.545 0.6092 4 P 0 
P 5.085 0.645 10 P 0 8 0;1=2,3=1
P 3.495 0.61 10 P 0 8 0;1=2,3=1
L 5.04 0.645 4.9888 0.5938 4 P 0 
L 4.9888 0.5938 4.8228 0.5938 4 P 0 
L 4.8228 0.5938 4.793 0.564 4 P 0 
L 4.793 0.564 3.541 0.564 4 P 0 
L 3.541 0.564 3.495 0.61 4 P 0 
P 5.04 0.645 10 P 0 8 0;1=2,3=1
P 3.125 0.875 9 P 0 8 0;1=9,3=1
L 3.99005 1.54816004 3.97861004 1.54816004 2 P 0 
A 3.97861004 1.54816004 3.97411004 1.55266004 3.97861004 1.55266004 2 P 0 Y
L 3.97411004 1.55266004 3.97411004 1.55903002 2 P 0 
A 3.97411004 1.55903002 3.96211004 1.57103002 3.96211004 1.55903002 2 P 0 N
L 3.96211004 1.57103002 3.93823996 1.57103002 2 P 0 
A 3.93823996 1.57103002 3.93731998 1.5711 3.93827431 1.57756398 2 P 0 Y
L 3.93731998 1.5711 3.93273996 1.57183996 2 P 0 
A 3.93273996 1.57183996 3.92826004 1.5722 3.92826014 1.54415069 2 P 0 N
L 3.92826004 1.5722 3.86241998 1.5722 2 P 0 
A 3.86241998 1.5722 3.846 1.579 3.8624188 1.59542205 2 P 0 Y
L 3.846 1.579 3.8435 1.5815 2 P 0 
A 3.8435 1.5815 3.83203002 1.58625 3.8320315 1.57003022 2 P 0 N
L 3.83203002 1.58625 3.80758996 1.58625 2 P 0 
A 3.80758996 1.58625 3.80321998 1.58718002 3.8076187 1.59711722 2 P 0 Y
A 3.80321998 1.58718002 3.80168002 1.58801004 3.80758937 1.59713032 2 P 0 Y
A 3.80168002 1.58801004 3.79828002 1.589 3.79831762 1.58279557 2 P 0 N
L 3.79828002 1.589 3.39263002 1.589 6 P 0 
A 3.39263002 1.589 3.34701998 1.57826004 3.39261309 1.48685433 6 P 0 N
A 3.34701998 1.57826004 3.3386 1.57218996 3.36145246 1.54936545 6 P 0 N
L 3.3386 1.57218996 3.17171004 1.40531004 6 P 0 
A 3.17171004 1.40531004 3.16561004 1.39675 3.19419734 1.38283179 6 P 0 N
A 3.16561004 1.39675 3.1557 1.35381004 3.2537122 1.35380344 6 P 0 N
L 3.1557 1.35381004 3.1557 0.89923002 6 P 0 
A 3.1557 0.89923002 3.15448996 0.89313996 3.13985699 0.8992126 6 P 0 Y
A 3.15448996 0.89313996 3.15021998 0.88676998 3.13627923 0.90073091 6 P 0 Y
L 3.15021998 0.88676998 3.14571998 0.88226998 6 P 0 
A 3.14571998 0.88226998 3.12816998 0.875 3.12816919 0.89981988 6 P 0 Y
L 3.12816998 0.875 3.125 0.875 6 P 0 
P 3.99005 1.54816004 9 P 0 8 0;1=11,3=1
P 3.14763002 0.85236998 9 P 0 8 0;1=9,3=1
L 3.95066998 1.54816004 3.96211004 1.54816004 2 P 0 
A 3.96211004 1.54816004 3.96661004 1.55266004 3.96211004 1.55266004 2 P 0 N
L 3.96661004 1.55266004 3.96661004 1.55903002 2 P 0 
A 3.96661004 1.55903002 3.96211004 1.56353002 3.96211004 1.55903002 2 P 0 N
L 3.96211004 1.56353002 3.93823002 1.56353002 2 P 0 
A 3.93823002 1.56353002 3.93598996 1.56371004 3.93823081 1.57756722 2 P 0 Y
L 3.93598996 1.56371004 3.93153996 1.56443002 2 P 0 
A 3.93153996 1.56443002 3.92826998 1.5647 3.92821969 1.54415404 2 P 0 N
L 3.92826998 1.5647 3.86241998 1.5647 2 P 0 
A 3.86241998 1.5647 3.84068996 1.5737 3.86241575 1.59542283 2 P 0 Y
L 3.84068996 1.5737 3.84068002 1.57368996 2 P 0 
L 3.84068002 1.57368996 3.83818996 1.57618996 2 P 0 
L 3.83818996 1.57618996 3.83818996 1.5762 2 P 0 
A 3.83818996 1.5762 3.83203996 1.57875 3.83202835 1.570031 2 P 0 N
L 3.83203996 1.57875 3.8076 1.57875 2 P 0 
L 3.8076 1.57875 3.80758002 1.57875 2 P 0 
A 3.80758002 1.57875 3.80018996 1.58031004 3.80759823 1.59712037 2 P 0 Y
A 3.80018996 1.58031004 3.79828002 1.576 3.79922126 1.57816102 2 P 0 Y
L 3.79828002 1.576 3.66181004 1.576 6 P 0 
A 3.66181004 1.576 3.65856004 1.57275 3.66181004 1.57275 6 P 0 N
A 3.65856004 1.57275 3.65531004 1.5695 3.65531004 1.57275 6 P 0 Y
L 3.65531004 1.5695 3.63701004 1.5695 6 P 0 
A 3.63701004 1.5695 3.63376004 1.57275 3.63701004 1.57275 6 P 0 Y
A 3.63376004 1.57275 3.63051004 1.576 3.63051004 1.57275 6 P 0 N
L 3.63051004 1.576 3.47578996 1.576 6 P 0 
A 3.47578996 1.576 3.47253996 1.57275 3.47578996 1.57275 6 P 0 N
A 3.47253996 1.57275 3.46928996 1.5695 3.46928996 1.57275 6 P 0 Y
L 3.46928996 1.5695 3.45098996 1.5695 6 P 0 
A 3.45098996 1.5695 3.44773996 1.57275 3.45098996 1.57275 6 P 0 Y
A 3.44773996 1.57275 3.44448996 1.576 3.44448996 1.57275 6 P 0 N
L 3.44448996 1.576 3.39261998 1.576 6 P 0 
A 3.39261998 1.576 3.35283002 1.56663002 3.39261417 1.48685453 6 P 0 N
A 3.35283002 1.56663002 3.3478 1.563 3.36146073 1.54937067 6 P 0 N
L 3.3478 1.563 3.31773002 1.53293002 6 P 0 
A 3.31773002 1.53293002 3.31773002 1.52838996 3.32 1.53065994 6 P 0 N
A 3.31773002 1.52838996 3.31773002 1.52385 3.31546004 1.52611998 6 P 0 Y
L 3.31773002 1.52385 3.30473002 1.51085 6 P 0 
A 3.30473002 1.51085 3.30018996 1.51085 3.30245994 1.51311998 6 P 0 Y
A 3.30018996 1.51085 3.29565 1.51085 3.29791998 1.50858002 6 P 0 N
L 3.29565 1.51085 3.21801998 1.43321998 6 P 0 
A 3.21801998 1.43321998 3.21801998 1.42861998 3.22031998 1.43091998 6 P 0 N
A 3.21801998 1.42861998 3.21801998 1.42401998 3.21571998 1.42631998 6 P 0 Y
L 3.21801998 1.42401998 3.20508002 1.41108002 6 P 0 
A 3.20508002 1.41108002 3.20048002 1.41108002 3.20278002 1.41338002 6 P 0 Y
A 3.20048002 1.41108002 3.19588002 1.41108002 3.19818002 1.40878002 6 P 0 N
L 3.19588002 1.41108002 3.18091004 1.39611004 6 P 0 
A 3.18091004 1.39611004 3.1773 1.39105 3.19418829 1.382819 6 P 0 N
A 3.1773 1.39105 3.1687 1.3538 3.25371033 1.35379114 6 P 0 N
L 3.1687 1.3538 3.1687 0.89923002 6 P 0 
A 3.1687 0.89923002 3.1665 0.88816004 3.1398564 0.89920866 6 P 0 Y
A 3.1665 0.88816004 3.15941998 0.87758002 3.136275 0.90072726 6 P 0 Y
L 3.15941998 0.87758002 3.15391998 0.87208002 6 P 0 
A 3.15391998 0.87208002 3.14763002 0.85688996 3.16911033 0.85689262 6 P 0 N
L 3.14763002 0.85688996 3.14763002 0.85236998 6 P 0 
P 3.95066998 1.54816004 9 P 0 8 0;1=11,3=1
P 2.81855 0.763 9 P 0 8 0;1=9,3=1
L 3.9113 1.50878996 3.89986998 1.50878996 2 P 0 
A 3.89986998 1.50878996 3.89536998 1.51328996 3.89986998 1.51328996 2 P 0 Y
L 3.89536998 1.51328996 3.89536998 1.51966004 2 P 0 
A 3.89536998 1.51966004 3.88213002 1.5329 3.88213002 1.51966004 2 P 0 N
L 3.88213002 1.5329 3.84075 1.5329 2 P 0 
L 3.84075 1.5329 3.838 1.53565 2 P 0 
L 3.838 1.53565 3.83688002 1.53565 2 P 0 
L 3.83688002 1.53565 3.828 1.53565 6 P 0 
A 3.828 1.53565 3.81033002 1.52833002 3.82800118 1.51065984 6 P 0 N
L 3.81033002 1.52833002 3.8015 1.5195 6 P 0 
A 3.8015 1.5195 3.78338996 1.512 3.78339213 1.53760965 6 P 0 Y
L 3.78338996 1.512 3.41265 1.512 6 P 0 
A 3.41265 1.512 3.3535 1.4875 3.41265787 1.42832835 6 P 0 N
L 3.3535 1.4875 3.23848996 1.37248996 6 P 0 
L 3.23848996 1.37248996 3.23848996 1.3725 6 P 0 
L 3.23848996 1.3725 3.23591004 1.36991998 6 P 0 
L 3.23591004 1.36991998 3.23591004 1.36991004 6 P 0 
A 3.23591004 1.36991004 3.214 1.31701004 3.2888314 1.31700374 6 P 0 N
L 3.214 1.31701004 3.214 0.82648002 6 P 0 
A 3.214 0.82648002 3.19651998 0.809 3.19651998 0.82648002 6 P 0 Y
L 3.19651998 0.809 2.85305 0.809 6 P 0 
A 2.85305 0.809 2.82805 0.784 2.85305 0.784 6 P 0 N
L 2.82805 0.784 2.82805 0.7725 6 P 0 
L 2.82805 0.7725 2.81855 0.763 6 P 0 
P 3.9113 1.50878996 9 P 0 8 0;1=11,3=1
P 2.85055 0.763 9 P 0 8 0;1=9,3=1
L 3.87193002 1.50878996 3.88336998 1.50878996 2 P 0 
A 3.88336998 1.50878996 3.88786998 1.51328996 3.88336998 1.51328996 2 P 0 N
L 3.88786998 1.51328996 3.88786998 1.51966004 2 P 0 
A 3.88786998 1.51966004 3.88213002 1.5254 3.88213002 1.51966004 2 P 0 N
L 3.88213002 1.5254 3.84075 1.5254 2 P 0 
L 3.84075 1.5254 3.838 1.52265 2 P 0 
L 3.838 1.52265 3.83688002 1.52265 2 P 0 
L 3.83688002 1.52265 3.82801004 1.52265 6 P 0 
A 3.82801004 1.52265 3.81953002 1.51913002 3.82801427 1.51066516 6 P 0 N
L 3.81953002 1.51913002 3.8177 1.5173 6 P 0 
L 3.8177 1.5173 3.81768996 1.5173 6 P 0 
L 3.81768996 1.5173 3.81068996 1.5103 6 P 0 
A 3.81068996 1.5103 3.78338002 1.499 3.78339675 1.53761093 6 P 0 Y
L 3.78338002 1.499 3.41266004 1.499 6 P 0 
A 3.41266004 1.499 3.36268996 1.4783 3.4126625 1.42832963 6 P 0 N
L 3.36268996 1.4783 3.32361004 1.43921998 6 P 0 
A 3.32361004 1.43921998 3.32361004 1.43448002 3.32598002 1.43685 6 P 0 N
L 3.32361004 1.43448002 3.32361998 1.43446998 6 P 0 
A 3.32361998 1.43446998 3.32361998 1.42973002 3.32125 1.4321 6 P 0 Y
L 3.32361998 1.42973002 3.31081998 1.41693002 6 P 0 
A 3.31081998 1.41693002 3.30608002 1.41693002 3.30845 1.4193 6 P 0 Y
L 3.30608002 1.41693002 3.30606998 1.41693996 6 P 0 
A 3.30606998 1.41693996 3.30133002 1.41693996 3.3037 1.41456998 6 P 0 N
L 3.30133002 1.41693996 3.24511004 1.36071998 6 P 0 
A 3.24511004 1.36071998 3.227 1.317 3.28883012 1.31699902 6 P 0 N
L 3.227 1.317 3.227 0.82648002 6 P 0 
A 3.227 0.82648002 3.19651998 0.796 3.19651998 0.82648002 6 P 0 Y
L 3.19651998 0.796 3.1754 0.796 6 P 0 
A 3.1754 0.796 3.17205 0.79265 3.1754 0.79265 6 P 0 N
A 3.17205 0.79265 3.1687 0.7893 3.1687 0.79265 6 P 0 Y
L 3.1687 0.7893 3.1506 0.7893 6 P 0 
A 3.1506 0.7893 3.14725 0.79265 3.1506 0.79265 6 P 0 Y
A 3.14725 0.79265 3.1439 0.796 3.1439 0.79265 6 P 0 N
L 3.1439 0.796 3.0374 0.796 6 P 0 
A 3.0374 0.796 3.03405 0.79265 3.0374 0.79265 6 P 0 N
A 3.03405 0.79265 3.0307 0.7893 3.0307 0.79265 6 P 0 Y
L 3.0307 0.7893 3.0126 0.7893 6 P 0 
A 3.0126 0.7893 3.00925 0.79265 3.0126 0.79265 6 P 0 Y
A 3.00925 0.79265 3.0059 0.796 3.0059 0.79265 6 P 0 N
L 3.0059 0.796 2.8974 0.796 6 P 0 
A 2.8974 0.796 2.89405 0.79265 2.8974 0.79265 6 P 0 N
A 2.89405 0.79265 2.8907 0.7893 2.8907 0.79265 6 P 0 Y
L 2.8907 0.7893 2.8726 0.7893 6 P 0 
A 2.8726 0.7893 2.86925 0.79265 2.8726 0.79265 6 P 0 Y
A 2.86925 0.79265 2.8659 0.796 2.8659 0.79265 6 P 0 N
L 2.8659 0.796 2.85305 0.796 6 P 0 
A 2.85305 0.796 2.84105 0.784 2.85305 0.784 6 P 0 N
L 2.84105 0.784 2.84105 0.7725 6 P 0 
L 2.84105 0.7725 2.85055 0.763 6 P 0 
P 3.87193002 1.50878996 9 P 0 8 0;1=11,3=1
P 2.66706998 0.763 9 P 0 8 0;1=9,3=1
L 3.99005 1.46941998 3.97861004 1.46941998 2 P 0 
A 3.97861004 1.46941998 3.9727 1.46351004 3.97860994 1.46351004 2 P 0 N
L 3.9727 1.46351004 3.9727 1.45891004 2 P 0 
A 3.9727 1.45891004 3.96028996 1.4465 3.96028996 1.45891004 2 P 0 Y
L 3.96028996 1.4465 3.94098996 1.4465 2 P 0 
L 3.94098996 1.4465 3.94096998 1.44648002 2 P 0 
L 3.94096998 1.44648002 3.94095 1.4465 2 P 0 
A 3.94095 1.4465 3.93273996 1.44605 3.94073583 1.37528809 2 P 0 N
A 3.93273996 1.44605 3.92306004 1.4455 3.92301722 1.53170974 2 P 0 Y
L 3.92306004 1.4455 3.85421998 1.4455 2 P 0 
A 3.85421998 1.4455 3.85101998 1.44521998 3.85427313 1.42646791 2 P 0 N
L 3.85101998 1.44521998 3.84326004 1.44388002 2 P 0 
A 3.84326004 1.44388002 3.83878002 1.4435 3.83879833 1.46988041 2 P 0 Y
L 3.83878002 1.4435 3.77473996 1.4435 2 P 0 
A 3.77473996 1.4435 3.77083996 1.44391004 3.77470807 1.46194921 2 P 0 Y
A 3.77083996 1.44391004 3.77075 1.4435 3.7707748 1.44370945 2 P 0 Y
L 3.77075 1.4435 3.768 1.44075 2 P 0 
L 3.768 1.44075 3.76688002 1.44075 2 P 0 
L 3.76688002 1.44075 3.47026998 1.44075 6 P 0 
A 3.47026998 1.44075 3.46118002 1.43943002 3.47026437 1.40882953 6 P 0 N
A 3.46118002 1.43943002 3.45585 1.43625 3.46477844 1.42734173 6 P 0 N
L 3.45585 1.43625 3.29661998 1.27701998 6 P 0 
A 3.29661998 1.27701998 3.29321998 1.27183002 3.30738612 1.26625827 6 P 0 N
A 3.29321998 1.27183002 3.2902 1.25593996 3.33355896 1.2559313 6 P 0 N
L 3.2902 1.25593996 3.2902 0.80903996 6 P 0 
A 3.2902 0.80903996 3.20816004 0.727 3.20816004 0.80903996 6 P 0 Y
L 3.20816004 0.727 2.95116998 0.727 6 P 0 
A 2.95116998 0.727 2.94056004 0.72415 2.95116752 0.70583465 6 P 0 N
A 2.94056004 0.72415 2.91691998 0.7178 2.91692215 0.76497077 6 P 0 Y
L 2.91691998 0.7178 2.69601004 0.7178 6 P 0 
A 2.69601004 0.7178 2.67733996 0.73248996 2.69600207 0.73699921 6 P 0 Y
A 2.67733996 0.73248996 2.67656998 0.73901004 2.70431063 0.73898051 6 P 0 Y
L 2.67656998 0.73901004 2.67656998 0.7535 6 P 0 
L 2.67656998 0.7535 2.66706998 0.763 6 P 0 
P 3.99005 1.46941998 9 P 0 8 0;1=11,3=1
P 2.69906998 0.763 9 P 0 8 0;1=9,3=1
L 3.95066998 1.46941998 3.95928996 1.46941998 2 P 0 
A 3.95928996 1.46941998 3.9652 1.46351004 3.95928996 1.46351004 2 P 0 Y
L 3.9652 1.46351004 3.9652 1.45891004 2 P 0 
A 3.9652 1.45891004 3.96028996 1.454 3.96028996 1.45891004 2 P 0 Y
L 3.96028996 1.454 3.94096998 1.454 2 P 0 
A 3.94096998 1.454 3.9319 1.45351004 3.94067382 1.37528593 2 P 0 N
A 3.9319 1.45351004 3.92305 1.453 3.92295364 1.53170728 2 P 0 Y
L 3.92305 1.453 3.85421998 1.453 2 P 0 
A 3.85421998 1.453 3.84973996 1.45261004 3.85427244 1.42646782 2 P 0 N
L 3.84973996 1.45261004 3.84198996 1.45128002 2 P 0 
A 3.84198996 1.45128002 3.83878996 1.451 3.83875039 1.46987628 2 P 0 Y
L 3.83878996 1.451 3.77475 1.451 2 P 0 
A 3.77475 1.451 3.7688 1.45276004 3.77475256 1.46194606 2 P 0 Y
A 3.7688 1.45276004 3.76543002 1.45375 3.76543868 1.44754872 2 P 0 N
L 3.76543002 1.45375 3.47028002 1.45375 6 P 0 
A 3.47028002 1.45375 3.45746998 1.4519 3.47022943 1.40882451 6 P 0 N
A 3.45746998 1.4519 3.44665 1.44543996 3.46478858 1.42735059 6 P 0 N
L 3.44665 1.44543996 3.28741998 1.28621998 6 P 0 
A 3.28741998 1.28621998 3.28111998 1.27658996 3.30739518 1.26627628 6 P 0 N
A 3.28111998 1.27658996 3.2772 1.25595 3.33355984 1.25593819 6 P 0 N
L 3.2772 1.25595 3.2772 1.08865 6 P 0 
A 3.2772 1.08865 3.274 1.08545 3.274 1.08865 6 P 0 Y
A 3.274 1.08545 3.2708 1.08225 3.274 1.08225 6 P 0 N
L 3.2708 1.08225 3.2708 1.06385 6 P 0 
A 3.2708 1.06385 3.274 1.06065 3.274 1.06385 6 P 0 N
A 3.274 1.06065 3.2772 1.05745 3.274 1.05745 6 P 0 Y
L 3.2772 1.05745 3.2772 0.87618996 6 P 0 
A 3.2772 0.87618996 3.274 0.87298996 3.274 0.87618996 6 P 0 Y
A 3.274 0.87298996 3.2708 0.86978996 3.274 0.86978996 6 P 0 N
L 3.2708 0.86978996 3.2708 0.85138996 6 P 0 
A 3.2708 0.85138996 3.274 0.84818996 3.274 0.85138996 6 P 0 N
A 3.274 0.84818996 3.2772 0.84498996 3.274 0.84498996 6 P 0 Y
L 3.2772 0.84498996 3.2772 0.80903996 6 P 0 
A 3.2772 0.80903996 3.20816004 0.74 3.20816004 0.80903996 6 P 0 Y
L 3.20816004 0.74 3.15403996 0.74 6 P 0 
A 3.15403996 0.74 3.15073996 0.7433 3.15403996 0.7433 6 P 0 Y
A 3.15073996 0.7433 3.14743996 0.7466 3.14743996 0.7433 6 P 0 N
L 3.14743996 0.7466 3.12923996 0.7466 6 P 0 
A 3.12923996 0.7466 3.12593996 0.7433 3.12923996 0.7433 6 P 0 N
A 3.12593996 0.7433 3.12263996 0.74 3.12263996 0.7433 6 P 0 Y
L 3.12263996 0.74 3.00403996 0.74 6 P 0 
A 3.00403996 0.74 3.00073996 0.7433 3.00403996 0.7433 6 P 0 Y
A 3.00073996 0.7433 2.99743996 0.7466 2.99743996 0.7433 6 P 0 N
L 2.99743996 0.7466 2.97923996 0.7466 6 P 0 
A 2.97923996 0.7466 2.97593996 0.7433 2.97923996 0.7433 6 P 0 N
A 2.97593996 0.7433 2.97263996 0.74 2.97263996 0.7433 6 P 0 Y
L 2.97263996 0.74 2.95118002 0.74 6 P 0 
A 2.95118002 0.74 2.93403996 0.73541004 2.95114606 0.70582894 6 P 0 N
A 2.93403996 0.73541004 2.91691004 0.7308 2.91690069 0.76496506 6 P 0 Y
L 2.91691004 0.7308 2.77491004 0.7308 6 P 0 
A 2.77491004 0.7308 2.77151004 0.7342 2.77491004 0.7342 6 P 0 Y
A 2.77151004 0.7342 2.76811004 0.7376 2.76811004 0.7342 6 P 0 N
L 2.76811004 0.7376 2.75011004 0.7376 6 P 0 
A 2.75011004 0.7376 2.74671004 0.7342 2.75011004 0.7342 6 P 0 N
A 2.74671004 0.7342 2.74331004 0.7308 2.74331004 0.7342 6 P 0 Y
L 2.74331004 0.7308 2.69601004 0.7308 6 P 0 
A 2.69601004 0.7308 2.68998002 0.73553996 2.69600423 0.73699823 6 P 0 Y
A 2.68998002 0.73553996 2.68956998 0.739 2.70430974 0.73899242 6 P 0 Y
L 2.68956998 0.739 2.68956998 0.7535 6 P 0 
L 2.68956998 0.7535 2.69906998 0.763 6 P 0 
P 3.95066998 1.46941998 9 P 0 8 0;1=11,3=1
P 2.47021998 0.763 9 P 0 8 0;1=9,3=1
L 3.9113 1.43005 3.89986998 1.43005 2 P 0 
A 3.89986998 1.43005 3.89436004 1.42615 3.89986998 1.42420768 2 P 0 N
A 3.89436004 1.42615 3.89425 1.42581998 3.89984537 1.4241376 2 P 0 N
A 3.89425 1.42581998 3.89403002 1.42421004 3.89987234 1.42423169 2 P 0 N
L 3.89403002 1.42421004 3.89403002 1.41928002 2 P 0 
A 3.89403002 1.41928002 3.8812 1.4064 3.8811499 1.41928002 2 P 0 Y
L 3.8812 1.4064 3.8672 1.4064 2 P 0 
A 3.8672 1.4064 3.85748002 1.40236998 3.86720522 1.39265039 2 P 0 N
L 3.85748002 1.40236998 3.8394 1.38428996 2 P 0 
A 3.8394 1.38428996 3.78981004 1.36375 3.78980256 1.43390079 2 P 0 Y
L 3.78981004 1.36375 3.76053002 1.36375 2 P 0 
A 3.76053002 1.36375 3.75735 1.36243002 3.76052992 1.35925955 2 P 0 N
L 3.75735 1.36243002 3.75591998 1.361 2 P 0 
L 3.75591998 1.361 3.7548 1.361 2 P 0 
L 3.7548 1.361 3.49451004 1.361 6 P 0 
A 3.49451004 1.361 3.47236004 1.35591004 3.49450472 1.31028297 6 P 0 N
A 3.47236004 1.35591004 3.46731004 1.35231004 3.48052067 1.33912037 6 P 0 N
L 3.46731004 1.35231004 3.35251998 1.23751998 6 P 0 
A 3.35251998 1.23751998 3.34891998 1.23246004 3.36560433 1.2244002 6 P 0 N
A 3.34891998 1.23246004 3.3452 1.22181004 3.39405709 1.21071919 6 P 0 N
A 3.3452 1.22181004 3.3445 1.21565 3.37225197 1.21561614 6 P 0 N
L 3.3445 1.21565 3.3445 0.7672 6 P 0 
A 3.3445 0.7672 3.2323 0.655 3.2323 0.7672 6 P 0 Y
L 3.2323 0.655 2.55301004 0.655 6 P 0 
A 2.55301004 0.655 2.52441004 0.66266004 2.55298612 0.71213219 6 P 0 Y
A 2.52441004 0.66266004 2.5168 0.6685 2.5428003 0.69450266 6 P 0 Y
L 2.5168 0.6685 2.49138996 0.69391998 6 P 0 
A 2.49138996 0.69391998 2.48538002 0.70206004 2.51521289 0.71779744 6 P 0 Y
A 2.48538002 0.70206004 2.47971998 0.72501004 2.52893504 0.7249747 6 P 0 Y
L 2.47971998 0.72501004 2.47971998 0.75093002 6 P 0 
A 2.47971998 0.75093002 2.4779 0.75531998 2.47351545 0.75092992 6 P 0 N
L 2.4779 0.75531998 2.47021998 0.763 6 P 0 
P 3.9113 1.43005 9 P 0 8 0;1=11,3=1
P 2.50221998 0.763 9 P 0 8 0;1=9,3=1
L 3.87193002 1.43005 3.88111998 1.43005 2 P 0 
A 3.88111998 1.43005 3.88496004 1.42846004 3.88112096 1.42462018 2 P 0 Y
A 3.88496004 1.42846004 3.88653002 1.42466998 3.88116998 1.42466978 2 P 0 Y
L 3.88653002 1.42466998 3.88653002 1.41928002 2 P 0 
A 3.88653002 1.41928002 3.88118002 1.4139 3.8811499 1.41928002 2 P 0 Y
L 3.88118002 1.4139 3.8672 1.4139 2 P 0 
A 3.8672 1.4139 3.85216998 1.40768002 3.86719311 1.39264715 2 P 0 N
L 3.85216998 1.40768002 3.8341 1.3896 2 P 0 
A 3.8341 1.3896 3.7898 1.37125 3.78979951 1.4338999 2 P 0 Y
L 3.7898 1.37125 3.76053002 1.37125 2 P 0 
A 3.76053002 1.37125 3.75735 1.37256998 3.76052992 1.37574045 2 P 0 Y
L 3.75735 1.37256998 3.75591998 1.374 2 P 0 
L 3.75591998 1.374 3.7548 1.374 2 P 0 
L 3.7548 1.374 3.49451004 1.374 6 P 0 
A 3.49451004 1.374 3.46668002 1.36761004 3.49449163 1.3102811 6 P 0 N
A 3.46668002 1.36761004 3.45811004 1.3615 3.4805252 1.33912549 6 P 0 N
L 3.45811004 1.3615 3.34333002 1.24671998 6 P 0 
A 3.34333002 1.24671998 3.33721004 1.23811004 3.36560689 1.22440541 6 P 0 N
A 3.33721004 1.23811004 3.33251998 1.2247 3.39405177 1.21070482 6 P 0 N
A 3.33251998 1.2247 3.3315 1.21566004 3.37225453 1.21563917 6 P 0 N
L 3.3315 1.21566004 3.3315 0.7672 6 P 0 
A 3.3315 0.7672 3.2323 0.668 3.2323 0.7672 6 P 0 Y
L 3.2323 0.668 3.21496004 0.668 6 P 0 
A 3.21496004 0.668 3.21166004 0.6713 3.21496004 0.6713 6 P 0 Y
A 3.21166004 0.6713 3.20836004 0.6746 3.20836004 0.6713 6 P 0 N
L 3.20836004 0.6746 3.19016004 0.6746 6 P 0 
A 3.19016004 0.6746 3.18686004 0.6713 3.19016004 0.6713 6 P 0 N
A 3.18686004 0.6713 3.18356004 0.668 3.18356004 0.6713 6 P 0 Y
L 3.18356004 0.668 3.07496004 0.668 6 P 0 
A 3.07496004 0.668 3.07166004 0.6713 3.07496004 0.6713 6 P 0 Y
A 3.07166004 0.6713 3.06836004 0.6746 3.06836004 0.6713 6 P 0 N
L 3.06836004 0.6746 3.05016004 0.6746 6 P 0 
A 3.05016004 0.6746 3.04686004 0.6713 3.05016004 0.6713 6 P 0 N
A 3.04686004 0.6713 3.04356004 0.668 3.04356004 0.6713 6 P 0 Y
L 3.04356004 0.668 2.89496004 0.668 6 P 0 
A 2.89496004 0.668 2.89166004 0.6713 2.89496004 0.6713 6 P 0 Y
A 2.89166004 0.6713 2.88836004 0.6746 2.88836004 0.6713 6 P 0 N
L 2.88836004 0.6746 2.87016004 0.6746 6 P 0 
A 2.87016004 0.6746 2.86686004 0.6713 2.87016004 0.6713 6 P 0 N
A 2.86686004 0.6713 2.86356004 0.668 2.86356004 0.6713 6 P 0 Y
L 2.86356004 0.668 2.75496004 0.668 6 P 0 
A 2.75496004 0.668 2.75166004 0.6713 2.75496004 0.6713 6 P 0 Y
A 2.75166004 0.6713 2.74836004 0.6746 2.74836004 0.6713 6 P 0 N
L 2.74836004 0.6746 2.73016004 0.6746 6 P 0 
A 2.73016004 0.6746 2.72686004 0.6713 2.73016004 0.6713 6 P 0 N
A 2.72686004 0.6713 2.72356004 0.668 2.72356004 0.6713 6 P 0 Y
L 2.72356004 0.668 2.61526004 0.668 6 P 0 
A 2.61526004 0.668 2.61201004 0.67125 2.61526004 0.67125 6 P 0 Y
A 2.61201004 0.67125 2.60876004 0.6745 2.60876004 0.67125 6 P 0 N
L 2.60876004 0.6745 2.59046004 0.6745 6 P 0 
A 2.59046004 0.6745 2.58721004 0.67125 2.59046004 0.67125 6 P 0 N
A 2.58721004 0.67125 2.58396004 0.668 2.58396004 0.67125 6 P 0 Y
L 2.58396004 0.668 2.553 0.668 6 P 0 
A 2.553 0.668 2.53091998 0.67391998 2.55299823 0.71213002 6 P 0 Y
A 2.53091998 0.67391998 2.526 0.6777 2.54281555 0.69449488 6 P 0 Y
L 2.526 0.6777 2.50058002 0.70311998 6 P 0 
A 2.50058002 0.70311998 2.49688996 0.70811998 2.51522264 0.71778799 6 P 0 Y
A 2.49688996 0.70811998 2.49271998 0.725 2.5289311 0.72499035 6 P 0 Y
L 2.49271998 0.725 2.49271998 0.7421 6 P 0 
A 2.49271998 0.7421 2.50078002 0.76156004 2.52024203 0.7420999 6 P 0 Y
L 2.50078002 0.76156004 2.50221998 0.763 6 P 0 
P 3.87193002 1.43005 9 P 0 8 0;1=11,3=1
P 1.889 0.5496 10 P 0 8 0;1=2,3=1
L 1.889 0.5496 1.9936 0.445 4 P 0 
L 1.9936 0.445 2.355 0.445 4 P 0 
L 2.355 0.445 2.3965 0.4865 4 P 0 
L 2.3965 0.4865 2.435 0.4865 4 P 0 
P 2.435 0.4865 9 P 0 8 0;1=4,3=1
L 3.80999961 -1.25 3.80999961 -1.33 5 P 0 ;0,2=23,4=0.000000
L 3.80999961 -1.33 3.8500003 -1.33 5 P 0 ;0,2=23,4=0.000000
L 3.90999902 -1.25 3.90199892 -1.25266614 5 P 0 ;0,2=23,4=0.000000
L 3.90199892 -1.25266614 3.8960002 -1.25933386 5 P 0 ;0,2=23,4=0.000000
L 3.8960002 -1.25933386 3.89199921 -1.26733209 5 P 0 ;0,2=23,4=0.000000
L 3.89199921 -1.26733209 3.8889999 -1.27800138 5 P 0 ;0,2=23,4=0.000000
L 3.8889999 -1.27800138 3.8880001 -1.29000128 5 P 0 ;0,2=23,4=0.000000
L 3.8880001 -1.29000128 3.8889999 -1.30200118 5 P 0 ;0,2=23,4=0.000000
L 3.8889999 -1.30200118 3.89199921 -1.31266801 5 P 0 ;0,2=23,4=0.000000
L 3.89199921 -1.31266801 3.8960002 -1.3206687 5 P 0 ;0,2=23,4=0.000000
L 3.8960002 -1.3206687 3.90199892 -1.32733396 5 P 0 ;0,2=23,4=0.000000
L 3.90199892 -1.32733396 3.90999902 -1.33 5 P 0 ;0,2=23,4=0.000000
L 3.90999902 -1.33 3.91799911 -1.32733396 5 P 0 ;0,2=23,4=0.000000
L 3.91799911 -1.32733396 3.9239997 -1.3206687 5 P 0 ;0,2=23,4=0.000000
L 3.9239997 -1.3206687 3.92800069 -1.31266801 5 P 0 ;0,2=23,4=0.000000
L 3.92800069 -1.31266801 3.931 -1.30200118 5 P 0 ;0,2=23,4=0.000000
L 3.931 -1.30200118 3.9319998 -1.29000128 5 P 0 ;0,2=23,4=0.000000
L 3.9319998 -1.29000128 3.931 -1.27800138 5 P 0 ;0,2=23,4=0.000000
L 3.931 -1.27800138 3.92800069 -1.26733209 5 P 0 ;0,2=23,4=0.000000
L 3.92800069 -1.26733209 3.9239997 -1.25933386 5 P 0 ;0,2=23,4=0.000000
L 3.9239997 -1.25933386 3.91799911 -1.25266614 5 P 0 ;0,2=23,4=0.000000
L 3.91799911 -1.25266614 3.90999902 -1.25 5 P 0 ;0,2=23,4=0.000000
L 3.98999902 -1.33 3.99699941 -1.32866703 5 P 0 ;0,2=23,4=0.000000
L 3.99699941 -1.32866703 4.00499951 -1.32466782 5 P 0 ;0,2=23,4=0.000000
L 4.00499951 -1.32466782 4.0100003 -1.31800266 5 P 0 ;0,2=23,4=0.000000
L 4.0100003 -1.31800266 4.0119998 -1.30866644 5 P 0 ;0,2=23,4=0.000000
L 4.0119998 -1.30866644 4.0100003 -1.29933504 5 P 0 ;0,2=23,4=0.000000
L 4.0100003 -1.29933504 4.0039997 -1.29133435 5 P 0 ;0,2=23,4=0.000000
L 4.0039997 -1.29133435 3.9949998 -1.28733278 5 P 0 ;0,2=23,4=0.000000
L 3.9949998 -1.28733278 3.9850001 -1.28733278 5 P 0 ;0,2=23,4=0.000000
L 3.9850001 -1.28733278 3.97899951 -1.28466663 5 P 0 ;0,2=23,4=0.000000
L 3.97899951 -1.28466663 3.97399882 -1.27800138 5 P 0 ;0,2=23,4=0.000000
L 3.97399882 -1.27800138 3.97199921 -1.26866762 5 P 0 ;0,2=23,4=0.000000
L 3.97199921 -1.26866762 3.97500039 -1.25933386 5 P 0 ;0,2=23,4=0.000000
L 3.97500039 -1.25933386 3.98199892 -1.25266614 5 P 0 ;0,2=23,4=0.000000
L 3.98199892 -1.25266614 3.98999902 -1.25 5 P 0 ;0,2=23,4=0.000000
L 3.98999902 -1.25 3.99799911 -1.25266614 5 P 0 ;0,2=23,4=0.000000
L 3.99799911 -1.25266614 4.00499951 -1.25933386 5 P 0 ;0,2=23,4=0.000000
L 4.00499951 -1.25933386 4.00800069 -1.26866762 5 P 0 ;0,2=23,4=0.000000
L 4.00800069 -1.26866762 4.00599931 -1.27800138 5 P 0 ;0,2=23,4=0.000000
L 4.00599931 -1.27800138 4.00100039 -1.28466663 5 P 0 ;0,2=23,4=0.000000
L 4.00100039 -1.28466663 3.9949998 -1.28733278 5 P 0 ;0,2=23,4=0.000000
L 3.9949998 -1.28733278 3.9850001 -1.28733278 5 P 0 ;0,2=23,4=0.000000
L 3.9850001 -1.28733278 3.9760002 -1.29133435 5 P 0 ;0,2=23,4=0.000000
L 3.9760002 -1.29133435 3.96999961 -1.29933504 5 P 0 ;0,2=23,4=0.000000
L 3.96999961 -1.29933504 3.9680001 -1.30866644 5 P 0 ;0,2=23,4=0.000000
L 3.9680001 -1.30866644 3.96999961 -1.31800266 5 P 0 ;0,2=23,4=0.000000
L 3.96999961 -1.31800266 3.97500039 -1.32466782 5 P 0 ;0,2=23,4=0.000000
L 3.97500039 -1.32466782 3.98300049 -1.32866703 5 P 0 ;0,2=23,4=0.000000
L 3.98300049 -1.32866703 3.98999902 -1.33 5 P 0 ;0,2=23,4=0.000000
L 4.04 -1.35666585 4.1 -1.35666585 5 P 0 ;0,2=23,4=0.000000
L 4.1289999 -1.31933563 4.137 -1.32600089 5 P 0 ;0,2=23,4=0.000000
L 4.137 -1.32600089 4.1459999 -1.33 5 P 0 ;0,2=23,4=0.000000
L 4.1459999 -1.33 4.154 -1.33 5 P 0 ;0,2=23,4=0.000000
L 4.154 -1.33 4.1620001 -1.32600089 5 P 0 ;0,2=23,4=0.000000
L 4.1620001 -1.32600089 4.16800069 -1.31933563 5 P 0 ;0,2=23,4=0.000000
L 4.16800069 -1.31933563 4.171 -1.30999941 5 P 0 ;0,2=23,4=0.000000
L 4.171 -1.30999941 4.16900049 -1.30066811 5 P 0 ;0,2=23,4=0.000000
L 4.16900049 -1.30066811 4.1639997 -1.29266732 5 P 0 ;0,2=23,4=0.000000
L 4.1639997 -1.29266732 4.1549998 -1.28733278 5 P 0 ;0,2=23,4=0.000000
L 4.1549998 -1.28733278 4.14300049 -1.28466663 5 P 0 ;0,2=23,4=0.000000
L 4.14300049 -1.28466663 4.1360002 -1.27933445 5 P 0 ;0,2=23,4=0.000000
L 4.1360002 -1.27933445 4.13299902 -1.27000069 5 P 0 ;0,2=23,4=0.000000
L 4.13299902 -1.27000069 4.13500039 -1.26066683 5 P 0 ;0,2=23,4=0.000000
L 4.13500039 -1.26066683 4.13999931 -1.25400167 5 P 0 ;0,2=23,4=0.000000
L 4.13999931 -1.25400167 4.1469997 -1.25 5 P 0 ;0,2=23,4=0.000000
L 4.1469997 -1.25 4.154 -1.25 5 P 0 ;0,2=23,4=0.000000
L 4.154 -1.25 4.16100039 -1.25266614 5 P 0 ;0,2=23,4=0.000000
L 4.16100039 -1.25266614 4.16700089 -1.25933386 5 P 0 ;0,2=23,4=0.000000
L 4.2179998 -1.25 4.24199833 -1.25 5 P 0 ;0,2=23,4=0.000000
L 4.22999902 -1.25 4.22999902 -1.33 5 P 0 ;0,2=23,4=0.000000
L 4.2179998 -1.33 4.24199833 -1.33 5 P 0 ;0,2=23,4=0.000000
L 4.31599961 -1.29000128 4.33600079 -1.29000128 5 P 0 ;0,2=23,4=0.000000
L 4.33600079 -1.29000128 4.33600079 -1.31400098 5 P 0 ;0,2=23,4=0.000000
L 4.33600079 -1.31400098 4.3300003 -1.32200177 5 P 0 ;0,2=23,4=0.000000
L 4.3300003 -1.32200177 4.3229999 -1.32733396 5 P 0 ;0,2=23,4=0.000000
L 4.3229999 -1.32733396 4.3130002 -1.33 5 P 0 ;0,2=23,4=0.000000
L 4.3130002 -1.33 4.30300049 -1.32733396 5 P 0 ;0,2=23,4=0.000000
L 4.30300049 -1.32733396 4.2960002 -1.32200177 5 P 0 ;0,2=23,4=0.000000
L 4.2960002 -1.32200177 4.28999961 -1.31400098 5 P 0 ;0,2=23,4=0.000000
L 4.28999961 -1.31400098 4.28599862 -1.30466722 5 P 0 ;0,2=23,4=0.000000
L 4.28599862 -1.30466722 4.28399911 -1.29400039 5 P 0 ;0,2=23,4=0.000000
L 4.28399911 -1.29400039 4.28399911 -1.28466663 5 P 0 ;0,2=23,4=0.000000
L 4.28399911 -1.28466663 4.28599862 -1.27666831 5 P 0 ;0,2=23,4=0.000000
L 4.28599862 -1.27666831 4.28999961 -1.26733209 5 P 0 ;0,2=23,4=0.000000
L 4.28999961 -1.26733209 4.2960002 -1.25933386 5 P 0 ;0,2=23,4=0.000000
L 4.2960002 -1.25933386 4.30199892 -1.25400167 5 P 0 ;0,2=23,4=0.000000
L 4.30199892 -1.25400167 4.30999902 -1.25 5 P 0 ;0,2=23,4=0.000000
L 4.30999902 -1.25 4.31699941 -1.25 5 P 0 ;0,2=23,4=0.000000
L 4.31699941 -1.25 4.32499951 -1.25266614 5 P 0 ;0,2=23,4=0.000000
L 4.32499951 -1.25266614 4.331 -1.25800079 5 P 0 ;0,2=23,4=0.000000
L 4.37099941 -1.26333297 4.377 -1.25533465 5 P 0 ;0,2=23,4=0.000000
L 4.377 -1.25533465 4.3840003 -1.25133307 5 P 0 ;0,2=23,4=0.000000
L 4.3840003 -1.25133307 4.39200039 -1.25 5 P 0 ;0,2=23,4=0.000000
L 4.39200039 -1.25 4.4020001 -1.25266614 5 P 0 ;0,2=23,4=0.000000
L 4.4020001 -1.25266614 4.40900049 -1.25933386 5 P 0 ;0,2=23,4=0.000000
L 4.40900049 -1.25933386 4.411 -1.26733209 5 P 0 ;0,2=23,4=0.000000
L 4.411 -1.26733209 4.4100003 -1.27533533 5 P 0 ;0,2=23,4=0.000000
L 4.4100003 -1.27533533 4.40599931 -1.28200049 5 P 0 ;0,2=23,4=0.000000
L 4.40599931 -1.28200049 4.3859999 -1.29533346 5 P 0 ;0,2=23,4=0.000000
L 4.3859999 -1.29533346 4.377 -1.30466722 5 P 0 ;0,2=23,4=0.000000
L 4.377 -1.30466722 4.37099941 -1.31800266 5 P 0 ;0,2=23,4=0.000000
L 4.37099941 -1.31800266 4.3689999 -1.33 5 P 0 ;0,2=23,4=0.000000
L 4.3689999 -1.33 4.411 -1.33 5 P 0 ;0,2=23,4=0.000000
L 3.16 -0.655 3.16 -1.58 7 P 0 ;0
L 1.36 -0.655 1.36 -1.58 7 P 0 ;0
L 1.36 -1.58 5.06 -1.58 7 P 0 ;0
L 5.06 -1.58 5.06 -0.655 7 P 0 ;0
L 5.06 -0.655 1.36 -0.655 7 P 0 ;0
A 1.559 -1.33655 1.559 -1.33655 1.55268002 -1.33655 5 P 0 N;0
A 1.54775 -1.205 1.54775 -1.205 1.53883002 -1.205 5 P 0 N;0
A 1.54763996 -0.99775 1.54763996 -0.99775 1.53871998 -0.99775 5 P 0 N;0
A 1.54063996 -1.10118002 1.54063996 -1.10118002 1.52603996 -1.10118002 5 P 0 N;0
A 1.49695 -1.10118002 1.49695 -1.10118002 1.48656998 -1.10118002 5 P 0 N;0
A 1.45963996 -1.10118002 1.45963996 -1.10118002 1.4533 -1.10118002 5 P 0 N;0
A 1.52135 -0.98681004 1.52135 -0.98681004 1.51503002 -0.98681004 5 P 0 N;0
A 1.79433002 -1.43586998 1.79433002 -1.43586998 1.78798996 -1.43586998 5 P 0 N;0
A 1.79841004 -1.40261004 1.79841004 -1.40261004 1.78798996 -1.40261004 5 P 0 N;0
A 1.80255 -1.36311004 1.80255 -1.36311004 1.78798996 -1.36311004 5 P 0 N;0
A 1.80668996 -1.31528002 1.80668996 -1.31528002 1.78798996 -1.31528002 5 P 0 N;0
A 1.68013002 -1.37456004 1.68013002 -1.37456004 1.67378996 -1.37456004 5 P 0 N;0
A 1.69321998 -1.35033002 1.69321998 -1.35033002 1.6843 -1.35033002 5 P 0 N;0
A 1.7108 -1.31738996 1.7108 -1.31738996 1.69798002 -1.31738996 5 P 0 N;0
A 1.89666998 -1.31511004 1.89666998 -1.31511004 1.88383996 -1.31511004 5 P 0 N;0
A 1.88198996 -1.16876004 1.88198996 -1.16876004 1.85558996 -1.16876004 5 P 0 N;0
A 1.87928002 -1.27801998 1.87928002 -1.27801998 1.86343996 -1.27801998 5 P 0 N;0
A 1.86176998 -1.23075 1.86176998 -1.23075 1.84206004 -1.23075 5 P 0 N;0
A 1.80978996 -1.25916998 1.80978996 -1.25916998 1.78798996 -1.25916998 5 P 0 N;0
A 1.74681004 -1.16876004 1.74681004 -1.16876004 1.72041004 -1.16876004 5 P 0 N;0
A 1.67813002 -1.15513002 1.67813002 -1.15513002 1.65841998 -1.15513002 5 P 0 N;0
A 1.73018002 -1.27816004 1.73018002 -1.27816004 1.71433996 -1.27816004 5 P 0 N;0
A 1.75373002 -1.23081004 1.75373002 -1.23081004 1.73405 -1.23081004 5 P 0 N;0
A 1.65531004 -1.25255 1.65531004 -1.25255 1.63661998 -1.25255 5 P 0 N;0
A 1.69808996 -1.21291998 1.69808996 -1.21291998 1.67628996 -1.21291998 5 P 0 N;0
A 1.81438996 -1.1968 1.81438996 -1.1968 1.78798996 -1.1968 5 P 0 N;0
A 1.6269 -1.1749 1.6269 -1.1749 1.61106004 -1.1749 5 P 0 N;0
A 1.58461004 -1.19126004 1.58461004 -1.19126004 1.57178002 -1.19126004 5 P 0 N;0
A 1.5853 -1.31428002 1.5853 -1.31428002 1.57488996 -1.31428002 5 P 0 N;0
A 1.61735 -1.28638996 1.61735 -1.28638996 1.60276998 -1.28638996 5 P 0 N;0
A 1.88198996 -1.03361004 1.88198996 -1.03361004 1.85558996 -1.03361004 5 P 0 N;0
A 1.71881004 -1.10118002 1.71881004 -1.10118002 1.69238996 -1.10118002 5 P 0 N;0
A 1.65183002 -1.10118002 1.65183002 -1.10118002 1.63003002 -1.10118002 5 P 0 N;0
A 1.67801998 -1.04738996 1.67801998 -1.04738996 1.65831004 -1.04738996 5 P 0 N;0
A 1.74681004 -1.03361004 1.74681004 -1.03361004 1.72041004 -1.03361004 5 P 0 N;0
A 1.69811998 -0.98951004 1.69811998 -0.98951004 1.67631998 -0.98951004 5 P 0 N;0
A 1.81438996 -1.00556004 1.81438996 -1.00556004 1.78798996 -1.00556004 5 P 0 N;0
A 1.59258002 -1.10118002 1.59258002 -1.10118002 1.5739 -1.10118002 5 P 0 N;0
A 1.58451004 -1.01148996 1.58451004 -1.01148996 1.57168002 -1.01148996 5 P 0 N;0
A 1.62681004 -1.02773996 1.62681004 -1.02773996 1.61096998 -1.02773996 5 P 0 N;0
A 1.92148002 -1.21285 1.92148002 -1.21285 1.89968002 -1.21285 5 P 0 N;0
A 1.92148002 -0.98951004 1.92148002 -0.98951004 1.89968002 -0.98951004 5 P 0 N;0
A 1.80978996 -0.9432 1.80978996 -0.9432 1.78798996 -0.9432 5 P 0 N;0
A 1.80668996 -0.88708002 1.80668996 -0.88708002 1.78798996 -0.88708002 5 P 0 N;0
A 1.80255 -0.83923996 1.80255 -0.83923996 1.78798996 -0.83923996 5 P 0 N;0
A 1.8919 -0.88538002 1.8919 -0.88538002 1.87906998 -0.88538002 5 P 0 N;0
A 1.87838996 -0.92456998 1.87838996 -0.92456998 1.86255 -0.92456998 5 P 0 N;0
A 1.65531004 -0.94981004 1.65531004 -0.94981004 1.63661998 -0.94981004 5 P 0 N;0
A 1.73123002 -0.92378002 1.73123002 -0.92378002 1.71538996 -0.92378002 5 P 0 N;0
A 1.71216998 -0.88443996 1.71216998 -0.88443996 1.69935 -0.88443996 5 P 0 N;0
A 1.86225 -0.97178002 1.86225 -0.97178002 1.84253996 -0.97178002 5 P 0 N;0
A 1.75451998 -0.97123996 1.75451998 -0.97123996 1.73483996 -0.97123996 5 P 0 N;0
A 1.61741998 -0.91601004 1.61741998 -0.91601004 1.60283996 -0.91601004 5 P 0 N;0
A 1.5853 -0.88808996 1.5853 -0.88808996 1.57488996 -0.88808996 5 P 0 N;0
A 1.79841004 -0.79975 1.79841004 -0.79975 1.78798996 -0.79975 5 P 0 N;0
A 1.79433002 -0.76648002 1.79433002 -0.76648002 1.78798996 -0.76648002 5 P 0 N;0
A 1.92135 -1.36781004 1.92135 -1.36781004 1.91503996 -1.36781004 5 P 0 N;0
A 1.91096004 -1.34658002 1.91096004 -1.34658002 1.90203996 -1.34658002 5 P 0 N;0
A 2.19078996 -1.1806 2.26591004 -1.16473002 2.21741014 -1.12088169 5 P 0 N;0
A 2.15903002 -1.1402 2.19078996 -1.18061004 2.22093406 -1.12423278 5 P 0 N;0
A 2.05721004 -1.16178996 2.08853002 -1.16658996 2.08281614 -1.09929134 5 P 0 N;0
A 2.00546998 -1.13951998 2.03345 -1.17196004 2.07793927 -1.10530069 5 P 0 N;0
A 2.03346004 -1.17195 2.0847 -1.18461004 2.07891181 -1.09801299 5 P 0 N;0
A 2.0847 -1.18461998 2.14261004 -1.15663002 2.07348435 -1.08751378 5 P 0 N;0
A 2.08853996 -1.16658002 2.13313002 -1.14451998 2.06368967 -1.06025512 5 P 0 N;0
A 1.95808002 -1.25255 1.95808002 -1.25255 1.93938996 -1.25255 5 P 0 N;0
A 1.98775 -1.28635 1.98775 -1.28635 1.97316998 -1.28635 5 P 0 N;0
A 2.27411998 -1.11835 2.15906004 -1.11835 2.21658996 -1.11611998 5 P 0 N;0
L 2.25188002 -1.11418002 2.1807 -1.11418002 5 P 0 ;0
L 2.1807 -1.11418002 2.1807 -1.11398996 5 P 8191 ;0
A 2.25188996 -1.11398996 2.18071004 -1.11398996 2.2163 -1.1124 5 P 0 N;0
A 2.08028996 -1.03428996 2.02048996 -1.08258996 2.0798126 -1.09486801 5 P 0 N;0
A 2.13151998 -1.05146004 2.0803 -1.0343 2.0802999 -1.11932195 5 P 0 N;0
A 2.1315 -1.05146998 2.14175 -1.03951004 2.1356003 -1.04461171 5 P 0 N;0
A 2.14175 -1.03951004 2.08283002 -1.01613002 2.07772461 -1.11492805 5 P 0 N;0
A 2.08283996 -1.01611998 2.00698002 -1.05835 2.08064724 -1.10143169 5 P 0 N;0
L 2.27413002 -1.12868996 2.18073996 -1.12868996 5 P 0 ;0
A 2.18075 -1.12868996 2.19083002 -1.15751998 2.22417795 -1.12968307 5 P 0 N;0
A 2.19083002 -1.15753002 2.25311004 -1.15211004 2.21927195 -1.12381791 5 P 0 N;0
L 2.15903996 -1.1402 2.15903996 -1.11835 5 P 8191 ;0
A 2.02048996 -1.0826 2.05721998 -1.16181004 2.09087933 -1.0980811 5 P 0 N;0
A 2.00698996 -1.05836004 2.00546998 -1.13953002 2.09672953 -1.10063967 5 P 0 N;0
A 2.14258996 -1.15661004 2.13313996 -1.14453002 2.13544892 -1.15246004 5 P 0 N;0
A 1.95808002 -0.94981004 1.95808002 -0.94981004 1.93938996 -0.94981004 5 P 0 N;0
A 1.90183996 -0.8525 1.90183996 -0.8525 1.89291004 -0.8525 5 P 0 N;0
A 1.91108002 -0.82726998 1.91108002 -0.82726998 1.90473996 -0.82726998 5 P 0 N;0
L 2.32081004 -1.02041004 2.32081004 -1.17625 5 P 0 ;0
A 2.49568002 -1.15528996 2.47898002 -1.16443002 2.4882003 -1.1614502 5 P 0 N;0
A 2.47896998 -1.16443996 2.50283002 -1.18086004 2.51649242 -1.13546152 5 P 0 N;0
A 2.50281998 -1.18086998 2.54318002 -1.1834 2.52887392 -1.08843022 5 P 0 N;0
A 2.52306998 -1.16761004 2.52848996 -1.16771998 2.52673258 -1.12070098 5 P 0 N;0
A 2.49566004 -1.15528996 2.52306998 -1.1676 2.5255122 -1.12549094 5 P 0 N;0
A 2.37851998 -1.15753002 2.4408 -1.15211004 2.40696191 -1.12381791 5 P 0 N;0
A 2.45358002 -1.16471998 2.44078996 -1.1521 2.44541191 -1.16020689 5 P 0 N;0
A 2.37848002 -1.1806 2.4536 -1.16473002 2.4051001 -1.12088169 5 P 0 N;0
A 2.34673002 -1.1402 2.37848996 -1.18061004 2.40863406 -1.12423278 5 P 0 N;0
A 2.2659 -1.16471998 2.25311004 -1.1521 2.25773199 -1.16020689 5 P 0 N;0
A 2.3006 -1.17626004 2.3208 -1.17626004 2.3107 -1.17386841 5 P 0 N;0
L 2.30058996 -1.17625 2.30058996 -1.02033996 5 P 0 ;0
A 2.50836998 -1.10106004 2.54306004 -1.11513002 2.56106673 -1.02093386 5 P 0 N;0
A 2.51081004 -1.07948002 2.50836998 -1.10103996 2.51886093 -1.09130915 5 P 0 N;0
A 2.53611004 -1.07688996 2.5108 -1.07948996 2.52742205 -1.11680827 5 P 0 N;0
A 2.56883996 -1.07368002 2.50178002 -1.06358996 2.5273123 -1.12178858 5 P 0 N;0
A 2.50178996 -1.06358996 2.48536998 -1.08248996 2.52926211 -1.10403986 5 P 0 N;0
L 2.48536998 -1.0825 2.48536998 -1.09748002 5 P 8191 ;0
A 2.48536998 -1.09748002 2.49956004 -1.12031004 2.51189104 -1.09682067 5 P 0 N;0
A 2.46181004 -1.11835 2.34675 -1.11835 2.40428002 -1.11611998 5 P 0 N;0
L 2.43956998 -1.11418002 2.36841004 -1.11418002 5 P 0 ;0
L 2.36841004 -1.11418002 2.36841004 -1.11398996 5 P 8191 ;0
A 2.43958002 -1.11398996 2.3684 -1.11398996 2.40398996 -1.1124 5 P 0 N;0
L 2.43956998 -1.11398996 2.43956998 -1.11418002 5 P 8191 ;0
A 2.49955 -1.1203 2.52723002 -1.12985 2.58163209 -0.92727982 5 P 0 N;0
A 2.55001998 -1.14328002 2.52723002 -1.12986004 2.51462185 -1.17733228 5 P 0 N;0
L 2.46181004 -1.12868996 2.36843996 -1.12868996 5 P 0 ;0
A 2.36843996 -1.12868996 2.37851998 -1.15751998 2.41186801 -1.12968307 5 P 0 N;0
L 2.34675 -1.1402 2.34675 -1.11835 5 P 8191 ;0
L 2.46181004 -1.11835 2.46181004 -1.12868996 5 P 8191 ;0
L 2.25188002 -1.11398996 2.25188002 -1.11418002 5 P 8191 ;0
A 2.3208 -1.02041004 2.3006 -1.02033996 2.31069163 -1.02276978 5 P 0 N;0
L 2.27413002 -1.11835 2.27413002 -1.12868996 5 P 8191 ;0
A 2.52848996 -1.16771004 2.54891998 -1.15895 2.52774557 -1.13777087 5 P 0 N;0
A 2.55608002 -1.08618002 2.53611998 -1.07688996 2.5249185 -1.12704419 5 P 0 N;0
L 2.71926004 -1.06796998 2.71926004 -1.17483996 5 P 0 ;0
A 2.78888996 -1.16296998 2.81508002 -1.16676998 2.8083499 -1.12100167 5 P 0 N;0
A 2.8151 -1.16675 2.83966004 -1.15211998 2.80521398 -1.12222392 5 P 0 N;0
A 2.85201004 -1.16508002 2.83966004 -1.15211004 2.84505768 -1.15933514 5 P 0 N;0
L 2.85201004 -1.16508002 2.84523996 -1.17161004 5 P 8191 ;0
A 2.81425 -1.1835 2.84525 -1.17161004 2.81425 -1.13714291 5 P 0 N;0
L 2.81425 -1.1835 2.79571004 -1.1835 5 P 8191 ;0
A 2.75886998 -1.16443002 2.79571998 -1.18351998 2.80278976 -1.12476142 5 P 0 N;0
A 2.74528996 -1.13568002 2.75888002 -1.16443002 2.80246565 -1.12624016 5 P 0 N;0
A 2.54316998 -1.1834 2.56906004 -1.1647 2.5305814 -1.13869892 5 P 0 N;0
A 2.56906004 -1.1647 2.57053996 -1.13728002 2.53763041 -1.14925374 5 P 0 N;0
A 2.65463996 -1.18351998 2.66863996 -1.17373996 2.65440246 -1.16826969 5 P 0 N;0
L 2.65463002 -1.1835 2.64165 -1.1835 5 P 8191 ;0
A 2.60955 -1.16043002 2.64163996 -1.18351004 2.63911063 -1.15317815 5 P 0 N;0
A 2.62978002 -1.15461998 2.66001998 -1.16328996 2.6502374 -1.14033868 5 P 0 N;0
A 2.66863996 -1.17375 2.66001998 -1.16328996 2.66100344 -1.17126132 5 P 0 N;0
A 2.6962 -1.17483996 2.71926004 -1.17483996 2.70773002 -1.17286427 5 P 0 N;0
L 2.69618996 -1.17483996 2.69618996 -1.06796998 5 P 0 ;0
A 2.83833002 -1.09275 2.82661998 -1.08201998 2.74555758 -1.18224094 5 P 0 N;0
A 2.82661998 -1.08198996 2.80036998 -1.07538996 2.80348839 -1.11848878 5 P 0 N;0
A 2.80036004 -1.07541998 2.76848996 -1.09933002 2.80700217 -1.1174685 5 P 0 N;0
A 2.76848996 -1.09931998 2.76446004 -1.12066004 2.82315728 -1.120694 5 P 0 N;0
A 2.74998002 -1.09273996 2.74528996 -1.11838996 2.8498563 -1.12425591 5 P 0 N;0
A 2.7954 -1.05776998 2.74998996 -1.09273996 2.80799961 -1.12109961 5 P 0 N;0
L 2.79541004 -1.05776998 2.80918996 -1.05776998 5 P 8191 ;0
A 2.85401998 -1.08106004 2.80918996 -1.05776998 2.80626024 -1.1181998 5 P 0 N;0
A 2.83833002 -1.09273996 2.85403002 -1.08106004 2.84418386 -1.08421683 5 P 0 N;0
L 2.76445 -1.12066004 2.76445 -1.12943002 5 P 8191 ;0
A 2.76446004 -1.12943002 2.76836998 -1.14305 2.80607844 -1.12485364 5 P 0 N;0
A 2.76836998 -1.14305 2.78891004 -1.16296998 2.80906152 -1.12164144 5 P 0 N;0
L 2.74528996 -1.13566004 2.74528996 -1.11838996 5 P 8191 ;0
A 2.55606004 -1.0862 2.56885 -1.07366998 2.56205354 -1.0795252 5 P 0 N;0
L 2.60953996 -1.07953996 2.59981998 -1.07953996 5 P 8191 ;0
A 2.5993 -1.05931998 2.59981004 -1.07955 2.6022813 -1.06936624 5 P 0 N;0
L 2.5993 -1.05931998 2.60953996 -1.05931998 5 P 8191 ;0
L 2.60953996 -1.05931998 2.60953996 -1.03491998 5 P 8191 ;0
A 2.62971998 -1.03418002 2.60953996 -1.03491004 2.61966791 -1.03559478 5 P 0 N;0
L 2.62971004 -1.03418996 2.62978002 -1.05931998 5 P 8191 ;0
L 2.62978002 -1.05931998 2.66008002 -1.05931998 5 P 8191 ;0
A 2.66003996 -1.07955 2.66008002 -1.05931998 2.65827421 -1.0694314 5 P 0 N;0
L 2.66003002 -1.07953996 2.62978002 -1.07953996 5 P 8191 ;0
A 2.71926004 -1.06796998 2.6962 -1.06796998 2.70773002 -1.0720561 5 P 0 N;0
A 2.71968996 -1.02341998 2.71968996 -1.02341998 2.70775 -1.02341998 5 P 0 N;0
A 2.57053996 -1.13728996 2.54306998 -1.11513002 2.53584449 -1.15219301 5 P 0 N;0
A 2.54891998 -1.15895 2.55001004 -1.14328002 2.54127923 -1.15054557 5 P 0 N;0
L 2.60953996 -1.16041004 2.60953996 -1.07953996 5 P 0 ;0
L 2.62978002 -1.07953996 2.62978002 -1.15463002 5 P 0 ;0
L 2.98495 -1.09393996 2.98495 -1.17625 5 P 0 ;0
A 2.96473996 -1.17626998 2.98493996 -1.17626998 2.97483996 -1.17442303 5 P 0 N;0
L 2.96473002 -1.17625 2.96473002 -1.17226004 5 P 8191 ;0
A 2.94165 -1.1835 2.96471004 -1.17226004 2.93076516 -1.1318935 5 P 0 N;0
L 2.94165 -1.1835 2.90701004 -1.1835 5 P 8191 ;0
A 2.90671004 -1.10841998 2.90703002 -1.18351004 2.9153065 -1.14592904 5 P 0 N;0
A 2.91853002 -1.12288996 2.91853002 -1.16618996 2.92048209 -1.14453996 5 P 0 N;0
L 2.91853002 -1.1662 2.94456004 -1.1662 5 P 8191 ;0
A 2.94456998 -1.16618996 2.94456998 -1.12288996 2.94406004 -1.14453996 5 P 0 N;0
A 2.96473002 -1.09686004 2.94741998 -1.07955 2.94874833 -1.09553169 5 P 0 N;0
L 2.9474 -1.07953996 2.90986998 -1.07953996 5 P 8191 ;0
A 2.90986998 -1.07953996 2.89821004 -1.0852 2.92433445 -1.12417766 5 P 0 N;0
A 2.89111998 -1.07086004 2.8982 -1.0852 2.8969689 -1.07688996 5 P 0 N;0
A 2.91561998 -1.05931998 2.89111998 -1.07085 2.92146033 -1.103525 5 P 0 N;0
L 2.91563002 -1.05931998 2.95031004 -1.05931998 5 P 8191 ;0
A 2.98496004 -1.09393996 2.95031004 -1.05933002 2.9453438 -1.09895197 5 P 0 N;0
A 2.92878996 -1.10535 2.9067 -1.10841998 2.93158484 -1.20646998 5 P 0 N;0
A 2.96471998 -1.10841004 2.92878002 -1.10536004 2.93215738 -1.27883829 5 P 0 N;0
L 2.96473002 -1.10841004 2.96473002 -1.09686004 5 P 8191 ;0
L 2.94456004 -1.12288002 2.91853002 -1.12288002 5 P 8191 ;0
L 3.04731004 -1.06001004 3.04191998 -1.07631998 5 P 8191 ;0
L 3.04191998 -1.07631998 3.03648002 -1.06001004 5 P 8191 ;0
L 3.03648002 -1.06001004 3.03243002 -1.06001004 5 P 8191 ;0
L 3.03243002 -1.06001004 3.02698002 -1.08543996 5 P 8191 ;0
L 3.02698002 -1.08543996 3.03226004 -1.08543996 5 P 8191 ;0
L 3.03226004 -1.08543996 3.03501004 -1.06886998 5 P 8191 ;0
L 3.03501004 -1.06886998 3.04086004 -1.08543996 5 P 8191 ;0
L 3.04086004 -1.08543996 3.04308996 -1.08543996 5 P 8191 ;0
L 3.04308996 -1.08543996 3.04888996 -1.06871004 5 P 8191 ;0
L 3.04888996 -1.06871004 3.05171004 -1.08543996 5 P 8191 ;0
L 3.05171004 -1.08543996 3.05713002 -1.08543996 5 P 8191 ;0
L 3.05713002 -1.08543996 3.05163996 -1.06001004 5 P 8191 ;0
L 3.05163996 -1.06001004 3.04731004 -1.06001004 5 P 8191 ;0
L 3.01066998 -1.06508002 3.00223002 -1.06508002 5 P 8191 ;0
L 3.00223002 -1.06508002 3.00223002 -1.06001004 5 P 8191 ;0
L 3.00223002 -1.06001004 3.02461004 -1.06001004 5 P 8191 ;0
L 3.02461004 -1.06001004 3.02461004 -1.06508002 5 P 8191 ;0
L 3.02461004 -1.06508002 3.01615 -1.06508002 5 P 8191 ;0
L 3.01615 -1.06508002 3.01615 -1.08533996 5 P 8191 ;0
L 3.01615 -1.08533996 3.01066998 -1.08533996 5 P 8191 ;0
L 3.01066998 -1.08533996 3.01066998 -1.06508002 5 P 8191 ;0
L 3.36933297 -0.955 3.36933297 -0.88 4 P 0 ;0,2=27,4=0.000000
L 3.36933297 -0.88 3.39173337 -0.88 4 P 0 ;0,2=27,4=0.000000
L 3.39173337 -0.88 3.3992001 -0.88375157 4 P 0 ;0,2=27,4=0.000000
L 3.3992001 -0.88375157 3.40480059 -0.8924997 4 P 0 ;0,2=27,4=0.000000
L 3.40480059 -0.8924997 3.40666693 -0.9024998 4 P 0 ;0,2=27,4=0.000000
L 3.40666693 -0.9024998 3.40480059 -0.9125 4 P 0 ;0,2=27,4=0.000000
L 3.40480059 -0.9125 3.40013327 -0.92000069 4 P 0 ;0,2=27,4=0.000000
L 3.40013327 -0.92000069 3.39173337 -0.92375217 4 P 0 ;0,2=27,4=0.000000
L 3.39173337 -0.92375217 3.36933297 -0.92375217 4 P 0 ;0,2=27,4=0.000000
L 3.44619931 -0.95749941 3.47980059 -0.88 4 P 0 ;0,2=27,4=0.000000
L 3.51653356 -0.955 3.51653356 -0.88 4 P 0 ;0,2=27,4=0.000000
L 3.51653356 -0.88 3.55946634 -0.955 4 P 0 ;0,2=27,4=0.000000
L 3.55946634 -0.955 3.55946634 -0.88 4 P 0 ;0,2=27,4=0.000000
L 3.68799911 -0.95749941 3.68613287 -0.9562497 4 P 0 ;0,2=27,4=0.000000
L 3.68613287 -0.9562497 3.68613287 -0.9537503 4 P 0 ;0,2=27,4=0.000000
L 3.68613287 -0.9537503 3.68799911 -0.95250059 4 P 0 ;0,2=27,4=0.000000
L 3.68799911 -0.95250059 3.68986703 -0.9537503 4 P 0 ;0,2=27,4=0.000000
L 3.68986703 -0.9537503 3.68986703 -0.9562497 4 P 0 ;0,2=27,4=0.000000
L 3.68986703 -0.9562497 3.68799911 -0.95749941 4 P 0 ;0,2=27,4=0.000000
L 3.68799911 -0.92375217 3.68613287 -0.9225001 4 P 0 ;0,2=27,4=0.000000
L 3.68613287 -0.9225001 3.68613287 -0.92000069 4 P 0 ;0,2=27,4=0.000000
L 3.68613287 -0.92000069 3.68799911 -0.91875089 4 P 0 ;0,2=27,4=0.000000
L 3.68799911 -0.91875089 3.68986703 -0.92000069 4 P 0 ;0,2=27,4=0.000000
L 3.68986703 -0.92000069 3.68986703 -0.9225001 4 P 0 ;0,2=27,4=0.000000
L 3.68986703 -0.9225001 3.68799911 -0.92375217 4 P 0 ;0,2=27,4=0.000000
L 3.81933297 -0.955 3.81933297 -0.88 4 P 0 ;0,2=27,4=0.000000
L 3.81933297 -0.88 3.84266644 -0.88 4 P 0 ;0,2=27,4=0.000000
L 3.84266644 -0.88 3.85013327 -0.88375157 4 P 0 ;0,2=27,4=0.000000
L 3.85013327 -0.88375157 3.85480059 -0.88875049 4 P 0 ;0,2=27,4=0.000000
L 3.85480059 -0.88875049 3.85666693 -0.89875059 4 P 0 ;0,2=27,4=0.000000
L 3.85666693 -0.89875059 3.85480059 -0.90875079 4 P 0 ;0,2=27,4=0.000000
L 3.85480059 -0.90875079 3.8492001 -0.91499941 4 P 0 ;0,2=27,4=0.000000
L 3.8492001 -0.91499941 3.84266644 -0.91875089 4 P 0 ;0,2=27,4=0.000000
L 3.84266644 -0.91875089 3.81933297 -0.91875089 4 P 0 ;0,2=27,4=0.000000
L 3.84266644 -0.91875089 3.85666693 -0.955 4 P 0 ;0,2=27,4=0.000000
L 3.9242001 -0.955 3.9242001 -0.88 4 P 0 ;0,2=27,4=0.000000
L 3.9242001 -0.88 3.88966565 -0.93375 4 P 0 ;0,2=27,4=0.000000
L 3.88966565 -0.93375 3.93633425 -0.93375 4 P 0 ;0,2=27,4=0.000000
L 3.98799911 -0.88 3.98053228 -0.88249951 4 P 0 ;0,2=27,4=0.000000
L 3.98053228 -0.88249951 3.97493346 -0.88875049 4 P 0 ;0,2=27,4=0.000000
L 3.97493346 -0.88875049 3.97119931 -0.89624882 4 P 0 ;0,2=27,4=0.000000
L 3.97119931 -0.89624882 3.9683999 -0.90625128 4 P 0 ;0,2=27,4=0.000000
L 3.9683999 -0.90625128 3.96746673 -0.91750118 4 P 0 ;0,2=27,4=0.000000
L 3.96746673 -0.91750118 3.9683999 -0.92875108 4 P 0 ;0,2=27,4=0.000000
L 3.9683999 -0.92875108 3.97119931 -0.93875128 4 P 0 ;0,2=27,4=0.000000
L 3.97119931 -0.93875128 3.97493346 -0.94625187 4 P 0 ;0,2=27,4=0.000000
L 3.97493346 -0.94625187 3.98053228 -0.95250059 4 P 0 ;0,2=27,4=0.000000
L 3.98053228 -0.95250059 3.98799911 -0.955 4 P 0 ;0,2=27,4=0.000000
L 3.98799911 -0.955 3.99546585 -0.95250059 4 P 0 ;0,2=27,4=0.000000
L 3.99546585 -0.95250059 4.00106644 -0.94625187 4 P 0 ;0,2=27,4=0.000000
L 4.00106644 -0.94625187 4.00480059 -0.93875128 4 P 0 ;0,2=27,4=0.000000
L 4.00480059 -0.93875128 4.0076 -0.92875108 4 P 0 ;0,2=27,4=0.000000
L 4.0076 -0.92875108 4.00853317 -0.91750118 4 P 0 ;0,2=27,4=0.000000
L 4.00853317 -0.91750118 4.0076 -0.90625128 4 P 0 ;0,2=27,4=0.000000
L 4.0076 -0.90625128 4.00480059 -0.89624882 4 P 0 ;0,2=27,4=0.000000
L 4.00480059 -0.89624882 4.00106644 -0.88875049 4 P 0 ;0,2=27,4=0.000000
L 4.00106644 -0.88875049 3.99546585 -0.88249951 4 P 0 ;0,2=27,4=0.000000
L 3.99546585 -0.88249951 3.98799911 -0.88 4 P 0 ;0,2=27,4=0.000000
L 4.06299911 -0.88 4.05553228 -0.88249951 4 P 0 ;0,2=27,4=0.000000
L 4.05553228 -0.88249951 4.04993346 -0.88875049 4 P 0 ;0,2=27,4=0.000000
L 4.04993346 -0.88875049 4.04619931 -0.89624882 4 P 0 ;0,2=27,4=0.000000
L 4.04619931 -0.89624882 4.0433999 -0.90625128 4 P 0 ;0,2=27,4=0.000000
L 4.0433999 -0.90625128 4.04246673 -0.91750118 4 P 0 ;0,2=27,4=0.000000
L 4.04246673 -0.91750118 4.0433999 -0.92875108 4 P 0 ;0,2=27,4=0.000000
L 4.0433999 -0.92875108 4.04619931 -0.93875128 4 P 0 ;0,2=27,4=0.000000
L 4.04619931 -0.93875128 4.04993346 -0.94625187 4 P 0 ;0,2=27,4=0.000000
L 4.04993346 -0.94625187 4.05553228 -0.95250059 4 P 0 ;0,2=27,4=0.000000
L 4.05553228 -0.95250059 4.06299911 -0.955 4 P 0 ;0,2=27,4=0.000000
L 4.06299911 -0.955 4.07046585 -0.95250059 4 P 0 ;0,2=27,4=0.000000
L 4.07046585 -0.95250059 4.07606644 -0.94625187 4 P 0 ;0,2=27,4=0.000000
L 4.07606644 -0.94625187 4.07980059 -0.93875128 4 P 0 ;0,2=27,4=0.000000
L 4.07980059 -0.93875128 4.0826 -0.92875108 4 P 0 ;0,2=27,4=0.000000
L 4.0826 -0.92875108 4.08353317 -0.91750118 4 P 0 ;0,2=27,4=0.000000
L 4.08353317 -0.91750118 4.0826 -0.90625128 4 P 0 ;0,2=27,4=0.000000
L 4.0826 -0.90625128 4.07980059 -0.89624882 4 P 0 ;0,2=27,4=0.000000
L 4.07980059 -0.89624882 4.07606644 -0.88875049 4 P 0 ;0,2=27,4=0.000000
L 4.07606644 -0.88875049 4.07046585 -0.88249951 4 P 0 ;0,2=27,4=0.000000
L 4.07046585 -0.88249951 4.06299911 -0.88 4 P 0 ;0,2=27,4=0.000000
L 4.12026614 -0.92375217 4.1267998 -0.91499941 4 P 0 ;0,2=27,4=0.000000
L 4.1267998 -0.91499941 4.1324003 -0.91000049 4 P 0 ;0,2=27,4=0.000000
L 4.1324003 -0.91000049 4.13986703 -0.90750108 4 P 0 ;0,2=27,4=0.000000
L 4.13986703 -0.90750108 4.14640069 -0.91000049 4 P 0 ;0,2=27,4=0.000000
L 4.14640069 -0.91000049 4.15106644 -0.91499941 4 P 0 ;0,2=27,4=0.000000
L 4.15106644 -0.91499941 4.15480059 -0.9225001 4 P 0 ;0,2=27,4=0.000000
L 4.15480059 -0.9225001 4.15573376 -0.93125059 4 P 0 ;0,2=27,4=0.000000
L 4.15573376 -0.93125059 4.15480059 -0.93875128 4 P 0 ;0,2=27,4=0.000000
L 4.15480059 -0.93875128 4.15106644 -0.94625187 4 P 0 ;0,2=27,4=0.000000
L 4.15106644 -0.94625187 4.14546585 -0.95250059 4 P 0 ;0,2=27,4=0.000000
L 4.14546585 -0.95250059 4.13893396 -0.955 4 P 0 ;0,2=27,4=0.000000
L 4.13893396 -0.955 4.13146713 -0.95250059 4 P 0 ;0,2=27,4=0.000000
L 4.13146713 -0.95250059 4.12493346 -0.94500217 4 P 0 ;0,2=27,4=0.000000
L 4.12493346 -0.94500217 4.12119931 -0.93375 4 P 0 ;0,2=27,4=0.000000
L 4.12119931 -0.93375 4.12026614 -0.92125039 4 P 0 ;0,2=27,4=0.000000
L 4.12026614 -0.92125039 4.12213238 -0.90500157 4 P 0 ;0,2=27,4=0.000000
L 4.12213238 -0.90500157 4.12493346 -0.89624882 4 P 0 ;0,2=27,4=0.000000
L 4.12493346 -0.89624882 4.12959921 -0.88750069 4 P 0 ;0,2=27,4=0.000000
L 4.12959921 -0.88750069 4.13613287 -0.8812498 4 P 0 ;0,2=27,4=0.000000
L 4.13613287 -0.8812498 4.14266644 -0.88 4 P 0 ;0,2=27,4=0.000000
L 4.14266644 -0.88 4.1492001 -0.88249951 4 P 0 ;0,2=27,4=0.000000
L 4.1492001 -0.88249951 4.15386752 -0.88875049 4 P 0 ;0,2=27,4=0.000000
L 4.20086663 -0.93000079 4.22513327 -0.93000079 4 P 0 ;0,2=27,4=0.000000
L 4.29546585 -0.91499941 4.2992001 -0.9112502 4 P 0 ;0,2=27,4=0.000000
L 4.2992001 -0.9112502 4.30199951 -0.90500157 4 P 0 ;0,2=27,4=0.000000
L 4.30199951 -0.90500157 4.30386752 -0.89624882 4 P 0 ;0,2=27,4=0.000000
L 4.30386752 -0.89624882 4.30199951 -0.88875049 4 P 0 ;0,2=27,4=0.000000
L 4.30199951 -0.88875049 4.29826703 -0.88375157 4 P 0 ;0,2=27,4=0.000000
L 4.29826703 -0.88375157 4.29173337 -0.88 4 P 0 ;0,2=27,4=0.000000
L 4.29173337 -0.88 4.26653356 -0.88 4 P 0 ;0,2=27,4=0.000000
L 4.26653356 -0.88 4.26653356 -0.955 4 P 0 ;0,2=27,4=0.000000
L 4.26653356 -0.955 4.29733386 -0.955 4 P 0 ;0,2=27,4=0.000000
L 4.29733386 -0.955 4.30386752 -0.95000108 4 P 0 ;0,2=27,4=0.000000
L 4.30386752 -0.95000108 4.3076 -0.94250039 4 P 0 ;0,2=27,4=0.000000
L 4.3076 -0.94250039 4.30946634 -0.93375 4 P 0 ;0,2=27,4=0.000000
L 4.30946634 -0.93375 4.3076 -0.92500187 4 P 0 ;0,2=27,4=0.000000
L 4.3076 -0.92500187 4.30199951 -0.91750118 4 P 0 ;0,2=27,4=0.000000
L 4.30199951 -0.91750118 4.29546585 -0.91499941 4 P 0 ;0,2=27,4=0.000000
L 4.29546585 -0.91499941 4.26653356 -0.91499941 4 P 0 ;0,2=27,4=0.000000
L 4.36299911 -0.88 4.35553228 -0.88249951 4 P 0 ;0,2=27,4=0.000000
L 4.35553228 -0.88249951 4.34993346 -0.88875049 4 P 0 ;0,2=27,4=0.000000
L 4.34993346 -0.88875049 4.34619931 -0.89624882 4 P 0 ;0,2=27,4=0.000000
L 4.34619931 -0.89624882 4.3433999 -0.90625128 4 P 0 ;0,2=27,4=0.000000
L 4.3433999 -0.90625128 4.34246673 -0.91750118 4 P 0 ;0,2=27,4=0.000000
L 4.34246673 -0.91750118 4.3433999 -0.92875108 4 P 0 ;0,2=27,4=0.000000
L 4.3433999 -0.92875108 4.34619931 -0.93875128 4 P 0 ;0,2=27,4=0.000000
L 4.34619931 -0.93875128 4.34993346 -0.94625187 4 P 0 ;0,2=27,4=0.000000
L 4.34993346 -0.94625187 4.35553228 -0.95250059 4 P 0 ;0,2=27,4=0.000000
L 4.35553228 -0.95250059 4.36299911 -0.955 4 P 0 ;0,2=27,4=0.000000
L 4.36299911 -0.955 4.37046585 -0.95250059 4 P 0 ;0,2=27,4=0.000000
L 4.37046585 -0.95250059 4.37606644 -0.94625187 4 P 0 ;0,2=27,4=0.000000
L 4.37606644 -0.94625187 4.37980059 -0.93875128 4 P 0 ;0,2=27,4=0.000000
L 4.37980059 -0.93875128 4.3826 -0.92875108 4 P 0 ;0,2=27,4=0.000000
L 4.3826 -0.92875108 4.38353317 -0.91750118 4 P 0 ;0,2=27,4=0.000000
L 4.38353317 -0.91750118 4.3826 -0.90625128 4 P 0 ;0,2=27,4=0.000000
L 4.3826 -0.90625128 4.37980059 -0.89624882 4 P 0 ;0,2=27,4=0.000000
L 4.37980059 -0.89624882 4.37606644 -0.88875049 4 P 0 ;0,2=27,4=0.000000
L 4.37606644 -0.88875049 4.37046585 -0.88249951 4 P 0 ;0,2=27,4=0.000000
L 4.37046585 -0.88249951 4.36299911 -0.88 4 P 0 ;0,2=27,4=0.000000
L 4.43799911 -0.88 4.43053228 -0.88249951 4 P 0 ;0,2=27,4=0.000000
L 4.43053228 -0.88249951 4.42493346 -0.88875049 4 P 0 ;0,2=27,4=0.000000
L 4.42493346 -0.88875049 4.42119931 -0.89624882 4 P 0 ;0,2=27,4=0.000000
L 4.42119931 -0.89624882 4.4183999 -0.90625128 4 P 0 ;0,2=27,4=0.000000
L 4.4183999 -0.90625128 4.41746673 -0.91750118 4 P 0 ;0,2=27,4=0.000000
L 4.41746673 -0.91750118 4.4183999 -0.92875108 4 P 0 ;0,2=27,4=0.000000
L 4.4183999 -0.92875108 4.42119931 -0.93875128 4 P 0 ;0,2=27,4=0.000000
L 4.42119931 -0.93875128 4.42493346 -0.94625187 4 P 0 ;0,2=27,4=0.000000
L 4.42493346 -0.94625187 4.43053228 -0.95250059 4 P 0 ;0,2=27,4=0.000000
L 4.43053228 -0.95250059 4.43799911 -0.955 4 P 0 ;0,2=27,4=0.000000
L 4.43799911 -0.955 4.44546585 -0.95250059 4 P 0 ;0,2=27,4=0.000000
L 4.44546585 -0.95250059 4.45106644 -0.94625187 4 P 0 ;0,2=27,4=0.000000
L 4.45106644 -0.94625187 4.45480059 -0.93875128 4 P 0 ;0,2=27,4=0.000000
L 4.45480059 -0.93875128 4.4576 -0.92875108 4 P 0 ;0,2=27,4=0.000000
L 4.4576 -0.92875108 4.45853317 -0.91750118 4 P 0 ;0,2=27,4=0.000000
L 4.45853317 -0.91750118 4.4576 -0.90625128 4 P 0 ;0,2=27,4=0.000000
L 4.4576 -0.90625128 4.45480059 -0.89624882 4 P 0 ;0,2=27,4=0.000000
L 4.45480059 -0.89624882 4.45106644 -0.88875049 4 P 0 ;0,2=27,4=0.000000
L 4.45106644 -0.88875049 4.44546585 -0.88249951 4 P 0 ;0,2=27,4=0.000000
L 4.44546585 -0.88249951 4.43799911 -0.88 4 P 0 ;0,2=27,4=0.000000
L 4.51299911 -0.88 4.50553228 -0.88249951 4 P 0 ;0,2=27,4=0.000000
L 4.50553228 -0.88249951 4.49993346 -0.88875049 4 P 0 ;0,2=27,4=0.000000
L 4.49993346 -0.88875049 4.49619931 -0.89624882 4 P 0 ;0,2=27,4=0.000000
L 4.49619931 -0.89624882 4.4933999 -0.90625128 4 P 0 ;0,2=27,4=0.000000
L 4.4933999 -0.90625128 4.49246673 -0.91750118 4 P 0 ;0,2=27,4=0.000000
L 4.49246673 -0.91750118 4.4933999 -0.92875108 4 P 0 ;0,2=27,4=0.000000
L 4.4933999 -0.92875108 4.49619931 -0.93875128 4 P 0 ;0,2=27,4=0.000000
L 4.49619931 -0.93875128 4.49993346 -0.94625187 4 P 0 ;0,2=27,4=0.000000
L 4.49993346 -0.94625187 4.50553228 -0.95250059 4 P 0 ;0,2=27,4=0.000000
L 4.50553228 -0.95250059 4.51299911 -0.955 4 P 0 ;0,2=27,4=0.000000
L 4.51299911 -0.955 4.52046585 -0.95250059 4 P 0 ;0,2=27,4=0.000000
L 4.52046585 -0.95250059 4.52606644 -0.94625187 4 P 0 ;0,2=27,4=0.000000
L 4.52606644 -0.94625187 4.52980059 -0.93875128 4 P 0 ;0,2=27,4=0.000000
L 4.52980059 -0.93875128 4.5326 -0.92875108 4 P 0 ;0,2=27,4=0.000000
L 4.5326 -0.92875108 4.53353317 -0.91750118 4 P 0 ;0,2=27,4=0.000000
L 4.53353317 -0.91750118 4.5326 -0.90625128 4 P 0 ;0,2=27,4=0.000000
L 4.5326 -0.90625128 4.52980059 -0.89624882 4 P 0 ;0,2=27,4=0.000000
L 4.52980059 -0.89624882 4.52606644 -0.88875049 4 P 0 ;0,2=27,4=0.000000
L 4.52606644 -0.88875049 4.52046585 -0.88249951 4 P 0 ;0,2=27,4=0.000000
L 4.52046585 -0.88249951 4.51299911 -0.88 4 P 0 ;0,2=27,4=0.000000
L 4.58799911 -0.955 4.58799911 -0.88 4 P 0 ;0,2=27,4=0.000000
L 4.58799911 -0.88 4.5767998 -0.89499911 4 P 0 ;0,2=27,4=0.000000
L 4.5767998 -0.955 4.59919843 -0.955 4 P 0 ;0,2=27,4=0.000000
L 4.65086663 -0.93000079 4.67513327 -0.93000079 4 P 0 ;0,2=27,4=0.000000
L 4.73799911 -0.88 4.73053228 -0.88249951 4 P 0 ;0,2=27,4=0.000000
L 4.73053228 -0.88249951 4.72493346 -0.88875049 4 P 0 ;0,2=27,4=0.000000
L 4.72493346 -0.88875049 4.72119931 -0.89624882 4 P 0 ;0,2=27,4=0.000000
L 4.72119931 -0.89624882 4.7183999 -0.90625128 4 P 0 ;0,2=27,4=0.000000
L 4.7183999 -0.90625128 4.71746673 -0.91750118 4 P 0 ;0,2=27,4=0.000000
L 4.71746673 -0.91750118 4.7183999 -0.92875108 4 P 0 ;0,2=27,4=0.000000
L 4.7183999 -0.92875108 4.72119931 -0.93875128 4 P 0 ;0,2=27,4=0.000000
L 4.72119931 -0.93875128 4.72493346 -0.94625187 4 P 0 ;0,2=27,4=0.000000
L 4.72493346 -0.94625187 4.73053228 -0.95250059 4 P 0 ;0,2=27,4=0.000000
L 4.73053228 -0.95250059 4.73799911 -0.955 4 P 0 ;0,2=27,4=0.000000
L 4.73799911 -0.955 4.74546585 -0.95250059 4 P 0 ;0,2=27,4=0.000000
L 4.74546585 -0.95250059 4.75106644 -0.94625187 4 P 0 ;0,2=27,4=0.000000
L 4.75106644 -0.94625187 4.75480059 -0.93875128 4 P 0 ;0,2=27,4=0.000000
L 4.75480059 -0.93875128 4.7576 -0.92875108 4 P 0 ;0,2=27,4=0.000000
L 4.7576 -0.92875108 4.75853317 -0.91750118 4 P 0 ;0,2=27,4=0.000000
L 4.75853317 -0.91750118 4.7576 -0.90625128 4 P 0 ;0,2=27,4=0.000000
L 4.7576 -0.90625128 4.75480059 -0.89624882 4 P 0 ;0,2=27,4=0.000000
L 4.75480059 -0.89624882 4.75106644 -0.88875049 4 P 0 ;0,2=27,4=0.000000
L 4.75106644 -0.88875049 4.74546585 -0.88249951 4 P 0 ;0,2=27,4=0.000000
L 4.74546585 -0.88249951 4.73799911 -0.88 4 P 0 ;0,2=27,4=0.000000
L 4.79526614 -0.8924997 4.80086663 -0.88500128 4 P 0 ;0,2=27,4=0.000000
L 4.80086663 -0.88500128 4.8074003 -0.8812498 4 P 0 ;0,2=27,4=0.000000
L 4.8074003 -0.8812498 4.81486703 -0.88 4 P 0 ;0,2=27,4=0.000000
L 4.81486703 -0.88 4.8242001 -0.88249951 4 P 0 ;0,2=27,4=0.000000
L 4.8242001 -0.88249951 4.83073376 -0.88875049 4 P 0 ;0,2=27,4=0.000000
L 4.83073376 -0.88875049 4.8326 -0.89624882 4 P 0 ;0,2=27,4=0.000000
L 4.8326 -0.89624882 4.83166693 -0.90375187 4 P 0 ;0,2=27,4=0.000000
L 4.83166693 -0.90375187 4.82793268 -0.91000049 4 P 0 ;0,2=27,4=0.000000
L 4.82793268 -0.91000049 4.80926654 -0.9225001 4 P 0 ;0,2=27,4=0.000000
L 4.80926654 -0.9225001 4.80086663 -0.93125059 4 P 0 ;0,2=27,4=0.000000
L 4.80086663 -0.93125059 4.79526614 -0.94375246 4 P 0 ;0,2=27,4=0.000000
L 4.79526614 -0.94375246 4.7933999 -0.955 4 P 0 ;0,2=27,4=0.000000
L 4.7933999 -0.955 4.8326 -0.955 4 P 0 ;0,2=27,4=0.000000
L 3.36746673 -1.205 3.36746673 -1.13 4 P 0 ;0,2=28,4=0.000000
L 3.36746673 -1.13 3.38613287 -1.13 4 P 0 ;0,2=28,4=0.000000
L 3.38613287 -1.13 3.39359961 -1.13375157 4 P 0 ;0,2=28,4=0.000000
L 3.39359961 -1.13375157 3.3992001 -1.13875049 4 P 0 ;0,2=28,4=0.000000
L 3.3992001 -1.13875049 3.40386752 -1.14624882 4 P 0 ;0,2=28,4=0.000000
L 3.40386752 -1.14624882 3.4076 -1.15500157 4 P 0 ;0,2=28,4=0.000000
L 3.4076 -1.15500157 3.40853317 -1.16750118 4 P 0 ;0,2=28,4=0.000000
L 3.40853317 -1.16750118 3.4076 -1.18000079 4 P 0 ;0,2=28,4=0.000000
L 3.4076 -1.18000079 3.40386752 -1.18875128 4 P 0 ;0,2=28,4=0.000000
L 3.40386752 -1.18875128 3.3992001 -1.19625187 4 P 0 ;0,2=28,4=0.000000
L 3.3992001 -1.19625187 3.39359961 -1.20125089 4 P 0 ;0,2=28,4=0.000000
L 3.39359961 -1.20125089 3.38613287 -1.205 4 P 0 ;0,2=28,4=0.000000
L 3.38613287 -1.205 3.36746673 -1.205 4 P 0 ;0,2=28,4=0.000000
L 3.47980059 -1.205 3.47980059 -1.15500157 4 P 0 ;0,2=28,4=0.000000
L 3.47980059 -1.1637497 3.47606644 -1.15875079 4 P 0 ;0,2=28,4=0.000000
L 3.47606644 -1.15875079 3.47046585 -1.15625128 4 P 0 ;0,2=28,4=0.000000
L 3.47046585 -1.15625128 3.46393396 -1.15500157 4 P 0 ;0,2=28,4=0.000000
L 3.46393396 -1.15500157 3.4574003 -1.15750108 4 P 0 ;0,2=28,4=0.000000
L 3.4574003 -1.15750108 3.4517998 -1.1625 4 P 0 ;0,2=28,4=0.000000
L 3.4517998 -1.1625 3.44806555 -1.17000069 4 P 0 ;0,2=28,4=0.000000
L 3.44806555 -1.17000069 3.44619931 -1.18000079 4 P 0 ;0,2=28,4=0.000000
L 3.44619931 -1.18000079 3.44806555 -1.19000098 4 P 0 ;0,2=28,4=0.000000
L 3.44806555 -1.19000098 3.4517998 -1.19750167 4 P 0 ;0,2=28,4=0.000000
L 3.4517998 -1.19750167 3.4574003 -1.20250059 4 P 0 ;0,2=28,4=0.000000
L 3.4574003 -1.20250059 3.46393396 -1.205 4 P 0 ;0,2=28,4=0.000000
L 3.46393396 -1.205 3.47046585 -1.2037503 4 P 0 ;0,2=28,4=0.000000
L 3.47046585 -1.2037503 3.47606644 -1.20000108 4 P 0 ;0,2=28,4=0.000000
L 3.47606644 -1.20000108 3.47980059 -1.19500217 4 P 0 ;0,2=28,4=0.000000
L 3.53799911 -1.13 3.53799911 -1.205 4 P 0 ;0,2=28,4=0.000000
L 3.52493346 -1.15500157 3.55106644 -1.15500157 4 P 0 ;0,2=28,4=0.000000
L 3.59900039 -1.17125039 3.62886752 -1.17125039 4 P 0 ;0,2=28,4=0.000000
L 3.62886752 -1.17125039 3.62606644 -1.1625 4 P 0 ;0,2=28,4=0.000000
L 3.62606644 -1.1625 3.62140069 -1.15750108 4 P 0 ;0,2=28,4=0.000000
L 3.62140069 -1.15750108 3.61486703 -1.15500157 4 P 0 ;0,2=28,4=0.000000
L 3.61486703 -1.15500157 3.60833346 -1.15625128 4 P 0 ;0,2=28,4=0.000000
L 3.60833346 -1.15625128 3.60273287 -1.16000049 4 P 0 ;0,2=28,4=0.000000
L 3.60273287 -1.16000049 3.59900039 -1.16875089 4 P 0 ;0,2=28,4=0.000000
L 3.59900039 -1.16875089 3.59713238 -1.17625157 4 P 0 ;0,2=28,4=0.000000
L 3.59713238 -1.17625157 3.59713238 -1.18375 4 P 0 ;0,2=28,4=0.000000
L 3.59713238 -1.18375 3.59900039 -1.19125069 4 P 0 ;0,2=28,4=0.000000
L 3.59900039 -1.19125069 3.60366604 -1.19875138 4 P 0 ;0,2=28,4=0.000000
L 3.60366604 -1.19875138 3.60926654 -1.2037503 4 P 0 ;0,2=28,4=0.000000
L 3.60926654 -1.2037503 3.6158002 -1.205 4 P 0 ;0,2=28,4=0.000000
L 3.6158002 -1.205 3.62233386 -1.20250059 4 P 0 ;0,2=28,4=0.000000
L 3.62233386 -1.20250059 3.62886752 -1.19500217 4 P 0 ;0,2=28,4=0.000000
L 3.68799911 -1.20749941 3.68613287 -1.2062497 4 P 0 ;0,2=28,4=0.000000
L 3.68613287 -1.2062497 3.68613287 -1.2037503 4 P 0 ;0,2=28,4=0.000000
L 3.68613287 -1.2037503 3.68799911 -1.20250059 4 P 0 ;0,2=28,4=0.000000
L 3.68799911 -1.20250059 3.68986703 -1.2037503 4 P 0 ;0,2=28,4=0.000000
L 3.68986703 -1.2037503 3.68986703 -1.2062497 4 P 0 ;0,2=28,4=0.000000
L 3.68986703 -1.2062497 3.68799911 -1.20749941 4 P 0 ;0,2=28,4=0.000000
L 3.68799911 -1.17375217 3.68613287 -1.1725001 4 P 0 ;0,2=28,4=0.000000
L 3.68613287 -1.1725001 3.68613287 -1.17000069 4 P 0 ;0,2=28,4=0.000000
L 3.68613287 -1.17000069 3.68799911 -1.16875089 4 P 0 ;0,2=28,4=0.000000
L 3.68799911 -1.16875089 3.68986703 -1.17000069 4 P 0 ;0,2=28,4=0.000000
L 3.68986703 -1.17000069 3.68986703 -1.1725001 4 P 0 ;0,2=28,4=0.000000
L 3.68986703 -1.1725001 3.68799911 -1.17375217 4 P 0 ;0,2=28,4=0.000000
L 3.82026614 -1.1424997 3.82586663 -1.13500128 4 P 0 ;0,2=28,4=0.000000
L 3.82586663 -1.13500128 3.8324003 -1.1312498 4 P 0 ;0,2=28,4=0.000000
L 3.8324003 -1.1312498 3.83986703 -1.13 4 P 0 ;0,2=28,4=0.000000
L 3.83986703 -1.13 3.8492001 -1.13249951 4 P 0 ;0,2=28,4=0.000000
L 3.8492001 -1.13249951 3.85573376 -1.13875049 4 P 0 ;0,2=28,4=0.000000
L 3.85573376 -1.13875049 3.8576 -1.14624882 4 P 0 ;0,2=28,4=0.000000
L 3.8576 -1.14624882 3.85666693 -1.15375187 4 P 0 ;0,2=28,4=0.000000
L 3.85666693 -1.15375187 3.85293268 -1.16000049 4 P 0 ;0,2=28,4=0.000000
L 3.85293268 -1.16000049 3.83426654 -1.1725001 4 P 0 ;0,2=28,4=0.000000
L 3.83426654 -1.1725001 3.82586663 -1.18125059 4 P 0 ;0,2=28,4=0.000000
L 3.82586663 -1.18125059 3.82026614 -1.19375246 4 P 0 ;0,2=28,4=0.000000
L 3.82026614 -1.19375246 3.8183999 -1.205 4 P 0 ;0,2=28,4=0.000000
L 3.8183999 -1.205 3.8576 -1.205 4 P 0 ;0,2=28,4=0.000000
L 3.91299911 -1.13 3.90553228 -1.13249951 4 P 0 ;0,2=28,4=0.000000
L 3.90553228 -1.13249951 3.89993346 -1.13875049 4 P 0 ;0,2=28,4=0.000000
L 3.89993346 -1.13875049 3.89619931 -1.14624882 4 P 0 ;0,2=28,4=0.000000
L 3.89619931 -1.14624882 3.8933999 -1.15625128 4 P 0 ;0,2=28,4=0.000000
L 3.8933999 -1.15625128 3.89246673 -1.16750118 4 P 0 ;0,2=28,4=0.000000
L 3.89246673 -1.16750118 3.8933999 -1.17875108 4 P 0 ;0,2=28,4=0.000000
L 3.8933999 -1.17875108 3.89619931 -1.18875128 4 P 0 ;0,2=28,4=0.000000
L 3.89619931 -1.18875128 3.89993346 -1.19625187 4 P 0 ;0,2=28,4=0.000000
L 3.89993346 -1.19625187 3.90553228 -1.20250059 4 P 0 ;0,2=28,4=0.000000
L 3.90553228 -1.20250059 3.91299911 -1.205 4 P 0 ;0,2=28,4=0.000000
L 3.91299911 -1.205 3.92046585 -1.20250059 4 P 0 ;0,2=28,4=0.000000
L 3.92046585 -1.20250059 3.92606644 -1.19625187 4 P 0 ;0,2=28,4=0.000000
L 3.92606644 -1.19625187 3.92980059 -1.18875128 4 P 0 ;0,2=28,4=0.000000
L 3.92980059 -1.18875128 3.9326 -1.17875108 4 P 0 ;0,2=28,4=0.000000
L 3.9326 -1.17875108 3.93353317 -1.16750118 4 P 0 ;0,2=28,4=0.000000
L 3.93353317 -1.16750118 3.9326 -1.15625128 4 P 0 ;0,2=28,4=0.000000
L 3.9326 -1.15625128 3.92980059 -1.14624882 4 P 0 ;0,2=28,4=0.000000
L 3.92980059 -1.14624882 3.92606644 -1.13875049 4 P 0 ;0,2=28,4=0.000000
L 3.92606644 -1.13875049 3.92046585 -1.13249951 4 P 0 ;0,2=28,4=0.000000
L 3.92046585 -1.13249951 3.91299911 -1.13 4 P 0 ;0,2=28,4=0.000000
L 3.97026614 -1.1424997 3.97586663 -1.13500128 4 P 0 ;0,2=28,4=0.000000
L 3.97586663 -1.13500128 3.9824003 -1.1312498 4 P 0 ;0,2=28,4=0.000000
L 3.9824003 -1.1312498 3.98986703 -1.13 4 P 0 ;0,2=28,4=0.000000
L 3.98986703 -1.13 3.9992001 -1.13249951 4 P 0 ;0,2=28,4=0.000000
L 3.9992001 -1.13249951 4.00573376 -1.13875049 4 P 0 ;0,2=28,4=0.000000
L 4.00573376 -1.13875049 4.0076 -1.14624882 4 P 0 ;0,2=28,4=0.000000
L 4.0076 -1.14624882 4.00666693 -1.15375187 4 P 0 ;0,2=28,4=0.000000
L 4.00666693 -1.15375187 4.00293268 -1.16000049 4 P 0 ;0,2=28,4=0.000000
L 4.00293268 -1.16000049 3.98426654 -1.1725001 4 P 0 ;0,2=28,4=0.000000
L 3.98426654 -1.1725001 3.97586663 -1.18125059 4 P 0 ;0,2=28,4=0.000000
L 3.97586663 -1.18125059 3.97026614 -1.19375246 4 P 0 ;0,2=28,4=0.000000
L 3.97026614 -1.19375246 3.9683999 -1.205 4 P 0 ;0,2=28,4=0.000000
L 3.9683999 -1.205 4.0076 -1.205 4 P 0 ;0,2=28,4=0.000000
L 4.04526614 -1.1424997 4.05086663 -1.13500128 4 P 0 ;0,2=28,4=0.000000
L 4.05086663 -1.13500128 4.0574003 -1.1312498 4 P 0 ;0,2=28,4=0.000000
L 4.0574003 -1.1312498 4.06486703 -1.13 4 P 0 ;0,2=28,4=0.000000
L 4.06486703 -1.13 4.0742001 -1.13249951 4 P 0 ;0,2=28,4=0.000000
L 4.0742001 -1.13249951 4.08073376 -1.13875049 4 P 0 ;0,2=28,4=0.000000
L 4.08073376 -1.13875049 4.0826 -1.14624882 4 P 0 ;0,2=28,4=0.000000
L 4.0826 -1.14624882 4.08166693 -1.15375187 4 P 0 ;0,2=28,4=0.000000
L 4.08166693 -1.15375187 4.07793268 -1.16000049 4 P 0 ;0,2=28,4=0.000000
L 4.07793268 -1.16000049 4.05926654 -1.1725001 4 P 0 ;0,2=28,4=0.000000
L 4.05926654 -1.1725001 4.05086663 -1.18125059 4 P 0 ;0,2=28,4=0.000000
L 4.05086663 -1.18125059 4.04526614 -1.19375246 4 P 0 ;0,2=28,4=0.000000
L 4.04526614 -1.19375246 4.0433999 -1.205 4 P 0 ;0,2=28,4=0.000000
L 4.0433999 -1.205 4.0826 -1.205 4 P 0 ;0,2=28,4=0.000000
L 4.12586663 -1.18000079 4.15013327 -1.18000079 4 P 0 ;0,2=28,4=0.000000
L 4.21299911 -1.13 4.20553228 -1.13249951 4 P 0 ;0,2=28,4=0.000000
L 4.20553228 -1.13249951 4.19993346 -1.13875049 4 P 0 ;0,2=28,4=0.000000
L 4.19993346 -1.13875049 4.19619931 -1.14624882 4 P 0 ;0,2=28,4=0.000000
L 4.19619931 -1.14624882 4.1933999 -1.15625128 4 P 0 ;0,2=28,4=0.000000
L 4.1933999 -1.15625128 4.19246673 -1.16750118 4 P 0 ;0,2=28,4=0.000000
L 4.19246673 -1.16750118 4.1933999 -1.17875108 4 P 0 ;0,2=28,4=0.000000
L 4.1933999 -1.17875108 4.19619931 -1.18875128 4 P 0 ;0,2=28,4=0.000000
L 4.19619931 -1.18875128 4.19993346 -1.19625187 4 P 0 ;0,2=28,4=0.000000
L 4.19993346 -1.19625187 4.20553228 -1.20250059 4 P 0 ;0,2=28,4=0.000000
L 4.20553228 -1.20250059 4.21299911 -1.205 4 P 0 ;0,2=28,4=0.000000
L 4.21299911 -1.205 4.22046585 -1.20250059 4 P 0 ;0,2=28,4=0.000000
L 4.22046585 -1.20250059 4.22606644 -1.19625187 4 P 0 ;0,2=28,4=0.000000
L 4.22606644 -1.19625187 4.22980059 -1.18875128 4 P 0 ;0,2=28,4=0.000000
L 4.22980059 -1.18875128 4.2326 -1.17875108 4 P 0 ;0,2=28,4=0.000000
L 4.2326 -1.17875108 4.23353317 -1.16750118 4 P 0 ;0,2=28,4=0.000000
L 4.23353317 -1.16750118 4.2326 -1.15625128 4 P 0 ;0,2=28,4=0.000000
L 4.2326 -1.15625128 4.22980059 -1.14624882 4 P 0 ;0,2=28,4=0.000000
L 4.22980059 -1.14624882 4.22606644 -1.13875049 4 P 0 ;0,2=28,4=0.000000
L 4.22606644 -1.13875049 4.22046585 -1.13249951 4 P 0 ;0,2=28,4=0.000000
L 4.22046585 -1.13249951 4.21299911 -1.13 4 P 0 ;0,2=28,4=0.000000
L 4.27026614 -1.1424997 4.27586663 -1.13500128 4 P 0 ;0,2=28,4=0.000000
L 4.27586663 -1.13500128 4.2824003 -1.1312498 4 P 0 ;0,2=28,4=0.000000
L 4.2824003 -1.1312498 4.28986703 -1.13 4 P 0 ;0,2=28,4=0.000000
L 4.28986703 -1.13 4.2992001 -1.13249951 4 P 0 ;0,2=28,4=0.000000
L 4.2992001 -1.13249951 4.30573376 -1.13875049 4 P 0 ;0,2=28,4=0.000000
L 4.30573376 -1.13875049 4.3076 -1.14624882 4 P 0 ;0,2=28,4=0.000000
L 4.3076 -1.14624882 4.30666693 -1.15375187 4 P 0 ;0,2=28,4=0.000000
L 4.30666693 -1.15375187 4.30293268 -1.16000049 4 P 0 ;0,2=28,4=0.000000
L 4.30293268 -1.16000049 4.28426654 -1.1725001 4 P 0 ;0,2=28,4=0.000000
L 4.28426654 -1.1725001 4.27586663 -1.18125059 4 P 0 ;0,2=28,4=0.000000
L 4.27586663 -1.18125059 4.27026614 -1.19375246 4 P 0 ;0,2=28,4=0.000000
L 4.27026614 -1.19375246 4.2683999 -1.205 4 P 0 ;0,2=28,4=0.000000
L 4.2683999 -1.205 4.3076 -1.205 4 P 0 ;0,2=28,4=0.000000
L 4.35086663 -1.18000079 4.37513327 -1.18000079 4 P 0 ;0,2=28,4=0.000000
L 4.42026614 -1.1424997 4.42586663 -1.13500128 4 P 0 ;0,2=28,4=0.000000
L 4.42586663 -1.13500128 4.4324003 -1.1312498 4 P 0 ;0,2=28,4=0.000000
L 4.4324003 -1.1312498 4.43986703 -1.13 4 P 0 ;0,2=28,4=0.000000
L 4.43986703 -1.13 4.4492001 -1.13249951 4 P 0 ;0,2=28,4=0.000000
L 4.4492001 -1.13249951 4.45573376 -1.13875049 4 P 0 ;0,2=28,4=0.000000
L 4.45573376 -1.13875049 4.4576 -1.14624882 4 P 0 ;0,2=28,4=0.000000
L 4.4576 -1.14624882 4.45666693 -1.15375187 4 P 0 ;0,2=28,4=0.000000
L 4.45666693 -1.15375187 4.45293268 -1.16000049 4 P 0 ;0,2=28,4=0.000000
L 4.45293268 -1.16000049 4.43426654 -1.1725001 4 P 0 ;0,2=28,4=0.000000
L 4.43426654 -1.1725001 4.42586663 -1.18125059 4 P 0 ;0,2=28,4=0.000000
L 4.42586663 -1.18125059 4.42026614 -1.19375246 4 P 0 ;0,2=28,4=0.000000
L 4.42026614 -1.19375246 4.4183999 -1.205 4 P 0 ;0,2=28,4=0.000000
L 4.4183999 -1.205 4.4576 -1.205 4 P 0 ;0,2=28,4=0.000000
L 4.49246673 -1.19375246 4.49806555 -1.20000108 4 P 0 ;0,2=28,4=0.000000
L 4.49806555 -1.20000108 4.50459921 -1.2037503 4 P 0 ;0,2=28,4=0.000000
L 4.50459921 -1.2037503 4.51299911 -1.205 4 P 0 ;0,2=28,4=0.000000
L 4.51299911 -1.205 4.52140069 -1.20250059 4 P 0 ;0,2=28,4=0.000000
L 4.52140069 -1.20250059 4.52793268 -1.19750167 4 P 0 ;0,2=28,4=0.000000
L 4.52793268 -1.19750167 4.5326 -1.18875128 4 P 0 ;0,2=28,4=0.000000
L 4.5326 -1.18875128 4.53353317 -1.17875108 4 P 0 ;0,2=28,4=0.000000
L 4.53353317 -1.17875108 4.53166693 -1.16875089 4 P 0 ;0,2=28,4=0.000000
L 4.53166693 -1.16875089 4.52699951 -1.1625 4 P 0 ;0,2=28,4=0.000000
L 4.52699951 -1.1625 4.52046585 -1.15750108 4 P 0 ;0,2=28,4=0.000000
L 4.52046585 -1.15750108 4.51393396 -1.15625128 4 P 0 ;0,2=28,4=0.000000
L 4.51393396 -1.15625128 4.5074003 -1.15750108 4 P 0 ;0,2=28,4=0.000000
L 4.5074003 -1.15750108 4.49900039 -1.1625 4 P 0 ;0,2=28,4=0.000000
L 4.49900039 -1.1625 4.5017998 -1.13 4 P 0 ;0,2=28,4=0.000000
L 4.5017998 -1.13 4.52699951 -1.13 4 P 0 ;0,2=28,4=0.000000
L 3.29433297 -1.255 3.29433297 -1.33 4 P 0 ;0,2=29,4=0.000000
L 3.29433297 -1.33 3.33166693 -1.33 4 P 0 ;0,2=29,4=0.000000
L 3.40480059 -1.33 3.40480059 -1.28000157 4 P 0 ;0,2=29,4=0.000000
L 3.40480059 -1.2887497 3.40106644 -1.28375079 4 P 0 ;0,2=29,4=0.000000
L 3.40106644 -1.28375079 3.39546585 -1.28125128 4 P 0 ;0,2=29,4=0.000000
L 3.39546585 -1.28125128 3.38893396 -1.28000157 4 P 0 ;0,2=29,4=0.000000
L 3.38893396 -1.28000157 3.3824003 -1.28250108 4 P 0 ;0,2=29,4=0.000000
L 3.3824003 -1.28250108 3.3767998 -1.2875 4 P 0 ;0,2=29,4=0.000000
L 3.3767998 -1.2875 3.37306555 -1.29500069 4 P 0 ;0,2=29,4=0.000000
L 3.37306555 -1.29500069 3.37119931 -1.30500079 4 P 0 ;0,2=29,4=0.000000
L 3.37119931 -1.30500079 3.37306555 -1.31500098 4 P 0 ;0,2=29,4=0.000000
L 3.37306555 -1.31500098 3.3767998 -1.32250167 4 P 0 ;0,2=29,4=0.000000
L 3.3767998 -1.32250167 3.3824003 -1.32750059 4 P 0 ;0,2=29,4=0.000000
L 3.3824003 -1.32750059 3.38893396 -1.33 4 P 0 ;0,2=29,4=0.000000
L 3.38893396 -1.33 3.39546585 -1.3287503 4 P 0 ;0,2=29,4=0.000000
L 3.39546585 -1.3287503 3.40106644 -1.32500108 4 P 0 ;0,2=29,4=0.000000
L 3.40106644 -1.32500108 3.40480059 -1.32000217 4 P 0 ;0,2=29,4=0.000000
L 3.4433999 -1.3524997 3.44900039 -1.35499921 4 P 0 ;0,2=29,4=0.000000
L 3.44900039 -1.35499921 3.45646713 -1.3524997 4 P 0 ;0,2=29,4=0.000000
L 3.45646713 -1.3524997 3.46113287 -1.34750079 4 P 0 ;0,2=29,4=0.000000
L 3.46113287 -1.34750079 3.46486703 -1.3412498 4 P 0 ;0,2=29,4=0.000000
L 3.46486703 -1.3412498 3.47046585 -1.32125187 4 P 0 ;0,2=29,4=0.000000
L 3.47046585 -1.32125187 3.4826 -1.28000157 4 P 0 ;0,2=29,4=0.000000
L 3.45273287 -1.28000157 3.47046585 -1.32125187 4 P 0 ;0,2=29,4=0.000000
L 3.52400039 -1.29625039 3.55386752 -1.29625039 4 P 0 ;0,2=29,4=0.000000
L 3.55386752 -1.29625039 3.55106644 -1.2875 4 P 0 ;0,2=29,4=0.000000
L 3.55106644 -1.2875 3.54640069 -1.28250108 4 P 0 ;0,2=29,4=0.000000
L 3.54640069 -1.28250108 3.53986703 -1.28000157 4 P 0 ;0,2=29,4=0.000000
L 3.53986703 -1.28000157 3.53333346 -1.28125128 4 P 0 ;0,2=29,4=0.000000
L 3.53333346 -1.28125128 3.52773287 -1.28500049 4 P 0 ;0,2=29,4=0.000000
L 3.52773287 -1.28500049 3.52400039 -1.29375089 4 P 0 ;0,2=29,4=0.000000
L 3.52400039 -1.29375089 3.52213238 -1.30125157 4 P 0 ;0,2=29,4=0.000000
L 3.52213238 -1.30125157 3.52213238 -1.30875 4 P 0 ;0,2=29,4=0.000000
L 3.52213238 -1.30875 3.52400039 -1.31625069 4 P 0 ;0,2=29,4=0.000000
L 3.52400039 -1.31625069 3.52866604 -1.32375138 4 P 0 ;0,2=29,4=0.000000
L 3.52866604 -1.32375138 3.53426654 -1.3287503 4 P 0 ;0,2=29,4=0.000000
L 3.53426654 -1.3287503 3.5408002 -1.33 4 P 0 ;0,2=29,4=0.000000
L 3.5408002 -1.33 3.54733386 -1.32750059 4 P 0 ;0,2=29,4=0.000000
L 3.54733386 -1.32750059 3.55386752 -1.32000217 4 P 0 ;0,2=29,4=0.000000
L 3.59993346 -1.33 3.59993346 -1.28000157 4 P 0 ;0,2=29,4=0.000000
L 3.59993346 -1.28999941 3.60459921 -1.28500049 4 P 0 ;0,2=29,4=0.000000
L 3.60459921 -1.28500049 3.60926654 -1.28125128 4 P 0 ;0,2=29,4=0.000000
L 3.60926654 -1.28125128 3.6158002 -1.28000157 4 P 0 ;0,2=29,4=0.000000
L 3.6158002 -1.28000157 3.62046585 -1.28125128 4 P 0 ;0,2=29,4=0.000000
L 3.62046585 -1.28125128 3.62606644 -1.28500049 4 P 0 ;0,2=29,4=0.000000
L 3.68799911 -1.33249941 3.68613287 -1.3312497 4 P 0 ;0,2=29,4=0.000000
L 3.68613287 -1.3312497 3.68613287 -1.3287503 4 P 0 ;0,2=29,4=0.000000
L 3.68613287 -1.3287503 3.68799911 -1.32750059 4 P 0 ;0,2=29,4=0.000000
L 3.68799911 -1.32750059 3.68986703 -1.3287503 4 P 0 ;0,2=29,4=0.000000
L 3.68986703 -1.3287503 3.68986703 -1.3312497 4 P 0 ;0,2=29,4=0.000000
L 3.68986703 -1.3312497 3.68799911 -1.33249941 4 P 0 ;0,2=29,4=0.000000
L 3.68799911 -1.29875217 3.68613287 -1.2975001 4 P 0 ;0,2=29,4=0.000000
L 3.68613287 -1.2975001 3.68613287 -1.29500069 4 P 0 ;0,2=29,4=0.000000
L 3.68613287 -1.29500069 3.68799911 -1.29375089 4 P 0 ;0,2=29,4=0.000000
L 3.68799911 -1.29375089 3.68986703 -1.29500069 4 P 0 ;0,2=29,4=0.000000
L 3.68986703 -1.29500069 3.68986703 -1.2975001 4 P 0 ;0,2=29,4=0.000000
L 3.68986703 -1.2975001 3.68799911 -1.29875217 4 P 0 ;0,2=29,4=0.000000
L 3.36933297 -1.08 3.36933297 -1.005 4 P 0 ;0,2=30,4=0.000000
L 3.36933297 -1.005 3.39266644 -1.005 4 P 0 ;0,2=30,4=0.000000
L 3.39266644 -1.005 3.40013327 -1.00875157 4 P 0 ;0,2=30,4=0.000000
L 3.40013327 -1.00875157 3.40480059 -1.01375049 4 P 0 ;0,2=30,4=0.000000
L 3.40480059 -1.01375049 3.40666693 -1.02375059 4 P 0 ;0,2=30,4=0.000000
L 3.40666693 -1.02375059 3.40480059 -1.03375079 4 P 0 ;0,2=30,4=0.000000
L 3.40480059 -1.03375079 3.3992001 -1.03999941 4 P 0 ;0,2=30,4=0.000000
L 3.3992001 -1.03999941 3.39266644 -1.04375089 4 P 0 ;0,2=30,4=0.000000
L 3.39266644 -1.04375089 3.36933297 -1.04375089 4 P 0 ;0,2=30,4=0.000000
L 3.39266644 -1.04375089 3.40666693 -1.08 4 P 0 ;0,2=30,4=0.000000
L 3.44900039 -1.04625039 3.47886752 -1.04625039 4 P 0 ;0,2=30,4=0.000000
L 3.47886752 -1.04625039 3.47606644 -1.0375 4 P 0 ;0,2=30,4=0.000000
L 3.47606644 -1.0375 3.47140069 -1.03250108 4 P 0 ;0,2=30,4=0.000000
L 3.47140069 -1.03250108 3.46486703 -1.03000157 4 P 0 ;0,2=30,4=0.000000
L 3.46486703 -1.03000157 3.45833346 -1.03125128 4 P 0 ;0,2=30,4=0.000000
L 3.45833346 -1.03125128 3.45273287 -1.03500049 4 P 0 ;0,2=30,4=0.000000
L 3.45273287 -1.03500049 3.44900039 -1.04375089 4 P 0 ;0,2=30,4=0.000000
L 3.44900039 -1.04375089 3.44713238 -1.05125157 4 P 0 ;0,2=30,4=0.000000
L 3.44713238 -1.05125157 3.44713238 -1.05875 4 P 0 ;0,2=30,4=0.000000
L 3.44713238 -1.05875 3.44900039 -1.06625069 4 P 0 ;0,2=30,4=0.000000
L 3.44900039 -1.06625069 3.45366604 -1.07375138 4 P 0 ;0,2=30,4=0.000000
L 3.45366604 -1.07375138 3.45926654 -1.0787503 4 P 0 ;0,2=30,4=0.000000
L 3.45926654 -1.0787503 3.4658002 -1.08 4 P 0 ;0,2=30,4=0.000000
L 3.4658002 -1.08 3.47233386 -1.07750059 4 P 0 ;0,2=30,4=0.000000
L 3.47233386 -1.07750059 3.47886752 -1.07000217 4 P 0 ;0,2=30,4=0.000000
L 3.52119931 -1.03000157 3.53799911 -1.08 4 P 0 ;0,2=30,4=0.000000
L 3.53799911 -1.08 3.55480059 -1.03000157 4 P 0 ;0,2=30,4=0.000000
L 3.68799911 -1.08249941 3.68613287 -1.0812497 4 P 0 ;0,2=30,4=0.000000
L 3.68613287 -1.0812497 3.68613287 -1.0787503 4 P 0 ;0,2=30,4=0.000000
L 3.68613287 -1.0787503 3.68799911 -1.07750059 4 P 0 ;0,2=30,4=0.000000
L 3.68799911 -1.07750059 3.68986703 -1.0787503 4 P 0 ;0,2=30,4=0.000000
L 3.68986703 -1.0787503 3.68986703 -1.0812497 4 P 0 ;0,2=30,4=0.000000
L 3.68986703 -1.0812497 3.68799911 -1.08249941 4 P 0 ;0,2=30,4=0.000000
L 3.68799911 -1.04875217 3.68613287 -1.0475001 4 P 0 ;0,2=30,4=0.000000
L 3.68613287 -1.0475001 3.68613287 -1.04500069 4 P 0 ;0,2=30,4=0.000000
L 3.68613287 -1.04500069 3.68799911 -1.04375089 4 P 0 ;0,2=30,4=0.000000
L 3.68799911 -1.04375089 3.68986703 -1.04500069 4 P 0 ;0,2=30,4=0.000000
L 3.68986703 -1.04500069 3.68986703 -1.0475001 4 P 0 ;0,2=30,4=0.000000
L 3.68986703 -1.0475001 3.68799911 -1.04875217 4 P 0 ;0,2=30,4=0.000000
L 3.83799911 -1.005 3.83053228 -1.00749951 4 P 0 ;0,2=30,4=0.000000
L 3.83053228 -1.00749951 3.82493346 -1.01375049 4 P 0 ;0,2=30,4=0.000000
L 3.82493346 -1.01375049 3.82119931 -1.02124882 4 P 0 ;0,2=30,4=0.000000
L 3.82119931 -1.02124882 3.8183999 -1.03125128 4 P 0 ;0,2=30,4=0.000000
L 3.8183999 -1.03125128 3.81746673 -1.04250118 4 P 0 ;0,2=30,4=0.000000
L 3.81746673 -1.04250118 3.8183999 -1.05375108 4 P 0 ;0,2=30,4=0.000000
L 3.8183999 -1.05375108 3.82119931 -1.06375128 4 P 0 ;0,2=30,4=0.000000
L 3.82119931 -1.06375128 3.82493346 -1.07125187 4 P 0 ;0,2=30,4=0.000000
L 3.82493346 -1.07125187 3.83053228 -1.07750059 4 P 0 ;0,2=30,4=0.000000
L 3.83053228 -1.07750059 3.83799911 -1.08 4 P 0 ;0,2=30,4=0.000000
L 3.83799911 -1.08 3.84546585 -1.07750059 4 P 0 ;0,2=30,4=0.000000
L 3.84546585 -1.07750059 3.85106644 -1.07125187 4 P 0 ;0,2=30,4=0.000000
L 3.85106644 -1.07125187 3.85480059 -1.06375128 4 P 0 ;0,2=30,4=0.000000
L 3.85480059 -1.06375128 3.8576 -1.05375108 4 P 0 ;0,2=30,4=0.000000
L 3.8576 -1.05375108 3.85853317 -1.04250118 4 P 0 ;0,2=30,4=0.000000
L 3.85853317 -1.04250118 3.8576 -1.03125128 4 P 0 ;0,2=30,4=0.000000
L 3.8576 -1.03125128 3.85480059 -1.02124882 4 P 0 ;0,2=30,4=0.000000
L 3.85480059 -1.02124882 3.85106644 -1.01375049 4 P 0 ;0,2=30,4=0.000000
L 3.85106644 -1.01375049 3.84546585 -1.00749951 4 P 0 ;0,2=30,4=0.000000
L 3.84546585 -1.00749951 3.83799911 -1.005 4 P 0 ;0,2=30,4=0.000000
L 3.91299911 -1.08 3.91299911 -1.005 4 P 0 ;0,2=30,4=0.000000
L 3.91299911 -1.005 3.9017998 -1.01999911 4 P 0 ;0,2=30,4=0.000000
L 3.9017998 -1.08 3.92419843 -1.08 4 P 0 ;0,2=30,4=0.000000

### steps/pcb/layers/l09_gnd4/features
#
#Num Features
#
F 2394

#
#Units
#
U INCH

#
#Feature symbol names
#
$0 r5
$1 r6
$2 r10
$3 r26
$4 r28
$5 r30
$6 r32
$7 r39
$8 r82
$9 r99
$10 r102
$11 r125
$12 r143
$13 r150
$14 024x051ob071x075p_l
$15 024x051ob071x075p_r
$16 024x063ob035x075p
$17 ths102x92.01x45x4x14 I
$18 ths105x95x45x4x14 I
$19 ths191.99x182x45x4x27 I
$20 ths42.01x31.99x45x4x10 I
$21 ths58.99x49x45x4x10 I
$22 ths89x79x45x4x11.99 I

#
#Feature attribute names
#
@0 .nomenclature
@1 .geometry
@2 .sip

#
#Feature attribute text strings
#
&0 V010C020P_TP030B
&1 V008C018P-ANTI28-NSM
&2 V010C020P
&3 TPV010CT020B030
&4 V008C018P_ANTI026_TP030B
&5 V008C018P_NATI28_TP030B_NSMT
&6 016C024P
&7 V008C018P_TP030B
&8 V008C018P
&9 V008C018P_ANTI28
&10 059C086P
&11 V008C018P_ANTI026_NSM
&12 076S104P
&13 076C104P
&14 079C100P
&15 V010C020P_SM014-NTH
&16 024X063OB035X075P
&17 166CT244CB198P
&18 024X051OB071X075P_R
&19 024X051OB071X075P_L
&20 033C057P
&21 063C090P
&22 MTH100C090N
&23 MTH125C115N
&24 MTH118C108N

#
#Layer features
#
S P 0;0,2=1
OB -24.76435 -17.98935 I
OS -24.76435 16.38535
OS 21.05735 16.38535
OS 21.05735 -17.98935
OS -24.76435 -17.98935
OE
OB -0.00110019685 0.21653976378 H
OC 0.039369783465 0.176069783465 0.039369783465 0.21653976378 N
OS 0.551194094488 0.176069980315
OC 0.59165 0.216525885827 0.551180019685 0.21653996063 N
OS 0.59165019685 0.46260019685
OC 0.629906200787 0.500870177165 0.629920177165 0.46260019685 Y
OS 1.273619980315 0.500869980315
OC 1.31188996063 0.462613779528 1.273619980315 0.4626 Y
OS 1.31188976378 0.21653976378
OC 1.35235984252 0.176069783465 1.352359744094 0.21653976378 N
OS 1.588594094488 0.176069980315
OC 1.62905 0.216525885827 1.588580019685 0.21653996063 N
OS 1.62905019685 0.430120177165
OC 1.77055019685 0.430134055118 1.69980019685 0.430120177165 Y
OS 1.770550098425 0.019702952756
OC 1.770872244094 0.018912204724 1.77165 0.019690059055 N
OS 1.790547933071 -0.000763484252
OC 1.791339862205 -0.001100098425 1.79133996063 -0.000000098425 N
OS 2.192896850394 -0.001100098425
OC 2.193511712598 -0.000920767717 2.192909645669 -0.00000019685 N
OC 2.193677066929 -0.000788484252 2.192910728346 -0.000000098425 N
OS 2.213388188976 0.018922637795
OC 2.213699901575 0.019689862205 2.212599901575 0.019689862205 N
OS 2.2137 0.29331003937
OC 2.2863 0.29331003937 2.25 0.29331003937 Y
OS 2.286300098425 0.019690059055
OC 2.286636712598 0.018898129921 2.287400098425 0.01969015748 N
OS 2.306298129921 -0.000763287402
OC 2.307090059055 -0.001099901575 2.30709015748 0.000000098425 N
OS 3.102347047244 -0.001099901575
OC 3.102961909449 -0.000920570866 3.10235984252 0 N
OC 3.10312726378 -0.000788287402 3.102360925197 0.000000098425 N
OS 3.122837893701 0.01892234252
OC 3.122970570866 0.019087992126 3.122049901575 0.019689468504 N
OC 3.123149901575 0.019702952756 3.12205 0.019690059055 N
OS 3.12314980315 0.462613779528
OC 3.161419783465 0.500869783465 3.161419783465 0.46259980315 Y
OS 6.561034055118 0.500869980315
OC 6.60148996063 0.541325885827 6.561019980315 0.54133996063 N
OS 6.60149015748 2.374999901575
OC 6.580710531496 2.39579015748 6.580705216535 2.375005216535 N
OS 6.572096555118 2.39578996063
OC 6.553530019685 2.414369980315 6.57211003937 2.414369980315 Y
OS 6.553529822835 2.826783759843
OC 6.572110137795 2.84535984252 6.57211476378 2.826774901575 Y
OS 6.572111122047 2.84535984252
OS 6.580724409449 2.84536003937
OC 6.60148996063 2.866125590551 6.58071003937 2.86613996063 N
OS 6.60149015748 4.33661023622
OC 6.561020177165 4.377080216535 6.561020177165 4.33661023622 N
OS 0.039355905512 4.377080019685
OC -0.0011 4.336624114173 0.039369980315 4.33661003937 N
OS -0.00110019685 0.21653976378
OE
SE
S P 0
OB -0.00110019685 0.21653976378 I
OS -0.0011 4.336624114173
OC 0.039355905512 4.377080019685 0.039369980315 4.33661003937 Y
OS 6.561020177165 4.377080216535
OC 6.60149015748 4.33661023622 6.561020177165 4.33661023622 Y
OS 6.60148996063 2.866125590551
OC 6.580724409449 2.84536003937 6.58071003937 2.86613996063 Y
OS 6.580725 2.84536003937
OS 6.580710629921 2.845359940945
OS 6.572123917323 2.845359940945
OS 6.572111122047 2.84535984252
OS 6.572110137795 2.84535984252
OC 6.553529822835 2.826783759843 6.57211476378 2.826774901575 N
OS 6.553530019685 2.414369980315
OC 6.572096555118 2.39578996063 6.57211003937 2.414369980315 N
OS 6.580710531496 2.39579015748
OC 6.60149015748 2.374999901575 6.580705216535 2.375005216535 Y
OS 6.60148996063 0.541325885827
OC 6.561034055118 0.500869980315 6.561019980315 0.54133996063 Y
OS 6.561034744094 0.500869980315
OS 6.561020570866 0.50086988189
OS 3.161433858268 0.50086988189
OS 3.161419783465 0.500869783465
OC 3.12314980315 0.462613779528 3.161419783465 0.46259980315 N
OS 3.123149901575 0.019702952756
OC 3.122970570866 0.019087992126 3.12205 0.019690059055 Y
OC 3.122837893701 0.01892234252 3.122049901575 0.019689468504 Y
OS 3.10312726378 -0.000788287402
OC 3.102961909449 -0.000920570866 3.102360925197 0.000000098425 Y
OC 3.102347047244 -0.001099901575 3.10235984252 0 Y
OS 2.307090059055 -0.001099901575
OC 2.306298129921 -0.000763287402 2.30709015748 0.000000098425 Y
OS 2.286636712598 0.018898129921
OC 2.286300098425 0.019690059055 2.287400098425 0.01969015748 Y
OS 2.2863 0.29331003937
OC 2.2137 0.29331003937 2.25 0.29331003937 N
OS 2.213699901575 0.019689862205
OC 2.213388188976 0.018922637795 2.212599901575 0.019689862205 Y
OS 2.193677066929 -0.000788484252
OC 2.193511712598 -0.000920767717 2.192910728346 -0.000000098425 Y
OC 2.192896850394 -0.001100098425 2.192909645669 -0.00000019685 Y
OS 1.791339862205 -0.001100098425
OC 1.790547933071 -0.000763484252 1.79133996063 -0.000000098425 Y
OS 1.770872244094 0.018912204724
OC 1.770550098425 0.019702952756 1.77165 0.019690059055 Y
OS 1.77055019685 0.430134055118
OC 1.62905019685 0.430120177165 1.69980019685 0.430120177165 N
OS 1.62905 0.216525885827
OC 1.588594094488 0.176069980315 1.588580019685 0.21653996063 Y
OS 1.588594783465 0.176069980315
OS 1.588580610236 0.17606988189
OS 1.352373917323 0.17606988189
OS 1.35235984252 0.176069783465
OC 1.31188976378 0.21653976378 1.352359744094 0.21653976378 Y
OS 1.31188996063 0.462613779528
OC 1.273619980315 0.500869980315 1.273619980315 0.4626 N
OS 0.629906200787 0.500870177165
OC 0.59165019685 0.46260019685 0.629920177165 0.46260019685 N
OS 0.59165 0.216525885827
OC 0.551194094488 0.176069980315 0.551180019685 0.21653996063 Y
OS 0.551194783465 0.176069980315
OS 0.551180610236 0.17606988189
OS 0.039383858268 0.17606988189
OS 0.039369783465 0.176069783465
OC -0.00110019685 0.21653976378 0.039369783465 0.21653976378 Y
OE
OB 0.03003996063 0.21653996063 H
OC 0.039369980315 0.20721003937 0.03936988189 0.21653996063 N
OS 0.551180019685 0.20721003937
OC 0.56051003937 0.21653996063 0.55118011811 0.21653996063 N
OS 0.56051003937 0.4626
OC 0.629919980315 0.53201003937 0.629919980315 0.462600098425 Y
OS 1.273619980315 0.53201003937
OC 1.343030019685 0.4626 1.273619980315 0.4626 Y
OS 1.343030019685 0.21653996063
OC 1.35236003937 0.20721003937 1.352359940945 0.21653996063 N
OS 1.588580019685 0.20721003937
OC 1.59791003937 0.21653996063 1.58858011811 0.21653996063 N
OS 1.59791003937 0.430119980315
OC 1.80168996063 0.430119980315 1.6998 0.430119980315 Y
OS 1.80168996063 0.262
OS 2.18256003937 0.262
OS 2.18256003937 0.29331003937
OC 2.31743996063 0.29331003937 2.25 0.29331003937 Y
OS 2.31743996063 0.262
OS 3.09201003937 0.262
OS 3.09201003937 0.4626
OC 3.161419980315 0.53201003937 3.161419980315 0.462600098425 Y
OS 6.561019980315 0.53201003937
OC 6.57035 0.54133996063 6.56102007874 0.54133996063 N
OS 6.57035 2.364680019685
OC 6.52238996063 2.414369980315 6.572111220472 2.41437007874 Y
OS 6.52238996063 2.826780019685
OC 6.57035 2.876469980315 6.572115452756 2.826775885827 Y
OS 6.57035 4.33661003937
OC 6.561019980315 4.34593996063 6.56102007874 4.33661003937 N
OS 0.039369980315 4.34593996063
OC 0.03003996063 4.33661003937 0.03936988189 4.33661003937 N
OS 0.03003996063 0.21653996063
OE
OB 0.36981003937 0.36811003937 I
OC 0.36981003937 0.36811003937 0.295280019685 0.36811003937 Y
OE
OB 0.36981003937 3.73031003937 I
OC 0.36981003937 3.73031003937 0.295280019685 3.73031003937 Y
OE
OB 0.688980019685 3.560980019685 I
OS 0.688980019685 3.589019980315
OS 0.749019980315 3.589019980315
OS 0.749019980315 3.560980019685
OS 0.688980019685 3.560980019685
OE
OB 1.058980019685 3.810980019685 I
OS 1.058980019685 3.839019980315
OS 1.119019980315 3.839019980315
OS 1.119019980315 3.810980019685
OS 1.058980019685 3.810980019685
OE
OB 1.4977 1.060430019685 I
OC 1.4977 1.060430019685 1.435669980315 1.060430019685 Y
OE
OB 1.5227 2.680430019685 I
OC 1.5227 2.680430019685 1.460669980315 2.680430019685 Y
OE
OB 2.3311 0.569980019685 I
OS 2.3311 0.598019980315
OS 2.355119980315 0.598019980315
OS 2.355119980315 0.569980019685
OS 2.3311 0.569980019685
OE
OB 2.3311 0.611980019685 I
OS 2.3311 0.640019980315
OS 2.355119980315 0.640019980315
OS 2.355119980315 0.611980019685
OS 2.3311 0.611980019685
OE
OB 2.3811 0.569980019685 I
OS 2.3811 0.598019980315
OS 2.405119980315 0.598019980315
OS 2.405119980315 0.569980019685
OS 2.3811 0.569980019685
OE
OB 2.3811 0.611980019685 I
OS 2.3811 0.640019980315
OS 2.405119980315 0.640019980315
OS 2.405119980315 0.611980019685
OS 2.3811 0.611980019685
OE
OB 2.39006003937 0.679980019685 I
OS 2.39006003937 0.750019980315
OS 2.4201 0.750019980315
OS 2.4201 0.679980019685
OS 2.39006003937 0.679980019685
OE
OB 2.4492 0.569980019685 I
OS 2.4492 0.598019980315
OS 2.47323996063 0.598019980315
OS 2.47323996063 0.569980019685
OS 2.4492 0.569980019685
OE
OB 2.4492 0.611980019685 I
OS 2.4492 0.640019980315
OS 2.47323996063 0.640019980315
OS 2.47323996063 0.611980019685
OS 2.4492 0.611980019685
OE
OB 2.4562 0.748980019685 I
OS 2.4562 0.777019980315
OS 2.51623996063 0.777019980315
OS 2.51623996063 0.748980019685
OS 2.4562 0.748980019685
OE
OB 2.4992 0.569980019685 I
OS 2.4992 0.598019980315
OS 2.52323996063 0.598019980315
OS 2.52323996063 0.569980019685
OS 2.4992 0.569980019685
OE
OB 2.4992 0.611980019685 I
OS 2.4992 0.640019980315
OS 2.52323996063 0.640019980315
OS 2.52323996063 0.611980019685
OS 2.4992 0.611980019685
OE
OB 2.7477 1.121430019685 I
OC 2.7477 1.121430019685 2.685669980315 1.121430019685 Y
OE
OB 2.7477 2.559430019685 I
OC 2.7477 2.559430019685 2.685669980315 2.559430019685 Y
OE
OB 2.629380019685 0.338980019685 I
OS 2.629380019685 0.399019980315
OS 2.6574 0.399019980315
OS 2.6574 0.338980019685
OS 2.629380019685 0.338980019685
OE
OB 2.64606003937 0.569980019685 I
OS 2.64606003937 0.598019980315
OS 2.670080019685 0.598019980315
OS 2.670080019685 0.569980019685
OS 2.64606003937 0.569980019685
OE
OB 2.64606003937 0.611980019685 I
OS 2.64606003937 0.640019980315
OS 2.670080019685 0.640019980315
OS 2.670080019685 0.611980019685
OS 2.64606003937 0.611980019685
OE
OB 2.65306003937 0.748980019685 I
OS 2.65306003937 0.777019980315
OS 2.713080019685 0.777019980315
OS 2.713080019685 0.748980019685
OS 2.65306003937 0.748980019685
OE
OB 2.69606003937 0.569980019685 I
OS 2.69606003937 0.598019980315
OS 2.720080019685 0.598019980315
OS 2.720080019685 0.569980019685
OS 2.69606003937 0.569980019685
OE
OB 2.69606003937 0.611980019685 I
OS 2.69606003937 0.640019980315
OS 2.720080019685 0.640019980315
OS 2.720080019685 0.611980019685
OS 2.69606003937 0.611980019685
OE
OB 2.782480019685 1.932980019685 I
OS 2.782480019685 1.957019980315
OS 2.810519980315 1.957019980315
OS 2.810519980315 1.932980019685
OS 2.782480019685 1.932980019685
OE
OB 2.782980019685 1.823980019685 I
OS 2.782980019685 1.852019980315
OS 2.807019980315 1.852019980315
OS 2.807019980315 1.823980019685
OS 2.782980019685 1.823980019685
OE
OB 2.782980019685 1.865980019685 I
OS 2.782980019685 1.894019980315
OS 2.807019980315 1.894019980315
OS 2.807019980315 1.865980019685
OS 2.782980019685 1.865980019685
OE
OB 2.783 1.971980019685 I
OS 2.783 2.002019980315
OS 2.853019980315 2.002019980315
OS 2.853019980315 1.971980019685
OS 2.783 1.971980019685
OE
OB 2.78686003937 0.338980019685 I
OS 2.78686003937 0.399019980315
OS 2.814880019685 0.399019980315
OS 2.814880019685 0.338980019685
OS 2.78686003937 0.338980019685
OE
OB 2.78853996063 0.569980019685 I
OS 2.78853996063 0.598019980315
OS 2.81256003937 0.598019980315
OS 2.81256003937 0.569980019685
OS 2.78853996063 0.569980019685
OE
OB 2.78853996063 0.611980019685 I
OS 2.78853996063 0.640019980315
OS 2.81256003937 0.640019980315
OS 2.81256003937 0.611980019685
OS 2.78853996063 0.611980019685
OE
OB 2.80453996063 0.748980019685 I
OS 2.80453996063 0.777019980315
OS 2.86456003937 0.777019980315
OS 2.86456003937 0.748980019685
OS 2.80453996063 0.748980019685
OE
OB 2.824480019685 1.932980019685 I
OS 2.824480019685 1.957019980315
OS 2.852519980315 1.957019980315
OS 2.852519980315 1.932980019685
OS 2.824480019685 1.932980019685
OE
OB 2.829980019685 1.823980019685 I
OS 2.829980019685 1.894019980315
OS 2.860019980315 1.894019980315
OS 2.860019980315 1.823980019685
OS 2.829980019685 1.823980019685
OE
OB 2.83853996063 0.569980019685 I
OS 2.83853996063 0.598019980315
OS 2.86256003937 0.598019980315
OS 2.86256003937 0.569980019685
OS 2.83853996063 0.569980019685
OE
OB 2.83853996063 0.611980019685 I
OS 2.83853996063 0.640019980315
OS 2.86256003937 0.640019980315
OS 2.86256003937 0.611980019685
OS 2.83853996063 0.611980019685
OE
OB 2.94433996063 0.338980019685 I
OS 2.94433996063 0.399019980315
OS 2.97236003937 0.399019980315
OS 2.97236003937 0.338980019685
OS 2.94433996063 0.338980019685
OE
OB 2.94433996063 0.434980019685 I
OS 2.94433996063 0.495019980315
OS 2.97236003937 0.495019980315
OS 2.97236003937 0.434980019685
OS 2.94433996063 0.434980019685
OE
OB 2.961019980315 0.569980019685 I
OS 2.961019980315 0.598019980315
OS 2.98503996063 0.598019980315
OS 2.98503996063 0.569980019685
OS 2.961019980315 0.569980019685
OE
OB 2.961019980315 0.611980019685 I
OS 2.961019980315 0.640019980315
OS 2.98503996063 0.640019980315
OS 2.98503996063 0.611980019685
OS 2.961019980315 0.611980019685
OE
OB 3.011019980315 0.569980019685 I
OS 3.011019980315 0.598019980315
OS 3.03503996063 0.598019980315
OS 3.03503996063 0.569980019685
OS 3.011019980315 0.569980019685
OE
OB 3.011019980315 0.611980019685 I
OS 3.011019980315 0.640019980315
OS 3.03503996063 0.640019980315
OS 3.03503996063 0.611980019685
OS 3.011019980315 0.611980019685
OE
OB 3.10516003937 0.875 I
OS 3.125 0.89483996063
OS 3.167469980315 0.852369980315
OS 3.147630019685 0.832530019685
OS 3.10516003937 0.875
OE
OB 3.213080019685 1.888980019685 I
OS 3.213080019685 1.917
OS 3.273119980315 1.917
OS 3.273119980315 1.888980019685
OS 3.213080019685 1.888980019685
OE
OB 3.359980019685 1.142980019685 I
OS 3.359980019685 1.213019980315
OS 3.390019980315 1.213019980315
OS 3.390019980315 1.142980019685
OS 3.359980019685 1.142980019685
OE
OB 3.398980019685 1.069980019685 I
OS 3.398980019685 1.100019980315
OS 3.469019980315 1.100019980315
OS 3.469019980315 1.069980019685
OS 3.398980019685 1.069980019685
OE
OB 3.439 1.884980019685 I
OS 3.439 1.945
OS 3.467019980315 1.945
OS 3.467019980315 1.884980019685
OS 3.439 1.884980019685
OE
OB 3.49563996063 1.03206003937 I
OS 3.49563996063 1.062080019685
OS 3.56566003937 1.062080019685
OS 3.56566003937 1.03206003937
OS 3.49563996063 1.03206003937
OE
OB 3.518980019685 1.874480019685 I
OS 3.518980019685 1.8985
OS 3.547019980315 1.8985
OS 3.547019980315 1.874480019685
OS 3.518980019685 1.874480019685
OE
OB 3.518980019685 1.919480019685 I
OS 3.518980019685 1.9435
OS 3.547019980315 1.9435
OS 3.547019980315 1.919480019685
OS 3.518980019685 1.919480019685
OE
OB 3.560980019685 1.874480019685 I
OS 3.560980019685 1.8985
OS 3.589019980315 1.8985
OS 3.589019980315 1.874480019685
OS 3.560980019685 1.874480019685
OE
OB 3.560980019685 1.919480019685 I
OS 3.560980019685 1.9435
OS 3.589019980315 1.9435
OS 3.589019980315 1.919480019685
OS 3.560980019685 1.919480019685
OE
OB 3.610980019685 0.905980019685 I
OS 3.610980019685 0.934019980315
OS 3.671019980315 0.934019980315
OS 3.671019980315 0.905980019685
OS 3.610980019685 0.905980019685
OE
OB 3.637 1.869580019685 I
OS 3.637 1.9296
OS 3.665019980315 1.9296
OS 3.665019980315 1.869580019685
OS 3.637 1.869580019685
OE
OB 3.871930019685 1.417019980315 I
OC 3.871930019685 1.443080019685 3.871930019685 1.43005 Y
OS 3.9113 1.443080019685
OC 3.9113 1.417019980315 3.9113 1.43005 Y
OS 3.871930019685 1.417019980315
OE
OB 3.871930019685 1.49576003937 I
OC 3.871930019685 1.521819980315 3.871930019685 1.508790059055 Y
OS 3.9113 1.521819980315
OC 3.9113 1.49576003937 3.9113 1.508790059055 Y
OS 3.871930019685 1.49576003937
OE
OB 3.871930019685 1.5745 I
OC 3.871930019685 1.60056003937 3.871930019685 1.587530019685 Y
OS 3.9113 1.60056003937
OC 3.9113 1.5745 3.9113 1.587530019685 Y
OS 3.871930019685 1.5745
OE
OB 3.871930019685 1.65323996063 I
OC 3.871930019685 1.6793 3.871930019685 1.666269980315 Y
OS 3.9113 1.6793
OC 3.9113 1.65323996063 3.9113 1.666269980315 Y
OS 3.871930019685 1.65323996063
OE
OB 3.950669980315 1.53513996063 I
OC 3.950669980315 1.561180019685 3.950669980315 1.54816003937 Y
OS 3.99003996063 1.561180019685
OC 3.99003996063 1.53513996063 3.99003996063 1.54816003937 Y
OS 3.950669980315 1.53513996063
OE
OB 3.950669980315 1.692619980315 I
OC 3.950669980315 1.71866003937 3.950669980315 1.705640059055 Y
OS 3.99003996063 1.71866003937
OC 3.99003996063 1.692619980315 3.99003996063 1.705640059055 Y
OS 3.950669980315 1.692619980315
OE
OB 3.950669980315 1.4564 I
OC 3.950669980315 1.48243996063 3.950669980315 1.469419980315 Y
OS 3.99003996063 1.48243996063
OC 3.99003996063 1.4564 3.99003996063 1.469419980315 Y
OS 3.950669980315 1.4564
OE
OB 3.950669980315 1.613880019685 I
OC 3.950669980315 1.639919980315 3.950669980315 1.6269 Y
OS 3.99003996063 1.639919980315
OC 3.99003996063 1.613880019685 3.99003996063 1.6269 Y
OS 3.950669980315 1.613880019685
OE
OB 3.997480019685 1.145980019685 I
OS 3.997480019685 1.176
OS 4.067519980315 1.176
OS 4.067519980315 1.145980019685
OS 3.997480019685 1.145980019685
OE
OB 4.029419980315 1.49576003937 I
OC 4.029419980315 1.521819980315 4.029419980315 1.508790059055 Y
OS 4.06878996063 1.521819980315
OC 4.06878996063 1.49576003937 4.06878996063 1.508790059055 Y
OS 4.029419980315 1.49576003937
OE
OB 4.029419980315 1.65323996063 I
OC 4.029419980315 1.6793 4.029419980315 1.666269980315 Y
OS 4.06878996063 1.6793
OC 4.06878996063 1.65323996063 4.06878996063 1.666269980315 Y
OS 4.029419980315 1.65323996063
OE
OB 4.3575 1.150980019685 I
OS 4.3575 1.181
OS 4.427519980315 1.181
OS 4.427519980315 1.150980019685
OS 4.3575 1.150980019685
OE
OB 4.42311003937 1.850080019685 I
OC 4.42311003937 1.87613996063 4.42311003937 1.86311003937 Y
OS 4.462480019685 1.87613996063
OC 4.462480019685 1.850080019685 4.462480019685 1.86311003937 Y
OS 4.42311003937 1.850080019685
OE
OB 4.462480019685 1.417019980315 I
OC 4.462480019685 1.443080019685 4.462480019685 1.43005 Y
OS 4.50185 1.443080019685
OC 4.50185 1.417019980315 4.50185 1.43005 Y
OS 4.462480019685 1.417019980315
OE
OB 4.5223 1.20666003937 I
OS 4.5223 1.236680019685
OS 4.592319980315 1.236680019685
OS 4.592319980315 1.20666003937
OS 4.5223 1.20666003937
OE
OB 4.61996003937 1.2989 I
OC 4.61996003937 1.32496003937 4.61996003937 1.311930019685 Y
OS 4.659330019685 1.32496003937
OC 4.659330019685 1.2989 4.659330019685 1.311930019685 Y
OS 4.61996003937 1.2989
OE
OB 4.6987 1.4564 I
OC 4.6987 1.48243996063 4.6987 1.469419980315 Y
OS 4.738069980315 1.48243996063
OC 4.738069980315 1.4564 4.738069980315 1.469419980315 Y
OS 4.6987 1.4564
OE
OB 4.72503996063 1.3513 I
OS 4.72503996063 1.390669980315
OC 4.7511 1.390669980315 4.738069980315 1.390669980315 Y
OS 4.7511 1.3513
OC 4.72503996063 1.3513 4.738069980315 1.3513 Y
OE
OB 6.190030019685 2.094 I
OC 6.190030019685 2.094 5.99 2.094 Y
OE
OB 5.974969980315 1.045 I
OC 5.984369980315 1.1056 6.174999507874 1.045001377953 Y
OC 5.97846003937 1.12348996063 6.008502165354 1.123493208661 Y
OS 5.97846003937 1.1235
OC 6.00696003937 1.1535 6.008499507874 1.1235 Y
OC 6.175 1.245030019685 6.175000098425 1.045012598425 Y
OC 6.375030019685 1.045 6.175 1.045 Y
OC 6.362830019685 0.97621003937 6.174992913386 1.045 Y
OC 6.365 0.96501003937 6.334998523622 0.965007480315 Y
OS 6.365 0.965
OC 6.342730019685 0.93601003937 6.334996161417 0.965 Y
OC 6.175 0.844969980315 6.174999901575 1.045000984252 Y
OC 5.974969980315 1.045 6.175 1.045 Y
OE
OB 6.1856 2.230719980315 I
OS 6.1856 2.29076003937
OS 6.213619980315 2.29076003937
OS 6.213619980315 2.230719980315
OS 6.1856 2.230719980315
OE
OB 6.424580019685 3.34448996063 I
OC 6.424580019685 3.34448996063 6.34055 3.34448996063 Y
OE
OB 6.424580019685 3.67518996063 I
OC 6.424580019685 3.67518996063 6.34055 3.67518996063 Y
OE
OB 6.474919980315 0.65353996063 I
OC 6.474919980315 0.65353996063 6.40038996063 0.65353996063 Y
OE
OB 6.474919980315 4.17835 I
OC 6.474919980315 4.17835 6.40038996063 4.17835 Y
OE
SE
P 4.31 4.065 6 P 0 8 0;1=0
P 4.31 4.115 6 P 0 8 0;1=0
P 4.61 2.3 6 P 0 8 0;1=0
P 4.50185 2.05996004 4 P 0 8 0;1=1
P 4.49 2.275 6 P 0 8 0;1=0
P 4.435 2.315 6 P 0 8 0;1=0
P 4.49 2.325 6 P 0 8 0;1=0
P 4.435 2.365 6 P 0 8 0;1=0
P 3.655 2.465 6 P 0 8 0;1=0
P 3.125 1.605 6 P 0 8 0;1=0
P 3.65 2.68 6 P 0 8 0;1=2
P 3.12 2.645 6 P 0 8 0;1=2
P 4.1869 2.09933002 4 P 0 8 0;1=1
P 3.765 2.69 6 P 0 8 0;1=0
P 4.50185 1.50878996 4 P 0 8 0;1=1
P 4.3 3.865 4 P 0 8 0;1=3
P 3.36525 3.305 3 P 0 8 0;1=4
P 3.37 3.44 4 P 0 8 0;1=3
P 4.795 0.925 4 P 0 8 0;1=3
P 4.08 3.27 4 P 0 8 0;1=3
P 3.95 3.82 4 P 0 8 0;1=3
P 3.746 1.782 4 P 0 8 0;1=3
P 4.06878996 1.58753002 4 P 0 8 0;1=1
P 4.205 0.82 4 P 0 8 0;1=3
P 3.82286004 0.86213996 6 P 0 8 0;1=0
P 3.705 0.84 4 P 0 8 0;1=3
P 0.496 2.13455 6 P 0 8 0;1=0
P 0.528 2.72 6 P 0 8 0;1=0
P 0.575 1.015 6 P 0 8 0;1=0
P 0.48956998 1.53618996 6 P 0 8 0;1=0
P 4.65933002 1.98121998 4 P 0 8 0;1=1
P 4.06878996 1.90248002 4 P 0 8 0;1=1
P 4.50185 1.39066998 4 P 0 8 0;1=1
P 4.06878996 2.1387 4 P 0 8 0;1=1
P 4.22626998 2.05996004 4 P 0 8 0;1=1
P 3.95066998 2.05996004 4 P 0 8 0;1=1
P 4.22626998 2.02058996 4 P 0 8 0;1=1
P 4.26563996 2.09933002 4 P 0 8 0;1=1
P 4.26563996 2.05996004 4 P 0 8 0;1=1
P 4.50185 1.90248002 4 P 0 8 0;1=1
P 4.73806998 2.09933002 4 P 0 8 0;1=1
P 4.02941998 2.02058996 4 P 0 8 0;1=1
P 4.50185 1.86311004 4 P 0 8 0;1=1
P 4.6987 2.05996004 4 P 0 8 0;1=1
P 4.61996004 1.94185 4 P 0 8 0;1=1
P 4.61996004 1.98121998 4 P 0 8 0;1=1
P 4.26563996 2.02058996 4 P 0 8 0;1=1
P 4.61996004 1.90248002 4 P 0 8 0;1=1
P 4.58058996 1.98121998 4 P 0 8 0;1=1
P 4.54121998 2.02058996 4 P 0 8 0;1=1
P 4.34436998 2.09933002 4 P 0 8 0;1=1
P 4.06878996 2.09933002 4 P 0 8 0;1=5
P 4.6987 1.50878996 4 P 0 8 0;1=1
P 4.54121998 1.98121998 4 P 0 8 0;1=1
P 4.06878996 2.05996004 4 P 0 8 0;1=1
P 4.65933002 1.50878996 4 P 0 8 0;1=1
P 3.95066998 2.09933002 4 P 0 8 0;1=1
P 4.61996004 1.54816004 4 P 0 8 0;1=1
P 3.99005 2.09933002 4 P 0 8 0;1=5
P 4.58058996 1.54816004 4 P 0 8 0;1=1
P 4.6987 1.94185 4 P 0 8 0;1=1
P 4.50185 2.02058996 4 P 0 8 0;1=1
P 4.46248002 2.02058996 4 P 0 8 0;1=1
P 4.42311004 1.98121998 4 P 0 8 0;1=1
P 4.46248002 1.94185 4 P 0 8 0;1=1
P 4.38373996 1.86311004 4 P 0 8 0;1=1
P 4.38373996 1.82373996 4 P 0 8 0;1=1
P 4.46248002 1.98121998 4 P 0 8 0;1=1
P 4.10816004 1.94185 4 P 0 8 0;1=1
P 4.02941998 1.98121998 4 P 0 8 0;1=1
P 4.58058996 2.17806998 4 P 0 8 0;1=1
P 4.73806998 1.90248002 4 P 0 8 0;1=1
P 4.54121998 2.1387 4 P 0 8 0;1=1
P 4.10816004 2.02058996 4 P 0 8 0;1=1
P 4.50185 2.1387 4 P 0 8 0;1=1
P 3.99005 1.94185 4 P 0 8 0;1=1
P 4.02941998 1.94185 4 P 0 8 0;1=1
P 4.50185 2.09933002 4 P 0 8 0;1=1
P 4.14753002 2.02058996 4 P 0 8 0;1=1
P 4.61996004 2.17806998 4 P 0 8 0;1=1
P 4.02941998 1.86311004 4 P 0 8 0;1=1
P 4.06878996 1.43005 4 P 0 8 0;1=1
P 4.54121998 1.54816004 4 P 0 8 0;1=1
P 4.26563996 1.50878996 4 P 0 8 0;1=1
P 4.1869 1.94185 4 P 0 8 0;1=1
P 4.14753002 1.46941998 4 P 0 8 0;1=1
P 4.1869 1.46941998 4 P 0 8 0;1=1
P 4.1869 2.1387 4 P 0 8 0;1=1
P 4.6987 1.43005 4 P 0 8 0;1=1
P 4.10816004 1.39066998 4 P 0 8 0;1=1
P 4.65933002 1.43005 4 P 0 8 0;1=1
P 4.14753002 1.39066998 4 P 0 8 0;1=1
P 4.61996004 1.43005 4 P 0 8 0;1=1
P 4.10816004 1.43005 4 P 0 8 0;1=1
P 4.58058996 1.43005 4 P 0 8 0;1=1
P 4.14753002 1.43005 4 P 0 8 0;1=1
P 4.1869 1.43005 4 P 0 8 0;1=1
P 4.22626998 1.43005 4 P 0 8 0;1=1
P 4.54121998 1.46941998 4 P 0 8 0;1=1
P 4.22626998 1.39066998 4 P 0 8 0;1=1
P 4.50185 1.46941998 4 P 0 8 0;1=1
P 4.26563996 1.39066998 4 P 0 8 0;1=1
P 4.61996004 1.46941998 4 P 0 8 0;1=1
P 4.26563996 1.31193002 4 P 0 8 0;1=1
P 4.61996004 1.50878996 4 P 0 8 0;1=1
P 4.34436998 1.31193002 4 P 0 8 0;1=1
P 4.58058996 1.46941998 4 P 0 8 0;1=1
P 4.34436998 1.3513 4 P 0 8 0;1=1
P 4.54121998 1.50878996 4 P 0 8 0;1=1
P 4.34436998 1.39066998 4 P 0 8 0;1=1
P 4.1869 1.50878996 4 P 0 8 0;1=1
P 4.46248002 1.50878996 4 P 0 8 0;1=1
P 4.22626998 1.50878996 4 P 0 8 0;1=1
P 4.26563996 1.43005 4 P 0 8 0;1=5
P 4.26563996 1.46941998 4 P 0 8 0;1=1
P 4.38373996 1.39066998 4 P 0 8 0;1=1
P 4.38373996 1.43005 4 P 0 8 0;1=1
P 4.54121998 1.31193002 4 P 0 8 0;1=1
P 4.49876004 1.31501998 4 P 0 8 0;1=1
P 4.34436998 1.98121998 4 P 0 8 0;1=1
P 4.57843996 1.35345 4 P 0 8 0;1=1
P 3.9113 1.3513 4 P 0 8 0;1=1
P 4.54121998 1.3513 4 P 0 8 0;1=1
P 3.95066998 1.3513 4 P 0 8 0;1=1
P 4.45938996 1.35438996 4 P 0 8 0;1=1
P 3.99 1.31188002 4 P 0 8 0;1=1
P 4.46248002 1.39066998 4 P 0 8 0;1=1
P 4.65933002 1.3513 4 P 0 8 0;1=1
P 3.99 1.35125 4 P 0 8 0;1=1
P 4.61996004 1.3513 4 P 0 8 0;1=1
P 4.6987 1.86311004 4 P 0 8 0;1=1
P 4.46248002 2.05996004 4 P 0 8 0;1=1
P 4.06873996 1.31188002 4 P 0 8 0;1=1
P 4.65933002 1.82373996 4 P 0 8 0;1=1
P 4.42311004 2.05996004 4 P 0 8 0;1=1
P 4.10811004 1.31188002 4 P 0 8 0;1=1
P 4.58058996 1.39066998 4 P 0 8 0;1=1
P 4.02941998 1.39066998 4 P 0 8 0;1=1
P 4.54121998 1.39066998 4 P 0 8 0;1=1
P 4.06878996 1.39066998 4 P 0 8 0;1=1
P 4.73806998 1.78436998 4 P 0 8 0;1=1
P 4.73806998 1.31193002 4 P 0 8 0;1=1
P 4.1869 1.31193002 4 P 0 8 0;1=1
P 4.73806998 1.70563996 4 P 0 8 0;1=1
P 4.6987 1.31193002 4 P 0 8 0;1=1
P 4.22626998 1.31193002 4 P 0 8 0;1=1
P 4.10816004 1.3513 4 P 0 8 0;1=1
P 4.14753002 1.3513 4 P 0 8 0;1=1
P 4.6987 1.39066998 4 P 0 8 0;1=1
P 4.1869 1.3513 4 P 0 8 0;1=1
P 4.65933002 1.39066998 4 P 0 8 0;1=1
P 4.22626998 1.3513 4 P 0 8 0;1=1
P 4.73806998 2.17806998 4 P 0 8 0;1=1
P 4.73806998 2.1387 4 P 0 8 0;1=1
P 4.58058996 2.09933002 4 P 0 8 0;1=1
P 4.54121998 2.09933002 4 P 0 8 0;1=1
P 4.58058996 1.86311004 4 P 0 8 0;1=1
P 4.65933002 2.05996004 4 P 0 8 0;1=1
P 4.58058996 2.05996004 4 P 0 8 0;1=1
P 4.54121998 1.90248002 4 P 0 8 0;1=1
P 4.58058996 2.02058996 4 P 0 8 0;1=1
P 4.22626998 1.98121998 4 P 0 8 0;1=1
P 4.26563996 1.94185 4 P 0 8 0;1=1
P 4.10816004 1.98121998 4 P 0 8 0;1=1
P 4.14753002 1.98121998 4 P 0 8 0;1=1
P 4.61996004 2.1387 4 P 0 8 0;1=1
P 4.6987 1.70563996 4 P 0 8 0;1=1
P 4.6987 1.66626998 4 P 0 8 0;1=1
P 1.45 3.59 6 P 0 8 0;1=0
P 1.56 3.165 6 P 0 8 0;1=2
P 1.56 3.205 6 P 0 8 0;1=0
P 0.72 3.463 6 P 0 8 0;1=2
P 0.42326004 3.4315 7 P 0 8 0;1=6
P 0.40553996 3.4008 7 P 0 8 0;1=6
P 0.2815 3.4315 7 P 0 8 0;1=6
P 0.26378002 3.4008 7 P 0 8 0;1=6
P 0.71 3.305 4 P 0 8 0;1=3
P 1.14 3.52 6 P 0 8 0;1=0
P 1.245 3.52 6 P 0 8 0;1=0
P 4.705 3.95 3 P 0 8 0;1=4
P 4.705 3.91 6 P 0 8 0;1=2
P 1.566 2.95 6 P 0 8 0;1=0
P 1.045 3.77 6 P 0 8 0;1=2
P 1.515 3.58 6 P 0 8 0;1=2
P 6.145 4.035 6 P 0 8 0;1=0
P 1.37 3.64 6 P 0 8 0;1=2
P 1.667 3.438 6 P 0 8 0;1=2
P 1.591 3.546 6 P 0 8 0;1=2
P 1.13 3.445 6 P 0 8 0;1=2
P 0.95 3.445 6 P 0 8 0;1=2
P 2.19 3.488 6 P 0 8 0;1=2
P 2.192 3.388 6 P 0 8 0;1=2
P 1.41916004 3.33916004 6 P 0 8 0;1=2
P 1.407 3.2 6 P 0 8 0;1=2
P 1.495 3.11033996 6 P 0 8 0;1=2
P 1.535 3.105 4 P 0 8 0;1=3
P 1.15253002 3.06246998 6 P 0 8 0;1=2
P 0.95 3.215 6 P 0 8 0;1=2
P 0.945 3.125 6 P 0 8 0;1=2
P 1.175 2.9 6 P 0 8 0;1=2
P 1.025 3.02 6 P 0 8 0;1=2
P 5.275 3.891 6 P 0 8 0;1=0
P 5.275 3.931 6 P 0 8 0;1=2
P 5.275 3.971 6 P 0 8 0;1=0
P 5.321 3.99 6 P 0 8 0;1=2
P 5.762 3.425 5 P 0 8 0;1=7
P 5.567 3.203 6 P 0 8 0;1=2
P 5.617 3.203 6 P 0 8 0;1=0
P 5.62 3.316 6 P 0 8 0;1=2
P 5.625 3.261 6 P 0 8 0;1=0
P 5.625 3.361 6 P 0 8 0;1=2
P 5.6 3.421 6 P 0 8 0;1=0
P 5.552 3.71141004 5 P 0 8 0;1=8
P 5.552 3.74683996 5 P 0 8 0;1=8
P 5.552 3.78226998 5 P 0 8 0;1=8
P 5.552 3.67596998 5 P 0 8 0;1=8
P 5.52 3.78226998 5 P 0 8 0;1=8
P 5.52 3.74683996 5 P 0 8 0;1=8
P 5.52 3.71141004 5 P 0 8 0;1=8
P 5.52 3.67596998 5 P 0 8 0;1=8
P 0.978 3.918 4 P 0 8 0;1=3
P 0.928 3.961 6 P 0 8 0;1=2
P 0.968 3.961 6 P 0 8 0;1=2
P 0.968 4.021 6 P 0 8 0;1=2
P 0.928 4.021 6 P 0 8 0;1=0
P 0.928 4.081 6 P 0 8 0;1=2
P 0.968 4.081 6 P 0 8 0;1=0
P 0.928 4.141 6 P 0 8 0;1=0
P 0.968 4.141 6 P 0 8 0;1=2
P 0.603 3.951 6 P 0 8 0;1=0
P 0.643 3.956 6 P 0 8 0;1=2
P 0.603 4.011 6 P 0 8 0;1=2
P 0.643 4.016 6 P 0 8 0;1=0
P 0.603 4.071 6 P 0 8 0;1=0
P 0.643 4.076 6 P 0 8 0;1=2
P 0.603 4.131 6 P 0 8 0;1=2
P 0.643 4.136 6 P 0 8 0;1=0
P 0.854 3.942 6 P 0 8 0;1=2
P 0.807 3.942 6 P 0 8 0;1=2
P 0.76 3.942 6 P 0 8 0;1=2
P 0.713 3.942 6 P 0 8 0;1=2
P 0.76 4.042 6 P 0 8 0;1=2
P 0.76 3.992 6 P 0 8 0;1=2
P 0.713 3.992 6 P 0 8 0;1=2
P 0.713 4.042 6 P 0 8 0;1=2
P 0.713 4.092 6 P 0 8 0;1=2
P 0.76 4.092 6 P 0 8 0;1=2
P 0.807 4.092 6 P 0 8 0;1=2
P 0.807 4.042 6 P 0 8 0;1=2
P 0.807 3.992 6 P 0 8 0;1=2
P 0.854 3.992 6 P 0 8 0;1=2
P 0.854 4.042 6 P 0 8 0;1=2
P 0.854 4.092 6 P 0 8 0;1=2
P 0.74 1.005 6 P 0 8 0;1=0
P 0.79 1.005 6 P 0 8 0;1=0
P 0.84 1.005 6 P 0 8 0;1=0
P 1.568 3.011 6 P 0 8 0;1=0
P 1.738 3.241 6 P 0 8 0;1=0
P 1.765 2.9 6 P 0 8 0;1=0
P 1.78 3.095 6 P 0 8 0;1=0
P 1.795 2.946 6 P 0 8 0;1=0
P 5.2 0.87 6 P 0 8 0;1=0
P 4.47 3.21998002 6 P 0 8 0;1=0
P 4.385 3.645 6 P 0 8 0;1=0
P 0.78 3.305 4 P 0 8 0;1=3
P 1.03 3.515 6 P 0 8 0;1=0
P 1.19 3.52 6 P 0 8 0;1=0
P 0.95 2.915 4 P 0 8 0;1=3
P 0.945 2.99 4 P 0 8 0;1=3
P 0.885 3.03 4 P 0 8 0;1=3
P 0.875 2.955 4 P 0 8 0;1=3
P 0.795 3.085 4 P 0 8 0;1=3
P 0.55 3.36 6 P 0 8 0;1=0
P 0.3701 3.4008 7 P 0 8 0;1=6
P 0.55 3.554 6 P 0 8 0;1=0
P 0.31693996 3.4315 7 P 0 8 0;1=6
P 5.92 1.57063002 6 P 0 8 0;1=0
P 6.22 1.57 6 P 0 8 0;1=0
P 5.92 1.46 6 P 0 8 0;1=0
P 6.22 1.465 6 P 0 8 0;1=0
P 5.92 1.68 6 P 0 8 0;1=0
P 6.22035 1.67063002 6 P 0 8 0;1=0
P 5.92 1.78 6 P 0 8 0;1=0
P 6.22 1.755 6 P 0 8 0;1=0
P 6.09423996 4.13778996 6 P 0 8 0;1=0
P 3.51 3.08 6 P 0 8 0;1=0
P 1.025 2.9 6 P 0 8 0;1=2
P 4.42311004 1.94185 4 P 0 8 0;1=1
P 3.46 3.065 6 P 0 8 0;1=0
P 1.125 2.9 6 P 0 8 0;1=2
P 4.42311004 1.90248002 4 P 0 8 0;1=1
P 3.035 1.64 6 P 0 8 0;1=2
P 3.445 2.65 4 P 0 8 0;1=3
P 1.1288 0.7302 5 P 0 8 0;1=7
P 3.075 1.605 6 P 0 8 0;1=2
P 3.365 2.95 3 P 0 8 0;1=4
P 0.755 0.62 4 P 0 8 0;1=3
P 0.715 0.77 6 P 0 8 0;1=0
P 0.83 3.445 6 P 0 8 0;1=0
P 0.795 3.485 6 P 0 8 0;1=0
P 0.83 3.525 6 P 0 8 0;1=0
P 0.951 3.519 6 P 0 8 0;1=0
P 0.82951004 3.2794 6 P 0 8 0;1=0
P 0.79 3.155 6 P 0 8 0;1=0
P 0.78635 3.24491998 6 P 0 8 0;1=0
P 1.26 3.18 6 P 0 8 0;1=0
P 1.295 3.28 6 P 0 8 0;1=0
P 1.075 3.02 6 P 0 8 0;1=0
P 1.125 3.02 6 P 0 8 0;1=0
P 1.073 3.825 4 P 0 8 0;1=9
P 0.703 3.575 4 P 0 8 0;1=9
P 0.35238002 3.4315 7 P 0 8 0;1=6
P 0.33466004 3.4008 7 P 0 8 0;1=6
P 0.735 3.575 4 P 0 8 0;1=9
P 1.105 3.825 4 P 0 8 0;1=9
P 0.38781998 3.4315 7 P 0 8 0;1=6
P 0.29921998 3.4008 7 P 0 8 0;1=6
P 0.995 3.7 4 P 0 8 0;1=3
P 4.285 3.46 6 P 0 8 0;1=2
P 2.15 3.438 6 P 0 8 0;1=0
P 2.05 3.538 6 P 0 8 0;1=0
P 2.05 3.488 6 P 0 8 0;1=0
P 1.29 3.215 6 P 0 8 0;1=2
P 1.0541 3.185 6 P 0 8 0;1=0
P 1.3 3.49663996 6 P 0 8 0;1=2
P 1.04018996 3.47425 6 P 0 8 0;1=2
P 4.205 3.66 6 P 0 8 0;1=0
P 0.975 3.41 6 P 0 8 0;1=2
P 4.225 3.545 6 P 0 8 0;1=0
P 1.015 3.41 6 P 0 8 0;1=2
P 3.95 3.6 6 P 0 8 0;1=0
P 0.835 3.6 6 P 0 8 0;1=2
P 3.95 3.7 6 P 0 8 0;1=0
P 0.915 3.595 6 P 0 8 0;1=2
P 4.1184 3.5362 6 P 0 8 0;1=2
P 4.085 3.11 6 P 0 8 0;1=0
P 4.51 3.065 6 P 0 8 0;1=2
P 4.33381998 3.60466004 6 P 0 8 0;1=0
P 4.34 3.28 6 P 0 8 0;1=2
P 4.335 3.665 6 P 0 8 0;1=0
P 4.09 3.71338996 6 P 0 8 0;1=0
P 3.38 1.025 6 P 0 8 0;1=2
P 4.585 0.865 6 P 0 8 0;1=0
P 0.62 3.235 6 P 0 8 0;1=2
P 3.925 3.239 6 P 0 8 0;1=0
P 0.825 3.39 6 P 0 8 0;1=2
P 0.795 3.4179 6 P 0 8 0;1=2
P 3.795 3.758 6 P 0 8 0;1=0
P 3.62 1.28 6 P 0 8 0;1=2
P 5.195 0.755 6 P 0 8 0;1=0
P 4.96 0.85 6 P 0 8 0;1=2
P 0.66 3.185 6 P 0 8 0;1=2
P 3.62 1.235 6 P 0 8 0;1=2
P 5.195 0.815 6 P 0 8 0;1=0
P 4.937 0.79161004 6 P 0 8 0;1=2
P 0.66 3.235 6 P 0 8 0;1=2
P 4.205 3.81 6 P 0 8 0;1=2
P 5.814 2.821 5 P 0 8 0;1=7
P 4.19 3.735 6 P 0 8 0;1=2
P 5.814 2.721 5 P 0 8 0;1=7
P 3.895 3.7 6 P 0 8 0;1=2
P 5.815 3.021 5 P 0 8 0;1=7
P 4.135 3.735 6 P 0 8 0;1=2
P 5.814 2.621 5 P 0 8 0;1=7
P 2.3 3.475 6 P 0 8 0;1=2
P 5.045 3.405 6 P 0 8 0;1=2
P 6.33 2.67 5 P 0 8 0;1=7
P 1.35 3.12 6 P 0 8 0;1=2
P 2.255 3.475 6 P 0 8 0;1=2
P 5.09 3.405 6 P 0 8 0;1=2
P 6.33 2.865 6 P 0 8 0;1=0
P 1.46 3.34 6 P 0 8 0;1=2
P 4.575 2.235 6 P 0 8 0;1=2
P 4.50185 1.94185 4 P 0 8 0;1=1
P 4.705 0.825 6 P 0 8 0;1=0
P 4.575 2.275 6 P 0 8 0;1=2
P 4.38373996 1.98121998 4 P 0 8 0;1=1
P 4.755 0.825 6 P 0 8 0;1=0
P 1.26 0.72 6 P 0 8 0;1=0
P 4.6987 1.82373996 4 P 0 8 0;1=1
P 0.842 0.75 6 P 0 8 0;1=0
P 4.73806998 1.82373996 4 P 0 8 0;1=1
P 4.10816004 1.90248002 4 P 0 8 0;1=5
P 3.73648996 1.85735 6 P 0 8 0;1=2
P 4.10816004 1.82373996 4 P 0 8 0;1=1
P 4.345 3.02 6 P 0 8 0;1=2
P 4.075 3.005 6 P 0 8 0;1=2
P 3.925 3.291 6 P 0 8 0;1=0
P 4.14753002 1.82373996 4 P 0 8 0;1=1
P 4.39 3.02 6 P 0 8 0;1=2
P 4.13 3.005 6 P 0 8 0;1=2
P 3.795 3.81 6 P 0 8 0;1=0
P 4.615 3.11 6 P 0 8 0;1=2
P 4.6987 1.90248002 4 P 0 8 0;1=1
P 4.4 3.325 6 P 0 8 0;1=0
P 4.615 2.68408996 6 P 0 8 0;1=2
P 4.15 2.468 6 P 0 8 0;1=2
P 6.22 1.415 6 P 0 8 0;1=0
P 4.685 2.7 6 P 0 8 0;1=2
P 4.209 2.468 6 P 0 8 0;1=2
P 4.34436998 2.1387 4 P 0 8 0;1=1
P 6.22 1.516 6 P 0 8 0;1=0
P 4.975 2.26 6 P 0 8 0;1=2
P 4.093 2.468 6 P 0 8 0;1=2
P 6.22 1.62 6 P 0 8 0;1=0
P 4.925 2.26 6 P 0 8 0;1=0
P 4.037 2.468 6 P 0 8 0;1=2
P 6.22 1.815 6 P 0 8 0;1=0
P 5.92 1.41 6 P 0 8 0;1=0
P 5.09 2.155 6 P 0 8 0;1=2
P 3.801 2.468 6 P 0 8 0;1=2
P 4.10816004 2.09933002 4 P 0 8 0;1=1
P 5.92 1.515 6 P 0 8 0;1=0
P 5.135 2.155 6 P 0 8 0;1=2
P 3.86 2.468 6 P 0 8 0;1=2
P 4.14753002 2.09933002 4 P 0 8 0;1=1
P 5.92 1.63 6 P 0 8 0;1=0
P 5.115 2.065 6 P 0 8 0;1=2
P 3.919 2.468 6 P 0 8 0;1=2
P 5.92 1.73 6 P 0 8 0;1=0
P 5.13 2.105 6 P 0 8 0;1=2
P 3.978 2.468 6 P 0 8 0;1=2
P 4.685 2.645 6 P 0 8 0;1=2
P 4.1 3.38 6 P 0 8 0;1=0
P 4.53 2.5 6 P 0 8 0;1=2
P 3.9 3.385 6 P 0 8 0;1=0
P 4.485 3.115 6 P 0 8 0;1=0
P 4.575 2.374 6 P 0 8 0;1=2
P 4.485 2.5 6 P 0 8 0;1=2
P 4.29441998 3.10075 6 P 0 8 0;1=0
P 4.61 2.345 6 P 0 8 0;1=2
P 4.54 3.125 6 P 0 8 0;1=0
P 4.085 3.21998002 6 P 0 8 0;1=0
P 4.35 2.505 6 P 0 8 0;1=2
P 5.365 0.79 6 P 0 8 0;1=0
P 5.365 0.845 6 P 0 8 0;1=0
P 4.0661 3.5341 6 P 0 8 0;1=0
P 3.83 3.466 5 P 0 8 0;1=7
P 4.35143002 3.06643002 6 P 0 8 0;1=2
P 3.7 3.325 6 P 0 8 0;1=0
P 3.5825 3.4005 3 P 0 8 0;1=4
P 4.33 3.1432 6 P 0 8 0;1=2
P 3.83 3.235 6 P 0 8 0;1=0
P 4.085 3.165 6 P 0 8 0;1=2
P 3.415 3.335 3 P 0 8 0;1=4
P 0.74 1.3 6 P 0 8 0;1=2
P 1.26 0.62 5 P 0 8 0;1=7
P 0.785 0.8225 6 P 0 8 0;1=2
P 0.695 1.3 6 P 0 8 0;1=2
P 1.26 0.67 5 P 0 8 0;1=7
P 0.76321004 0.783 6 P 0 8 0;1=2
P 3.32 3.015 4 P 0 8 0;1=3
P 3.24 3.01 4 P 0 8 0;1=3
P 0.606 1.57 6 P 0 8 0;1=0
P 0.835 1.73 6 P 0 8 0;1=0
P 0.355 3.27 6 P 0 8 0;1=0
P 0.28 3.27 6 P 0 8 0;1=0
P 0.13 3.187 6 P 0 8 0;1=0
P 0.69023002 1.98523996 6 P 0 8 0;1=2
P 0.125 2.195 6 P 0 8 0;1=0
P 0.69 1.93 6 P 0 8 0;1=2
P 0.125 2.145 6 P 0 8 0;1=0
P 0.69 1.875 6 P 0 8 0;1=2
P 0.125 2.045 6 P 0 8 0;1=0
P 0.13 2.73326998 6 P 0 8 0;1=0
P 0.287 2.743 6 P 0 8 0;1=0
P 0.125 2.615 6 P 0 8 0;1=0
P 0.735 1.19 6 P 0 8 0;1=2
P 0.125 1.06 6 P 0 8 0;1=0
P 0.68 1.19 6 P 0 8 0;1=2
P 0.125 1.01 6 P 0 8 0;1=0
P 0.675 1.145 6 P 0 8 0;1=2
P 0.125 0.91 6 P 0 8 0;1=0
P 0.125 1.62 6 P 0 8 0;1=0
P 0.13 1.57 6 P 0 8 0;1=0
P 0.1362 1.4872 6 P 0 8 0;1=0
P 2.937 3.173 6 P 0 8 0;1=0
P 3.01 3.17 6 P 0 8 0;1=2
P 0.896 2.489 3 P 0 8 0;1=4
P 4.31168996 4.01168996 3 P 0 8 0;1=4
P 4.319 3.922 3 P 0 8 0;1=4
P 4.5 4.115 6 P 0 8 0;1=0
P 1.315 2.905 5 P 0 8 0;1=8
P 2.932 3.295 5 P 0 8 0;1=8
P 0.915 1.4 6 P 0 8 0;1=2
P 1.42 0.69535 5 P 0 8 0;1=7
P 4.5 4.165 6 P 0 8 0;1=0
P 1.36 2.905 5 P 0 8 0;1=8
P 2.896 3.301 5 P 0 8 0;1=8
P 0.965 1.4 6 P 0 8 0;1=2
P 1.4207 0.779 5 P 0 8 0;1=7
P 4.65933002 2.02058996 4 P 0 8 0;1=5
P 4.33 3.535 6 P 0 8 0;1=2
P 4.44 4.065 3 P 0 8 0;1=4
P 4.61996004 2.05996004 4 P 0 8 0;1=1
P 4.395 3.415 5 P 0 8 0;1=8
P 4.44 4.115 3 P 0 8 0;1=4
P 4.61996004 2.09933002 4 P 0 8 0;1=1
P 4.425 3.36088996 5 P 0 8 0;1=8
P 0.638 2.74 5 P 0 8 0;1=8
P 0.825 2.305 3 P 0 8 0;1=4
P 0.755 2.825 5 P 0 8 0;1=8
P 0.795 2.345 3 P 0 8 0;1=4
P 5.97613002 4.13778996 6 P 0 8 0;1=0
P 5.90748002 4.18725 6 P 0 8 0;1=0
P 4.06878996 2.02058996 4 P 0 8 0;1=1
P 0.905 1.935 6 P 0 8 0;1=0
P 3.99005 2.05996004 4 P 0 8 0;1=1
P 0.945 1.97 6 P 0 8 0;1=0
P 4.02941998 2.05996004 4 P 0 8 0;1=1
P 0.905 1.885 6 P 0 8 0;1=0
P 0.63 2.15 6 P 0 8 0;1=2
P 3.95066998 2.02058996 4 P 0 8 0;1=1
P 0.985 2.185 6 P 0 8 0;1=0
P 0.287 2.62508002 6 P 0 8 0;1=2
P 0.43 2.555 6 P 0 8 0;1=0
P 3.95066998 1.98121998 4 P 0 8 0;1=1
P 0.63 2.105 6 P 0 8 0;1=2
P 0.99 2.015 6 P 0 8 0;1=2
P 0.242 2.62508002 6 P 0 8 0;1=0
P 3.99005 1.98121998 4 P 0 8 0;1=1
P 0.63 2.06 6 P 0 8 0;1=2
P 0.99 1.975 6 P 0 8 0;1=2
P 4.02941998 1.82373996 4 P 0 8 0;1=1
P 0.935 1.3 6 P 0 8 0;1=0
P 3.95066998 1.90248002 4 P 0 8 0;1=1
P 0.87 1.255 6 P 0 8 0;1=0
P 3.95066998 1.86311004 4 P 0 8 0;1=1
P 0.935 1.25 6 P 0 8 0;1=0
P 4.06878996 1.94185 4 P 0 8 0;1=1
P 0.92 1.73 6 P 0 8 0;1=0
P 0.281 1.48798002 6 P 0 8 0;1=2
P 4.06878996 1.86311004 4 P 0 8 0;1=1
P 0.985 1.655 6 P 0 8 0;1=0
P 0.371 1.48798002 6 P 0 8 0;1=2
P 4.06878996 1.82373996 4 P 0 8 0;1=1
P 0.985 1.59 6 P 0 8 0;1=0
P 0.236 1.48798002 6 P 0 8 0;1=2
P 0.345 3.09 6 P 0 8 0;1=2
P 3.84091004 2.00091004 6 P 0 8 0;1=0
P 0.99 1.885 6 P 0 8 0;1=2
P 0.395 3.09 6 P 0 8 0;1=2
P 3.87193002 2.09933002 4 P 0 8 0;1=5
P 0.99 2.065 6 P 0 8 0;1=2
P 0.445 3.09 6 P 0 8 0;1=0
P 3.9113 2.09933002 4 P 0 8 0;1=1
P 0.975 2.14 6 P 0 8 0;1=2
P 0.53 2.005 6 P 0 8 0;1=0
P 0.552 2.535 6 P 0 8 0;1=0
P 0.455 1.825 6 P 0 8 0;1=0
P 0.16038996 1.85433002 8 P 0 8 0;1=10
P 0.46 2.195 6 P 0 8 0;1=0
P 0.16038996 2.4252 8 P 0 8 0;1=10
P 0.445 0.735 6 P 0 8 0;1=0
P 0.16038996 0.7126 8 P 0 8 0;1=10
P 0.455 1.0439 6 P 0 8 0;1=0
P 0.16038996 1.28346004 8 P 0 8 0;1=10
P 0.535 1.835 6 P 0 8 0;1=0
P 0.532 2.40186998 6 P 0 8 0;1=0
P 0.505 0.60228002 6 P 0 8 0;1=0
P 0.5374 1.26 6 P 0 8 0;1=0
P 0.48 2.005 6 P 0 8 0;1=0
P 0.485 2.525 6 P 0 8 0;1=0
P 0.515 0.835 6 P 0 8 0;1=0
P 0.475 1.405 6 P 0 8 0;1=0
P 6.335 0.965 6 P 0 8 0;1=0
P 6.335 1.02 6 P 0 8 0;1=0
P 6.335 1.08 6 P 0 8 0;1=0
P 2.085 3.017 5 P 0 8 0;1=7
P 2.135 3.017 5 P 0 8 0;1=7
P 2.185 3.017 5 P 0 8 0;1=7
P 6.0085 1.1235 6 P 0 8 0;1=0
P 2.22 3.3 5 P 0 8 0;1=7
P 5.8 1.048 4 P 0 8 0;1=3
P 4.34436998 2.02058996 4 P 0 8 0;1=1
P 5.285 2.99 5 P 0 8 0;1=8
P 3.125 3.075 6 P 0 8 0;1=2
P 4.34436998 2.17806998 4 P 0 8 0;1=1
P 2.017 3.279 4 P 0 8 0;1=3
P 0.636 2.915 4 P 0 8 0;1=3
P 4.38373996 2.17806998 4 P 0 8 0;1=1
P 2.97 3.105 6 P 0 8 0;1=0
P 5.91 2.785 6 P 0 8 0;1=0
P 5.91 2.615 5 P 0 8 0;1=7
P 5.91 2.915 6 P 0 8 0;1=0
P 5.91 2.715 6 P 0 8 0;1=0
P 0.54 2.135 6 P 0 8 0;1=2
P 0.67 1.09 6 P 0 8 0;1=0
P 4.61996004 1.66626998 4 P 0 8 0;1=1
P 0.45 2.13 6 P 0 8 0;1=2
P 4.6987 2.09933002 4 P 0 8 0;1=1
P 0.965 2.355 6 P 0 8 0;1=0
P 4.5806 1.70563996 4 P 0 8 0;1=1
P 0.735 1.125 6 P 0 8 0;1=0
P 0.48231998 2.6453 6 P 0 8 0;1=2
P 3.755 3.505 5 P 0 8 0;1=8
P 4.6987 2.1387 4 P 0 8 0;1=1
P 0.525 2.78 6 P 0 8 0;1=2
P 4.6 0.76 6 P 0 8 0;1=2
P 4.61996004 1.78436998 4 P 0 8 0;1=1
P 0.905 1.05 6 P 0 8 0;1=2
P 4.175 0.75 6 P 0 8 0;1=2
P 0.51765 0.966 3 P 0 8 0;1=4
P 2.078 0.8301 6 P 0 8 0;1=2
P 0.46 0.82 3 P 0 8 0;1=4
P 4.65933002 1.78436998 4 P 0 8 0;1=1
P 0.5413 1.525 6 P 0 8 0;1=0
P 4.61996004 1.70563996 4 P 0 8 0;1=1
P 0.625 1.005 6 P 0 8 0;1=2
P 4.65933002 1.70563996 4 P 0 8 0;1=1
P 0.935 1.105 6 P 0 8 0;1=0
P 0.4839 1.28311998 6 P 0 8 0;1=2
P 1.128 0.666 3 P 0 8 0;1=4
P 5.97613002 4.27558002 6 P 0 8 0;1=0
P 4.14753002 1.86311004 4 P 0 8 0;1=1
P 0.945 1.63 6 P 0 8 0;1=2
P 0.635 0.845 4 P 0 8 0;1=3
P 4.1869 1.86311004 4 P 0 8 0;1=1
P 0.975 1.72 6 P 0 8 0;1=2
P 0.644 0.7 4 P 0 8 0;1=3
P 0.555 0.59 6 P 0 8 0;1=0
P 3.935 3.91 5 P 0 8 0;1=7
P 0.835 1.885 6 P 0 8 0;1=2
P 3.885 3.91 5 P 0 8 0;1=7
P 0.835 1.93 6 P 0 8 0;1=2
P 3.985 3.91 5 P 0 8 0;1=7
P 0.835 1.78 6 P 0 8 0;1=2
P 0.645 1.295 4 P 0 8 0;1=3
P 4.1869 1.90248002 4 P 0 8 0;1=1
P 0.955 1.92 6 P 0 8 0;1=2
P 0.565 1.13 4 P 0 8 0;1=3
P 4.14753002 1.90248002 4 P 0 8 0;1=1
P 0.885 1.49 6 P 0 8 0;1=0
P 0.99 1.755 6 P 0 8 0;1=2
P 3.935 4 5 P 0 8 0;1=8
P 0.332 2.62508002 6 P 0 8 0;1=0
P 3.885 4 5 P 0 8 0;1=8
P 0.405 2.62 6 P 0 8 0;1=0
P 3.985 4 5 P 0 8 0;1=8
P 0.19 2.625 6 P 0 8 0;1=0
P 0.62 1.995 4 P 0 8 0;1=3
P 4.34436998 1.82373996 4 P 0 8 0;1=1
P 0.75 1.417 6 P 0 8 0;1=2
P 4.26563996 1.82373996 4 P 0 8 0;1=1
P 0.952 1.51 6 P 0 8 0;1=0
P 0.545 1.71 4 P 0 8 0;1=3
P 0.415 1.275 6 P 0 8 0;1=2
P 0.87 1.2 6 P 0 8 0;1=2
P 0.7558 4.19003996 5 P 0 8 0;1=7
P 3.98 4.185 5 P 0 8 0;1=8
P 0.465 1.33 6 P 0 8 0;1=2
P 0.87 1.3 6 P 0 8 0;1=2
P 0.705 4.19 5 P 0 8 0;1=7
P 4.03 4.185 5 P 0 8 0;1=8
P 0.41408996 1.32591004 6 P 0 8 0;1=2
P 0.89 1.105 6 P 0 8 0;1=2
P 0.805 4.205 6 P 0 8 0;1=0
P 3.93 4.185 5 P 0 8 0;1=8
P 0.647 2.517 4 P 0 8 0;1=3
P 4.22626998 1.82373996 4 P 0 8 0;1=1
P 0.939 1.552 6 P 0 8 0;1=2
P 0.575 2.265 4 P 0 8 0;1=3
P 4.22626998 1.86311004 4 P 0 8 0;1=1
P 0.957 2.275 6 P 0 8 0;1=0
P 4.168 4.24 5 P 0 8 0;1=8
P 0.855 4.205 5 P 0 8 0;1=8
P 0.15 2.79 6 P 0 8 0;1=0
P 0.326 1.487 6 P 0 8 0;1=2
P 0.09 2.86 6 P 0 8 0;1=0
P 0.9 4.205 5 P 0 8 0;1=8
P 4.22336998 4.24 5 P 0 8 0;1=8
P 0.416 1.48798002 6 P 0 8 0;1=2
P 0.09 2.79 6 P 0 8 0;1=0
P 0.98 4.2 5 P 0 8 0;1=8
P 4.14 4.19 5 P 0 8 0;1=8
P 0.191 1.48798002 6 P 0 8 0;1=2
P 4.10463002 3.83 5 P 0 8 0;1=7
P 0.33 3.145 6 P 0 8 0;1=2
P 4.05463002 3.83 5 P 0 8 0;1=7
P 0.43 3.145 6 P 0 8 0;1=2
P 4.15463002 3.83 5 P 0 8 0;1=7
P 0.18 3.145 6 P 0 8 0;1=2
P 0.869 2.672 6 P 0 8 0;1=2
P 0.871 2.713 3 P 0 8 0;1=4
P 0.686 2.74 5 P 0 8 0;1=8
P 0.64248002 2.58 6 P 0 8 0;1=2
P 0.736 2.525 5 P 0 8 0;1=8
P 0.714 2.329 6 P 0 8 0;1=2
P 3.429 2.468 3 P 0 8 0;1=4
P 3.51 2.33243002 6 P 0 8 0;1=2
P 3.278 2.468 3 P 0 8 0;1=4
P 3.243 2.547 3 P 0 8 0;1=4
P 3.385 2.135 4 P 0 8 0;1=3
P 3.24 2.36 3 P 0 8 0;1=4
P 3.285 2.38645 3 P 0 8 0;1=4
P 0.832 2.603 6 P 0 8 0;1=0
P 0.77963996 2.601 3 P 0 8 0;1=4
P 0.695 2.578 6 P 0 8 0;1=0
P 0.72 2.714 3 P 0 8 0;1=4
P 0.825 2.732 3 P 0 8 0;1=4
P 6.01953002 2.18853002 6 P 0 8 0;1=0
P 4.415 2.975 3 P 0 8 0;1=4
P 6.09423996 4.27558002 6 P 0 8 0;1=0
P 0.959 2.789 6 P 0 8 0;1=2
P 0.845 2.18 6 P 0 8 0;1=0
P 5.955 2.39 4 P 0 8 0;1=3
P 5.94153002 2.205 5 P 0 8 0;1=7
P 6.01901998 2.001 5 P 0 8 0;1=7
P 5.87 1.84 4 P 0 8 0;1=3
P 3.4593 2.17 5 P 0 8 0;1=7
P 3.44 2.12 6 P 0 8 0;1=0
P 4.34436998 1.94185 4 P 0 8 0;1=1
P 3.18 2.685 3 P 0 8 0;1=4
P 3.523 1.75 5 P 0 8 0;1=8
P 4.712 1.157 4 P 0 8 0;1=3
P 4.42311004 1.50878996 4 P 0 8 0;1=1
P 4.61996004 1.6269 4 P 0 8 0;1=3
P 4.29 1.235 4 P 0 8 0;1=3
P 4.38373996 1.46941998 4 P 0 8 0;1=1
P 4.15 1.235 4 P 0 8 0;1=3
P 4.34436998 1.50878996 4 P 0 8 0;1=1
P 5.035 1.49 4 P 0 8 0;1=3
P 4.65933002 1.58753002 4 P 0 8 0;1=1
P 4.185 1.17 4 P 0 8 0;1=3
P 4.34436998 1.46941998 4 P 0 8 0;1=1
P 4.816 1.258 4 P 0 8 0;1=3
P 4.665 1.104 4 P 0 8 0;1=3
P 4.38373996 1.3513 4 P 0 8 0;1=1
P 4.91 1.54 4 P 0 8 0;1=3
P 4.768 1.207 4 P 0 8 0;1=3
P 4.42311004 1.46941998 4 P 0 8 0;1=1
P 5.03 1.55 4 P 0 8 0;1=3
P 4.58058996 1.6269 4 P 0 8 0;1=1
P 4.828 1.103 4 P 0 8 0;1=3
P 4.42311004 1.43005 4 P 0 8 0;1=1
P 4.83 1.33 4 P 0 8 0;1=3
P 4.22 1.235 4 P 0 8 0;1=3
P 3.83128002 1.78371998 5 P 0 8 0;1=8
P 6.02558996 4.175 6 P 0 8 0;1=0
P 6.1437 4.175 6 P 0 8 0;1=0
P 3.87193002 1.86311004 4 P 0 8 0;1=1
P 4.14753002 2.05996004 4 P 0 8 0;1=1
P 5.83 2.97 6 P 0 8 0;1=2
P 5.89953002 2.366 5 P 0 8 0;1=7
P 3.61123996 3.49876004 3 P 0 8 0;1=4
P 4.54121998 1.94185 4 P 0 8 0;1=1
P 4.22626998 1.94185 4 P 0 8 0;1=1
P 1.96496998 0.76501998 5 P 0 8 0;1=7
P 4.1869 1.98121998 4 P 0 8 0;1=1
P 3.12 2.565 6 P 0 8 0;1=2
P 3.119 2.299 6 P 0 8 0;1=0
P 4.26563996 1.90248002 4 P 0 8 0;1=1
P 3.385 2.59 6 P 0 8 0;1=0
P 5.155 2.01 6 P 0 8 0;1=2
P 6.025 1.83 6 P 0 8 0;1=0
P 4.1869 2.05996004 4 P 0 8 0;1=1
P 4.34436998 1.90248002 4 P 0 8 0;1=1
P 2.554 2.901 6 P 0 8 0;1=0
P 4.75 1.63 4 P 0 8 0;1=5
P 3.205 1.7 6 P 0 8 0;1=0
P 4.775 1.705 6 P 0 8 0;1=2
P 4.84 1.855 6 P 0 8 0;1=0
P 4.58058996 1.82373996 4 P 0 8 0;1=1
P 4.65933002 1.86311004 4 P 0 8 0;1=1
P 4.815 1.93 6 P 0 8 0;1=0
P 4.885 3.46 6 P 0 8 0;1=2
P 4.61996004 1.86311004 4 P 0 8 0;1=1
P 4.83501004 3.46 6 P 0 8 0;1=0
P 3.125 2.254 6 P 0 8 0;1=2
P 4.26563996 1.86311004 4 P 0 8 0;1=5
P 3.12 2.69 6 P 0 8 0;1=2
P 4.565 3.055 6 P 0 8 0;1=2
P 4.3 3.81 6 P 0 8 0;1=0
P 1.3825 3.7225 5 P 0 8 0;1=8
P 5.905 3.015 5 P 0 8 0;1=7
P 5.41 0.96 4 P 0 8 0;1=3
P 4.85033002 1.74933996 6 P 0 8 0;1=2
P 4.54121998 1.78436998 4 P 0 8 0;1=1
P 5.26 2.955 6 P 0 8 0;1=2
P 3.625 0.92 4 P 0 8 0;1=9
P 6.19961004 2.27673996 4 P 0 8 0;1=9
P 3.657 0.92 4 P 0 8 0;1=9
P 6.19961004 2.24473996 4 P 0 8 0;1=9
P 3.3255 2.1355 6 P 0 8 0;1=0
P 3.35153002 2.17875 6 P 0 8 0;1=2
P 3.44 2.95 3 P 0 8 0;1=4
P 3.27923002 2.21576998 6 P 0 8 0;1=2
P 3.3435 2.82 3 P 0 8 0;1=4
P 4.46 2.94 6 P 0 8 0;1=0
P 4.47 2.83 6 P 0 8 0;1=0
P 5.995 1.165 6 P 0 8 0;1=2
P 3.106 3.26 6 P 0 8 0;1=2
P 3.222 3.385 5 P 0 8 0;1=8
P 3.106 3.35 5 P 0 8 0;1=8
P 1.959 3.325 6 P 0 8 0;1=2
P 3.222 3.205 5 P 0 8 0;1=8
P 3.49 2.955 6 P 0 8 0;1=2
P 3.98 3.365 6 P 0 8 0;1=2
P 3.7 3.37 6 P 0 8 0;1=2
P 3.55 3.37 6 P 0 8 0;1=2
P 4.175 3.37 6 P 0 8 0;1=2
P 3.71 3.26 6 P 0 8 0;1=2
P 3.55 3.28 5 P 0 8 0;1=8
P 3.414 3.235 6 P 0 8 0;1=2
P 3.41 3.04 6 P 0 8 0;1=2
P 3.548 2.856 5 P 0 8 0;1=8
P 3.5768 2.7178 6 P 0 8 0;1=2
P 3.395 2.82 6 P 0 8 0;1=2
P 3.58 2.615 4 P 0 8 0;1=3
P 3.485 2.6 6 P 0 8 0;1=2
P 3.525 2.6 6 P 0 8 0;1=2
P 3.335 2.589 6 P 0 8 0;1=2
P 3.24 2.2075 6 P 0 8 0;1=2
P 4.905 2.1675 6 P 0 8 0;1=2
P 4.85 2.02738996 6 P 0 8 0;1=2
P 4.965 1.975 6 P 0 8 0;1=2
P 3.49128002 1.86628002 6 P 0 8 0;1=2
P 4.65933002 1.66626998 4 P 0 8 0;1=1
P 3.795 2.375 6 P 0 8 0;1=2
P 3.99005 2.02058996 4 P 0 8 0;1=1
P 4.34436998 1.86311004 4 P 0 8 0;1=1
P 4.02941998 1.90248002 4 P 0 8 0;1=1
P 3.855 1.96153996 4 P 0 8 0;1=1
P 3.9113 1.86311004 4 P 0 8 0;1=1
P 4.06878996 1.78436998 4 P 0 8 0;1=1
P 4.1869 1.82373996 4 P 0 8 0;1=1
P 3.86 2.5925 6 P 0 8 0;1=2
P 3.758 2.552 6 P 0 8 0;1=2
P 4.209 2.59 6 P 0 8 0;1=2
P 4.65933002 2.09933002 4 P 0 8 0;1=1
P 4.54121998 2.05996004 4 P 0 8 0;1=1
P 4.50185 2.17806998 4 P 0 8 0;1=1
P 4.46248002 1.90248002 4 P 0 8 0;1=1
P 4.42311004 2.02058996 4 P 0 8 0;1=1
P 4.38373996 2.1387 4 P 0 8 0;1=1
P 4.26563996 1.98121998 4 P 0 8 0;1=1
P 4.22626998 2.09933002 4 P 0 8 0;1=1
P 4.14753002 1.94185 4 P 0 8 0;1=1
P 4.10816004 2.05996004 4 P 0 8 0;1=1
P 4.06878996 2.17806998 4 P 0 8 0;1=1
P 3.95066998 2.1387 4 P 0 8 0;1=1
P 4.6987 1.98121998 4 P 0 8 0;1=1
P 4.58058996 1.94185 4 P 0 8 0;1=1
P 4.73806998 1.86311004 4 P 0 8 0;1=1
P 4.61996004 1.82373996 4 P 0 8 0;1=1
P 4.50185 1.78436998 4 P 0 8 0;1=1
P 4.249 2.929 6 P 0 8 0;1=0
P 4.239 2.785 6 P 0 8 0;1=0
P 4.249 2.843 6 P 0 8 0;1=0
P 4.575 2.5 6 P 0 8 0;1=2
P 4.395 2.5 6 P 0 8 0;1=2
P 4.77 2.39 6 P 0 8 0;1=2
P 4.71 2.39 6 P 0 8 0;1=2
P 4.075 2.25 6 P 0 8 0;1=2
P 3.735 2.47 6 P 0 8 0;1=2
P 5.0395 1.335 6 P 0 8 0;1=2
P 4.97 1.75 6 P 0 8 0;1=0
P 4.96 1.63 6 P 0 8 0;1=2
P 6.22 1.27063002 6 P 0 8 0;1=2
P 3.839 3.846 6 P 0 8 0;1=2
P 4.384 3.824 6 P 0 8 0;1=2
P 4.95 3.46 6 P 0 8 0;1=2
P 5.94003002 1.87 6 P 0 8 0;1=2
P 6.379 1.169 6 P 0 8 0;1=2
P 6.105 1.905 6 P 0 8 0;1=2
P 5.92 1.27063002 6 P 0 8 0;1=2
P 5.88 0.965 6 P 0 8 0;1=2
P 6.47 1.08 6 P 0 8 0;1=2
P 5.19 3.075 6 P 0 8 0;1=2
P 5.375 3.04 6 P 0 8 0;1=2
P 5.41 2.815 6 P 0 8 0;1=2
P 5.544 2.675 6 P 0 8 0;1=2
P 6.1865 2.493 6 P 0 8 0;1=2
P 6.141 2.364 6 P 0 8 0;1=2
P 5.85 2.265 6 P 0 8 0;1=2
P 5.62 2.5487 6 P 0 8 0;1=2
P 5.42 2.9645 6 P 0 8 0;1=2
P 4.645 2.985 6 P 0 8 0;1=2
P 4.61 3.025 6 P 0 8 0;1=2
P 4.43 3.865 5 P 0 8 0;1=8
P 5.221 4.165 6 P 0 8 0;1=2
P 4.32 3.965 5 P 0 8 0;1=8
P 4.535 3.815 6 P 0 8 0;1=2
P 4.509 3.309 6 P 0 8 0;1=2
P 4.235 4.155 6 P 0 8 0;1=2
P 4.505 3.685 6 P 0 8 0;1=2
P 5.975 4.219 6 P 0 8 0;1=2
P 5.84 4.219 6 P 0 8 0;1=2
P 6.145 3.98 6 P 0 8 0;1=2
P 4.655 0.785 6 P 0 8 0;1=2
P 4.635 0.92 6 P 0 8 0;1=2
P 5.249 0.99 6 P 0 8 0;1=2
P 5.53 1.085 6 P 0 8 0;1=2
P 5.33 0.82 6 P 0 8 0;1=2
P 5.265 0.675 6 P 0 8 0;1=2
P 2.964 0.702 6 P 0 8 0;1=2
P 5.515 0.59596998 6 P 0 8 0;1=2
P 2.0477 0.6778 6 P 0 8 0;1=2
P 2.285 0.79 6 P 0 8 0;1=2
P 2.285 0.755 6 P 0 8 0;1=2
P 3.09 1.645 6 P 0 8 0;1=2
P 1.605 0.715 6 P 0 8 0;1=2
P 1.605 0.755 6 P 0 8 0;1=2
P 1.826 2.895 6 P 0 8 0;1=2
P 1.401 3.069 6 P 0 8 0;1=2
P 3.119 2.434 6 P 0 8 0;1=2
P 2.245 3.02 5 P 0 8 0;1=8
P 2.49 2.903 6 P 0 8 0;1=2
P 2.128 2.895 5 P 0 8 0;1=8
P 0.11976004 3.23523996 6 P 0 8 0;1=2
P 0.78 2.915 6 P 0 8 0;1=2
P 0.241 3.109 6 P 0 8 0;1=2
P 0.16 2.975 6 P 0 8 0;1=2
P 0.374 2.829 6 P 0 8 0;1=2
P 0.5459 2.6687 6 P 0 8 0;1=2
P 0.674 2.271 6 P 0 8 0;1=2
P 0.857 2.365 6 P 0 8 0;1=2
P 0.677 2.402 6 P 0 8 0;1=2
P 0.11963002 2.66436998 6 P 0 8 0;1=2
P 0.51451998 2.199 6 P 0 8 0;1=2
P 0.58 2.135 6 P 0 8 0;1=2
P 0.125 2.095 6 P 0 8 0;1=2
P 0.64445 1.68945 6 P 0 8 0;1=2
P 0.884 1.549 6 P 0 8 0;1=2
P 0.883 1.639 5 P 0 8 0;1=8
P 0.514 1.616 6 P 0 8 0;1=2
P 0.605 1.52 6 P 0 8 0;1=2
P 0.11263996 1.52263996 6 P 0 8 0;1=2
P 0.625 1.17 6 P 0 8 0;1=2
P 0.59 0.965 6 P 0 8 0;1=0
P 0.505 1.048 6 P 0 8 0;1=2
P 0.125 0.96 6 P 0 8 0;1=2
P 0.821 0.793 6 P 0 8 0;1=2
P 0.764 0.872 6 P 0 8 0;1=2
P 1.25 0.765 6 P 0 8 0;1=2
P 1.1133 0.5981 6 P 0 8 0;1=2
P 0.86 0.631 6 P 0 8 0;1=2
P 0.601 0.73 6 P 0 8 0;1=2
P 0.596 0.602 6 P 0 8 0;1=2
P 1.5327 0.584 6 P 0 8 0;1=2
P 4.6987 1.54816004 4 P 0 8 0;1=1
P 4.58058996 1.50878996 4 P 0 8 0;1=1
P 4.14753002 1.50878996 4 P 0 8 0;1=1
P 4.73806998 1.43005 4 P 0 8 0;1=1
P 4.61996004 1.39066998 4 P 0 8 0;1=1
P 4.50185 1.3513 4 P 0 8 0;1=1
P 4.46248002 1.46941998 4 P 0 8 0;1=1
P 4.38373996 1.31193002 4 P 0 8 0;1=1
P 4.34436998 1.43005 4 P 0 8 0;1=1
P 4.1869 1.39066998 4 P 0 8 0;1=1
P 4.06878996 1.3513 4 P 0 8 0;1=1
P 3.95066998 1.31193002 4 P 0 8 0;1=1
P 5.039 1.2869 6 P 0 8 0;1=2
P 5.0386 1.2415 6 P 0 8 0;1=2
P 4.625 1.17 6 P 0 8 0;1=2
P 4.485 1.005 6 P 0 8 0;1=2
P 3.69171998 1.02828002 6 P 0 8 0;1=2
P 3.6931 1.095 6 P 0 8 0;1=2
P 6.04 3.98 6 P 0 8 0;1=2
P 5.445 0.795 4 P 0 8 0;1=3
P 5.494 0.816 6 P 0 8 0;1=2
P 5.443 0.871 6 P 0 8 0;1=2
P 5.49 0.78223002 6 P 0 8 0;1=2
P 3.795 4.175 6 P 0 8 0;1=2
P 3.66 3.5085 6 P 0 8 0;1=2
P 3.105 3.21 6 P 0 8 0;1=2
P 5.55 4.02 6 P 0 8 0;1=2
P 5.01 2.635 6 P 0 8 0;1=0
P 5 2.78798996 5 P 0 8 0;1=7
P 5.226 2.762 5 P 0 8 0;1=7
P 3.775 2.235 6 P 0 8 0;1=2
P 3.775 2.265 6 P 0 8 0;1=0
P 3.775 2.21 6 P 0 8 0;1=2
P 3.775 2.185 6 P 0 8 0;1=2
P 4.42311004 1.78436998 4 P 0 8 0;1=1
P 4.46248002 1.70563996 4 P 0 8 0;1=1
P 4.34436998 1.78436998 4 P 0 8 0;1=1
P 4.22626998 1.78436998 4 P 0 8 0;1=1
P 4.22626998 1.66626998 4 P 0 8 0;1=1
P 4.14753002 1.78436998 4 P 0 8 0;1=1
P 4.02941998 1.78436998 4 P 0 8 0;1=1
P 5.765 0.98 4 P 0 8 0;1=3
P 1.385 3.875 5 P 0 8 0;1=7
P 5.31 2.855 6 P 0 8 0;1=2
P 4.608 2.942 6 P 0 8 0;1=2
P 4.25 3.81 6 P 0 8 0;1=2
P 0.99 2.60025 6 P 0 8 0;1=2
P 0.985 2.56661004 6 P 0 8 0;1=2
P 3.555 2.23 6 P 0 8 0;1=2
P 3.555 2.255 6 P 0 8 0;1=2
P 3.555 2.205 6 P 0 8 0;1=2
P 3.555 2.18 6 P 0 8 0;1=2
P 5.345 2.536 4 P 0 8 0;1=3
P 5.22 2.47 6 P 0 8 0;1=2
P 5.254 2.47 6 P 0 8 0;1=2
P 5.239 2.571 6 P 0 8 0;1=2
P 5.243 2.617 6 P 0 8 0;1=2
P 5.224 2.707 5 P 0 8 0;1=7
P 5.005 2.711 5 P 0 8 0;1=7
P 3.793 3.05 3 P 0 8 0;1=4
P 3.96981004 3.04481998 6 P 0 8 0;1=0
P 3.948 2.813 6 P 0 8 0;1=0
P 4.831 2.728 4 P 0 8 0;1=3
P 3.55 1.415 6 P 0 8 0;1=2
P 3.525 1.415 6 P 0 8 0;1=2
P 3.5 1.415 6 P 0 8 0;1=2
P 3.475 1.415 6 P 0 8 0;1=2
P 3.655 2.795 4 P 0 8 0;1=3
P 3.745 2.76 6 P 0 8 0;1=2
P 3.7 2.76 6 P 0 8 0;1=2
P 3.822 2.81 6 P 0 8 0;1=2
P 3.78 2.81 6 P 0 8 0;1=2
P 3.894 2.811 6 P 0 8 0;1=0
P 3.916 3.048 3 P 0 8 0;1=4
P 5.589 2.025 6 P 0 8 0;1=0
P 5.546 2.024 6 P 0 8 0;1=2
P 5.69943002 2.233 6 P 0 8 0;1=0
P 5.48158002 2.28033002 5 P 0 8 0;1=7
P 4.50185 1.66626998 4 P 0 8 0;1=1
P 4.42311004 1.66626998 4 P 0 8 0;1=1
P 4.38373996 1.70563996 4 P 0 8 0;1=1
P 4.26563996 1.70563996 4 P 0 8 0;1=1
P 4.14753002 1.66626998 4 P 0 8 0;1=1
P 4.1869 1.70563996 4 P 0 8 0;1=1
P 4.50185 1.58753002 4 P 0 8 0;1=1
P 4.46248002 1.6269 4 P 0 8 0;1=1
P 4.46248002 1.54816004 4 P 0 8 0;1=1
P 4.38373996 1.54816004 4 P 0 8 0;1=1
P 4.42311004 1.58753002 4 P 0 8 0;1=1
P 4.34436998 1.58753002 4 P 0 8 0;1=1
P 4.26563996 1.54816004 4 P 0 8 0;1=1
P 4.22626998 1.58753002 4 P 0 8 0;1=1
P 4.14753002 1.58753002 4 P 0 8 0;1=1
P 4.1869 1.6269 4 P 0 8 0;1=1
P 4.1869 1.54816004 4 P 0 8 0;1=1
P 5.145 1.57 6 P 0 8 0;1=2
P 5.145 1.54 6 P 0 8 0;1=2
P 5.145 1.44 6 P 0 8 0;1=0
P 5.145 1.48 6 P 0 8 0;1=2
P 5.145 1.51 6 P 0 8 0;1=2
P 5.76 2.465 4 P 0 8 0;1=3
P 4.2136 3.5997 3 P 0 8 0;1=4
P 3.755 3.092 6 P 0 8 0;1=2
P 3.99005 1.66626998 4 P 0 8 0;1=1
P 4.06878996 1.54816004 4 P 0 8 0;1=1
P 4.06878996 1.6269 4 P 0 8 0;1=1
P 4.02941998 1.58753002 4 P 0 8 0;1=1
P 3.99005 1.50878996 4 P 0 8 0;1=1
P 3.679 1.54228002 6 P 0 8 0;1=2
P 3.714 1.543 6 P 0 8 0;1=2
P 3.784 1.543 6 P 0 8 0;1=2
P 3.749 1.54228002 6 P 0 8 0;1=2
P 3.605 1.545 6 P 0 8 0;1=2
P 3.50085 1.543 6 P 0 8 0;1=2
P 3.53481998 1.54156998 6 P 0 8 0;1=2
P 3.57 1.542 6 P 0 8 0;1=2
P 5.4227 1.724 6 P 0 8 0;1=2
P 5.3977 1.724 6 P 0 8 0;1=2
P 5.58 1.615 4 P 0 8 0;1=3
P 5.3977 1.699 6 P 0 8 0;1=2
P 5.3977 1.749 6 P 0 8 0;1=2
P 5.4227 1.699 6 P 0 8 0;1=2
P 5.4352 1.7497 6 P 0 8 0;1=2
P 5.654 2.447 6 P 0 8 0;1=2
P 5.667 2.275 5 P 0 8 0;1=7
P 5.595 2.28 5 P 0 8 0;1=7
P 5.483 2.226 6 P 0 8 0;1=0
P 5.6695 2.2 6 P 0 8 0;1=2
P 5.771 2.279 5 P 0 8 0;1=7
P 5.789 2.366 6 P 0 8 0;1=2
P 5.6 2.4 6 P 0 8 0;1=2
P 5.6 4.01 4 P 0 8 0;1=3
P 5.55568996 3.88051004 3 P 0 8 0;1=4
P 5.765 2.197 6 P 0 8 0;1=0
P 5.71 2.179 6 P 0 8 0;1=2
P 5.41 2.164 6 P 0 8 0;1=0
P 5.458 2.165 6 P 0 8 0;1=2
P 5.465 2.405 6 P 0 8 0;1=2
P 5.53121998 2.27978996 5 P 0 8 0;1=7
P 3.817 0.924 5 P 0 8 0;1=7
P 4.25 0.877 6 P 0 8 0;1=0
P 5.495 0.694 5 P 0 8 0;1=7
P 5.49 0.635 6 P 0 8 0;1=0
P 5.725 0.60301004 5 P 0 8 0;1=7
P 5.686 0.76 5 P 0 8 0;1=7
P 5.7287 0.6757 5 P 0 8 0;1=7
P 5.38558002 4.13778996 6 P 0 8 0;1=0
P 5.485 4.11 6 P 0 8 0;1=0
P 5.725 4.135 6 P 0 8 0;1=0
P 5.6218 4.13778996 6 P 0 8 0;1=0
P 5.323 4.257 5 P 0 8 0;1=7
P 3.83 3.335 3 P 0 8 0;1=4
P 3.415 3.285 3 P 0 8 0;1=4
P 3.83 3.285 3 P 0 8 0;1=4
P 3.415 3.385 3 P 0 8 0;1=4
P 4.83871004 1.98241004 6 P 0 8 0;1=0
P 4.80288002 2.03788002 6 P 0 8 0;1=0
P 4.97 3.41 6 P 0 8 0;1=0
P 4.38373996 1.90248002 4 P 0 8 0;1=1
P 4.81 3.41 6 P 0 8 0;1=2
P 4.42311004 2.09933002 4 P 0 8 0;1=5
P 3.48863002 4.105 6 P 0 8 0;1=0
P 2.987 3.235 5 P 0 8 0;1=8
P 0.7595 1.642 5 P 0 8 0;1=7
P 2.987 3.27 5 P 0 8 0;1=8
P 0.761 1.544 5 P 0 8 0;1=7
P 4.54121998 1.82373996 4 P 0 8 0;1=1
P 4.79246004 1.78463996 6 P 0 8 0;1=0
P 4.54121998 2.17806998 4 P 0 8 0;1=5
P 0.955 1.455 6 P 0 8 0;1=0
P 1.512 0.75191004 6 P 0 8 0;1=2
P 1.8091 0.6339 5 P 0 8 0;1=7
P 1.459 0.752 5 P 0 8 0;1=8
P 0.905 1.445 6 P 0 8 0;1=2
P 2.40508002 0.731 5 P 0 8 0;1=8
P 4.06878996 1.66626998 3 P 0 8 0;1=11
P 2.40508002 0.699 5 P 0 8 0;1=8
P 4.02941998 1.66626998 3 P 0 8 0;1=11
P 4.4085 1.16598996 5 P 0 8 0;1=8
P 4.46248002 1.43005 3 P 0 8 0;1=11
P 4.3765 1.16598996 5 P 0 8 0;1=8
P 4.50185 1.43005 3 P 0 8 0;1=11
P 4.0485 1.16098996 5 P 0 8 0;1=8
P 4.06878996 1.50878996 3 P 0 8 0;1=11
P 4.0165 1.16098996 5 P 0 8 0;1=8
P 4.02941998 1.50878996 3 P 0 8 0;1=11
P 4.82 2.125 4 P 0 8 0;1=3
P 4.38373996 1.78436998 4 P 0 8 0;1=1
P 3.54663996 1.04706998 5 P 0 8 0;1=8
P 4.6987 1.46941998 3 P 0 8 0;1=11
P 3.51463996 1.04706998 5 P 0 8 0;1=8
P 4.73806998 1.46941998 3 P 0 8 0;1=11
P 3.44998996 1.085 5 P 0 8 0;1=8
P 4.73806998 1.39066998 3 P 0 8 0;1=11
P 3.41798996 1.085 5 P 0 8 0;1=8
P 4.73806998 1.3513 3 P 0 8 0;1=11
P 3.445 1.815 6 P 0 8 0;1=2
P 4.58058996 1.90248002 4 P 0 8 0;1=1
P 4.65933002 1.94185 4 P 0 8 0;1=1
P 4.785 3.46 6 P 0 8 0;1=0
P 3.9113 1.70563996 4 P 0 8 0;1=1
P 3.674 1.744 6 P 0 8 0;1=2
P 3.95066998 1.58753002 4 P 0 8 0;1=1
P 3.9113 1.54816004 4 P 0 8 0;1=1
P 3.9113 1.6269 4 P 0 8 0;1=1
P 3.95066998 1.43005 4 P 0 8 0;1=1
P 3.9113 1.46941998 4 P 0 8 0;1=1
P 3.82 1.42 6 P 0 8 0;1=0
P 3.79 1.41 6 P 0 8 0;1=2
P 3.74 1.41 6 P 0 8 0;1=2
P 3.765 1.41 6 P 0 8 0;1=2
P 4.54121998 1.6269 4 P 0 8 0;1=1
P 4.9097 1.385 5 P 0 8 0;1=7
P 4.54121998 1.66626998 4 P 0 8 0;1=1
P 4.84 1.66 6 P 0 8 0;1=0
P 4.81 1.725 6 P 0 8 0;1=0
P 3.375 1.194 5 P 0 8 0;1=8
P 4.5413 1.22166998 5 P 0 8 0;1=8
P 4.61996004 1.31193002 3 P 0 8 0;1=11
P 3.375 1.162 5 P 0 8 0;1=8
P 4.5733 1.22166998 5 P 0 8 0;1=8
P 4.65933002 1.31193002 3 P 0 8 0;1=11
P 5.3 4.065 4 P 0 8 0;1=3
P 4.10816004 1.70563996 4 P 0 8 0;1=1
P 4.365 2.33 6 P 0 8 0;1=2
P 4.38373996 2.02058996 4 P 0 8 0;1=5
P 4.38373996 2.05996004 4 P 0 8 0;1=1
P 4.485 2.375 6 P 0 8 0;1=0
P 4.38373996 2.09933002 4 P 0 8 0;1=1
P 4.54121998 1.58753002 4 P 0 8 0;1=1
P 4.9097 1.335 5 P 0 8 0;1=7
P 4.26563996 1.78436998 4 P 0 8 0;1=1
P 4.365 2.375 6 P 0 8 0;1=0
P 3.465 1.74 6 P 0 8 0;1=2
P 3.44 1.03 6 P 0 8 0;1=0
P 6.285 1.895 6 P 0 8 0;1=2
P 6.258 2.15873996 5 P 0 8 0;1=8
P 6.275 2.05373996 6 P 0 8 0;1=2
P 6.335 2.05906004 5 P 0 8 0;1=7
P 1.77 3.98 6 P 0 8 0;1=0
P 1.75 3.945 6 P 0 8 0;1=2
P 1.5315 3.9459 5 P 0 8 0;1=7
P 1.517 4.113 6 P 0 8 0;1=0
P 1.511 3.863 5 P 0 8 0;1=7
P 1.5153 4.063 5 P 0 8 0;1=7
P 1.521 3.993 5 P 0 8 0;1=7
P 1.579 3.874 6 P 0 8 0;1=0
P 1.585 4.052 6 P 0 8 0;1=2
P 1.435 4.18 6 P 0 8 0;1=2
P 1.522 4.163 5 P 0 8 0;1=7
P 1.4 4.01 6 P 0 8 0;1=2
P 5.14 3.74 6 P 0 8 0;1=2
P 5.175 3.74 6 P 0 8 0;1=2
P 5.18 3.825 6 P 0 8 0;1=2
P 5.675 4.03 6 P 0 8 0;1=2
P 1.56 3.29 6 P 0 8 0;1=2
P 1.56 3.25 6 P 0 8 0;1=2
P 3.245 2.955 6 P 0 8 0;1=2
P 3.21 2.955 6 P 0 8 0;1=2
P 3.175 2.955 6 P 0 8 0;1=2
P 2.59 3.445 6 P 0 8 0;1=2
P 2.55 3.445 6 P 0 8 0;1=2
P 2.51 3.445 6 P 0 8 0;1=2
P 2.47 3.445 6 P 0 8 0;1=2
P 2.2 3.96 6 P 0 8 0;1=2
P 2.25 3.96 4 P 0 8 0;1=3
P 1.351 4.126 6 P 0 8 0;1=2
P 2.165 3.96 6 P 0 8 0;1=2
P 2.155 3.925 6 P 0 8 0;1=2
P 2.19 3.925 6 P 0 8 0;1=2
P 3.23 4.015 6 P 0 8 0;1=0
P 3.2 3.985 6 P 0 8 0;1=2
P 5.9065 2.4568 6 P 0 8 0;1=2
P 3.745 4.185 4 P 0 8 0;1=3
P 3.47 3.912 6 P 0 8 0;1=0
P 3.69 4.135 4 P 0 8 0;1=3
P 3.48278996 4.05678002 6 P 0 8 0;1=2
P 3.476 3.988 6 P 0 8 0;1=0
P 3.437 4.099 6 P 0 8 0;1=0
P 3.598 3.977 6 P 0 8 0;1=2
P 3.477 3.816 6 P 0 8 0;1=0
P 3.405 3.916 6 P 0 8 0;1=2
P 5.68326004 3.712 6 P 0 8 0;1=0
P 5.686 3.807 6 P 0 8 0;1=0
P 5.50643002 4.009 3 P 0 8 0;1=4
P 5.686 3.76 6 P 0 8 0;1=0
P 5.675 3.865 6 P 0 8 0;1=0
P 5.718 3.965 4 P 0 8 0;1=3
P 6.05315 3.67518996 9 P 0 8 0;1=12
P 6.05315 3.50983996 9 P 0 8 0;1=13
P 6.05315 3.34448996 9 P 0 8 0;1=13
P 0.865 3.645 6 P 0 8 0;1=2
P 0.905 3.645 6 P 0 8 0;1=2
P 0.945 3.645 6 P 0 8 0;1=2
P 0.945 3.69 6 P 0 8 0;1=2
P 0.945 3.73 6 P 0 8 0;1=2
P 0.945 3.765 6 P 0 8 0;1=2
P 0.865 3.845 6 P 0 8 0;1=2
P 0.905 3.845 6 P 0 8 0;1=2
P 0.94 3.845 6 P 0 8 0;1=2
P 0.945 3.805 6 P 0 8 0;1=0
P 0.828 3.846 6 P 0 8 0;1=2
P 0.828 3.646 6 P 0 8 0;1=2
P 5.66 3.47 4 P 0 8 0;1=3
P 5.68 3.567 3 P 0 8 0;1=4
P 5.406 3.863 6 P 0 8 0;1=0
P 3.46 4.16 6 P 0 8 0;1=2
P 3.495 4.15 6 P 0 8 0;1=2
P 3.5 4.195 6 P 0 8 0;1=2
P 3.53 4.165 6 P 0 8 0;1=2
P 5.769 4.031 6 P 0 8 0;1=2
P 5.644 3.967 6 P 0 8 0;1=0
P 5.803 3.907 6 P 0 8 0;1=2
P 1.45 3.78 6 P 0 8 0;1=2
P 1.485 3.76 5 P 0 8 0;1=7
P 1.485 3.8 6 P 0 8 0;1=2
P 5.406 2.346 4 P 0 8 0;1=3
P 5.375 2.32 6 P 0 8 0;1=2
P 5.34 2.315 6 P 0 8 0;1=2
P 5.43 3.6 6 P 0 8 0;1=0
P 5.433 3.651 6 P 0 8 0;1=2
P 5.43 3.7 6 P 0 8 0;1=2
P 5.39 3.6 6 P 0 8 0;1=2
P 5.393 3.651 6 P 0 8 0;1=2
P 5.39 3.7 6 P 0 8 0;1=2
P 1.6055 4.134 6 P 0 8 0;1=2
P 1.60581998 4.1 6 P 0 8 0;1=2
P 1.606 4.174 5 P 0 8 0;1=7
P 1.636 3.786 6 P 0 8 0;1=2
P 1.591 3.826 6 P 0 8 0;1=2
P 1.633 3.829 5 P 0 8 0;1=7
P 3.408 4.152 6 P 0 8 0;1=2
P 3.363 4.192 6 P 0 8 0;1=2
P 3.363 4.152 6 P 0 8 0;1=2
P 3.363 4.232 6 P 0 8 0;1=0
P 3.393 3.877 6 P 0 8 0;1=2
P 3.393 3.84 6 P 0 8 0;1=2
P 3.392 3.803 6 P 0 8 0;1=2
P 3.607 4.062 6 P 0 8 0;1=2
P 1.352 4.084 6 P 0 8 0;1=0
P 1.95 0.5455 5 P 0 8 0;1=7
P 5.681 3.617 6 P 0 8 0;1=0
P 5.681 3.664 6 P 0 8 0;1=0
P 5.40318002 2.70436004 5 P 0 8 0;1=7
P 0.55921998 1.40543002 6 P 0 8 0;1=0
P 0.57 0.835 6 P 0 8 0;1=0
P 3.584 1.827 5 P 0 8 0;1=7
P 1.535 3.905 5 P 0 8 0;1=8
P 1.98135 0.365 5 P 0 8 0;1=8
P 1.7317 0.7084 6 P 0 8 0;1=0
P 1.91535 0.412 5 P 0 8 0;1=8
P 1.8039 0.7072 5 P 0 8 0;1=7
P 3.2271 1.90298996 4 P 0 8 0;1=9
P 3.45301004 1.89898996 4 P 0 8 0;1=9
P 3.2591 1.90298996 4 P 0 8 0;1=9
P 3.45301004 1.93098996 4 P 0 8 0;1=9
P 1.26066998 2.64043002 10 P 0 8 0;1=14
P 5.035 3.945 6 P 0 8 0;1=0
P 5.075 3.945 6 P 0 8 0;1=2
P 2.97771998 1.88693996 6 P 0 8 0;1=2
P 3.00995 1.87611004 6 P 0 8 0;1=2
P 2.86066998 2.64043002 10 P 0 8 0;1=14
P 2.105 0.305 5 P 0 8 0;1=8
P 2.235 0.5825 6 P 0 8 0;1=2
P 3.405 0.635 6 P 0 8 0;1=2
P 5.295 0.605 6 P 0 8 0;1=0
P 5.91 4.04 6 P 0 8 0;1=0
P 2.135 0.54 6 P 0 8 0;1=2
P 5.215 0.6 6 P 0 8 0;1=0
P 6.025 4.04 6 P 0 8 0;1=0
P 3.36 0.6106 6 P 0 8 0;1=2
P 0.96 2.41 6 P 0 8 0;1=2
P 0.68 2.355 6 P 0 8 0;1=2
P 2.38 3.45 6 P 0 8 0;1=2
P 1.41 3.795 6 P 0 8 0;1=2
P 3.445 3.613 6 P 0 8 0;1=2
P 3.365 3.613 6 P 0 8 0;1=0
P 3.25 3.63 6 P 0 8 0;1=2
P 3.325 3.613 6 P 0 8 0;1=2
P 3.405 3.613 6 P 0 8 0;1=2
P 3.48418002 3.613 6 P 0 8 0;1=2
P 3.645 4.135 6 P 0 8 0;1=2
P 3.655 3.059 6 P 0 8 0;1=2
P 3.614 3.099 6 P 0 8 0;1=2
P 3.614 3.058 6 P 0 8 0;1=2
P 3.614 3.015 6 P 0 8 0;1=2
P 5.236 2.811 6 P 0 8 0;1=2
P 4.3305 2.914 6 P 0 8 0;1=15
P 4.3815 2.838 6 P 0 8 0;1=15
P 4.29 2.74 4 P 0 8 0;1=3
P 4.456 2.783 6 P 0 8 0;1=2
P 4.355 2.745 6 P 0 8 0;1=2
P 4.346 2.783 6 P 0 8 0;1=2
P 4.4 2.785 6 P 0 8 0;1=2
P 4 2.655 6 P 0 8 0;1=2
P 5.022 2.407 6 P 0 8 0;1=2
P 4.923 2.408 6 P 0 8 0;1=2
P 4.972 2.406 6 P 0 8 0;1=2
P 4.971 2.447 6 P 0 8 0;1=2
P 5.2871 2.275 6 P 0 8 0;1=2
P 5.62533002 1.02001004 6 P 0 8 0;1=2
P 5.65933002 1.02 6 P 0 8 0;1=2
P 3.804 0.816 5 P 0 8 0;1=8
P 4.23 0.7295 6 P 0 8 0;1=2
P 2.31 0.715 6 P 0 8 0;1=2
P 2.31 0.68 6 P 0 8 0;1=2
P 2.595 0.547 6 P 0 8 0;1=2
P 1.87598002 0.289 5 P 0 8 0;1=8
P 1.86 0.33 5 P 0 8 0;1=8
P 1.895 0.33 5 P 0 8 0;1=8
P 1.87598002 0.369 5 P 0 8 0;1=8
P 0.705 3.82 6 P 0 8 0;1=2
P 0.665 3.82 6 P 0 8 0;1=2
P 0.625 3.82 6 P 0 8 0;1=2
P 0.625 3.78 6 P 0 8 0;1=0
P 0.625 3.73 6 P 0 8 0;1=0
P 0.66 3.65 6 P 0 8 0;1=2
P 0.695 3.65 6 P 0 8 0;1=2
P 0.73 3.65 6 P 0 8 0;1=2
P 0.625 3.69 6 P 0 8 0;1=2
P 0.625 3.65 6 P 0 8 0;1=2
P 3.51 2.37 6 P 0 8 0;1=2
P 0.29 2.915 6 P 0 8 0;1=0
P 0.28 2.965 6 P 0 8 0;1=0
P 0.285 3.02 6 P 0 8 0;1=0
P 2.977 3.351 3 P 0 8 0;1=4
P 3.36525 3.255 3 P 0 8 0;1=4
P 3.36525 3.205 3 P 0 8 0;1=4
P 1.8062 0.7789 5 P 0 8 0;1=7
P 3.073 0.613 5 P 0 8 0;1=7
P 2.54526998 0.339 5 P 0 8 0;1=8
P 2.527 0.44 3 P 0 8 0;1=4
P 5.73991004 4.27558002 6 P 0 8 0;1=0
P 5.38558002 4.27558002 6 P 0 8 0;1=0
P 5.50368996 4.27558002 6 P 0 8 0;1=0
P 5.6218 4.27558002 6 P 0 8 0;1=0
P 5.875 1.9 6 P 0 8 0;1=0
P 3.865 3.65 6 P 0 8 0;1=2
P 6.06901998 1.86 6 P 0 8 0;1=0
P 3.81 3.65 6 P 0 8 0;1=2
P 5.97 1.999 5 P 0 8 0;1=7
P 2.86066998 1.04042992 18 P 0 8 0;1=14
P 5.9645 2.1035 6 P 0 8 0;1=15
P 6.0155 2.0845 6 P 0 8 0;1=15
P 0.43705 3.51576004 16 P 0 8 0;1=16
P 0.43705 3.31655 16 P 0 8 0;1=16
P 0.24806998 3.47245 16 P 0 8 0;1=16
P 0.24806998 3.35985 16 P 0 8 0;1=16
P 0.24605994 3.4315 20 P 0 8 0;1=6
P 0.4587 3.4315 20 P 0 8 0;1=6
P 0.44097992 3.4008 20 P 0 8 0;1=6
P 0.22833996 3.4008 20 P 0 8 0;1=6
P 4.94093996 4.12008002 19 P 0 8 0;1=17
P 4.94093996 3.09646004 19 P 0 8 0;1=17
P 2.55906004 4.12008002 19 P 0 8 0;1=17
P 2.55906004 3.09646004 19 P 0 8 0;1=17
P 5.88778996 3.34448996 17 P 0 8 0;1=13
P 5.88778996 3.50983996 17 P 0 8 0;1=13
P 5.88778996 3.67518996 17 P 0 8 0;1=13
P 6.51581998 2.24803996 15 P 0 8 0;1=18
P 6.51581998 1.97243996 14 P 0 8 0;1=19
P 6.40951998 2.20866998 21 P 0 8 0;1=20
P 6.40951998 2.01180994 21 P 0 8 0;1=20
P 0.06038996 1.38345994 22 P 0 8 0;1=21
P 0.26038996 1.38345994 22 P 0 8 0;1=21
P 0.06038996 1.18345994 22 P 0 8 0;1=21
P 0.26038996 1.18345994 22 P 0 8 0;1=21
P 0.06038996 0.8126 22 P 0 8 0;1=21
P 0.26038996 0.8126 22 P 0 8 0;1=21
P 0.06038996 0.6126 22 P 0 8 0;1=21
P 0.26038996 0.6126 22 P 0 8 0;1=21
P 0.06038996 2.5252 22 P 0 8 0;1=21
P 0.26038996 2.5252 22 P 0 8 0;1=21
P 0.06038996 2.3252 22 P 0 8 0;1=21
P 0.26038996 2.3252 22 P 0 8 0;1=21
P 0.06038996 1.95433002 22 P 0 8 0;1=21
P 0.26038996 1.95433002 22 P 0 8 0;1=21
P 0.06038996 1.75433002 22 P 0 8 0;1=21
P 0.26038996 1.75433002 22 P 0 8 0;1=21
P 1.26066998 1.84042992 18 P 0 8 0;1=14
P 5.91901998 2.003 5 P 0 8 0;1=7
P 6.06901998 2.004 5 P 0 8 0;1=7
P 3.49 0.825 5 P 0 8 0;1=7
P 2.65966998 0.93443002 10 P 0 8 0;1=14
P 6.095 2.545 6 P 0 8 0;1=0
P 5.07 1.885 6 P 0 8 0;1=2
P 5.33 0.995 5 P 0 8 0;1=8
P 3.54 0.825 6 P 0 8 0;1=2
P 6.04 2.545 6 P 0 8 0;1=0
P 5.07 1.925 6 P 0 8 0;1=2
P 5.33 0.95 5 P 0 8 0;1=8
P 2.53966998 0.93443002 10 P 0 8 0;1=14
P 2.802 1.987 5 P 0 8 0;1=8
P 2.834 1.987 5 P 0 8 0;1=8
P 2.845 1.875 5 P 0 8 0;1=8
P 2.845 1.843 5 P 0 8 0;1=8
P 2.77866998 0.93443002 10 P 0 8 0;1=14
P 4.97 1.54 4 P 0 8 0;1=3
P 4.9806 1.855 6 P 0 8 0;1=0
P 1.26066998 1.04043002 10 P 0 8 0;1=14
P 0.724 2.646 6 P 0 8 0;1=0
P 0.758 2.743 3 P 0 8 0;1=4
P 3.235 2.63 4 P 0 8 0;1=3
P 3.275 2.32 3 P 0 8 0;1=4
P 3.24 2.275 6 P 0 8 0;1=0
P 3.305 2.65 4 P 0 8 0;1=3
P 3.375 2.65 4 P 0 8 0;1=3
P 3.326 2.466 3 P 0 8 0;1=4
P 2.1481 0.7881 5 P 0 8 0;1=7
P 5.08 1.105 6 P 0 8 0;1=2
P 5.225 1.145 6 P 0 8 0;1=2
P 5.132 0.66 6 P 0 8 0;1=2
P 2.0816 0.7399 6 P 0 8 0;1=2
P 2.03 0.75 5 P 0 8 0;1=7
P 5.08 1.155 6 P 0 8 0;1=2
P 5.08 1.055 6 P 0 8 0;1=2
P 2.0788 0.7874 5 P 0 8 0;1=7
P 2.29581998 0.48918002 4 P 0 8 0;1=3
P 2.633 0.522 5 P 0 8 0;1=8
P 3.455 0.87 6 P 0 8 0;1=2
P 0.9225 0.9775 6 P 0 8 0;1=2
P 4.82 0.835 6 P 0 8 0;1=0
P 0.8825 1.7725 6 P 0 8 0;1=2
P 3.405 0.87 6 P 0 8 0;1=2
P 0.965 0.98 6 P 0 8 0;1=2
P 0.91 1.815 6 P 0 8 0;1=0
P 4.78 0.78 6 P 0 8 0;1=2
P 4.42311004 1.86311004 3 P 0 8 0;1=11
P 3.65101004 1.88358996 4 P 0 8 0;1=9
P 4.46248002 1.86311004 3 P 0 8 0;1=11
P 3.65101004 1.91558996 4 P 0 8 0;1=9
P 3.065 1.695 4 P 0 8 0;1=3
P 2.98283996 1.75183996 6 P 0 8 0;1=2
P 2.225 3.245 6 P 0 8 0;1=2
P 4.595 2.62 6 P 0 8 0;1=2
P 4.025 3.08 6 P 0 8 0;1=2
P 0.62 3.07 6 P 0 8 0;1=2
P 5.865 1.125 6 P 0 8 0;1=0
P 5.865 1.07 6 P 0 8 0;1=0
P 2.265 3.34 6 P 0 8 0;1=2
P 4.57 2.585 6 P 0 8 0;1=2
P 4.02 3.03 6 P 0 8 0;1=2
P 0.645 2.9675 6 P 0 8 0;1=2
P 5.48828996 4.16328996 6 P 0 8 0;1=0
P 3.99005 1.90248002 4 P 0 8 0;1=1
P 5.55315 4.175 6 P 0 8 0;1=0
P 3.99005 1.86311004 4 P 0 8 0;1=1
P 5.67126004 4.175 6 P 0 8 0;1=0
P 3.95066998 1.82373996 4 P 0 8 0;1=1
P 5.78936998 4.175 6 P 0 8 0;1=0
P 3.9113 1.82373996 4 P 0 8 0;1=1
P 4.205 2.295 4 P 0 8 0;1=3
P 4.65933002 1.6269 4 P 0 8 0;1=3
P 4.254 2.296 4 P 0 8 0;1=3
P 4.23 2.354 4 P 0 8 0;1=3
P 4.915 1.485 4 P 0 8 0;1=3
P 4.65933002 1.54816004 4 P 0 8 0;1=1
P 3.94 2.235 4 P 0 8 0;1=3
P 4.85 1.54 4 P 0 8 0;1=3
P 4.149 2.298 4 P 0 8 0;1=3
P 4.161 2.354 4 P 0 8 0;1=3
P 3.75 2.1 4 P 0 8 0;1=3
P 4.975 1.485 4 P 0 8 0;1=3
P 4.58058996 1.58753002 4 P 0 8 0;1=1
P 3.8 2.1 4 P 0 8 0;1=3
P 4.73806998 1.54816004 4 P 0 8 0;1=3
P 3.9 2.325 4 P 0 8 0;1=3
P 4.73806998 1.50878996 4 P 0 8 0;1=3
P 3.83 2.325 4 P 0 8 0;1=3
P 0.846 2.489 3 P 0 8 0;1=4
P 3.28 3.065 6 P 0 8 0;1=2
P 0.796 2.489 3 P 0 8 0;1=4
P 3.325 3.065 6 P 0 8 0;1=2
P 5.03 3.546 3 P 0 8 0;1=4
P 4.935 3.59 3 P 0 8 0;1=4
P 4.67 3.555 4 P 0 8 0;1=3
P 4.885 3.59 5 P 0 8 0;1=7
P 4.70461998 3.69461998 3 P 0 8 0;1=4
P 4.50185 1.82373996 4 P 0 8 0;1=1
P 5.395 2.92 6 P 0 8 0;1=0
P 5.015 1.925 6 P 0 8 0;1=2
P 5.39976998 2.75123996 5 P 0 8 0;1=7
P 4.46248002 1.82373996 4 P 0 8 0;1=1
P 5.375 2.96606998 5 P 0 8 0;1=7
P 4.58058996 1.78436998 4 P 0 8 0;1=1
P 5.4525 2.563 5 P 0 8 0;1=7
P 3.545 0.6092 6 P 0 8 0;1=2
P 1.395 0.625 5 P 0 8 0;1=7
P 5.085 0.645 6 P 0 8 0;1=2
P 3.495 0.61 6 P 0 8 0;1=2
P 5.04 0.645 6 P 0 8 0;1=2
P 1.485 0.625 5 P 0 8 0;1=7
P 3.99005 1.6269 3 P 0 8 0;1=11
P 2.95835 0.385 4 P 0 8 0;1=9
P 3.95066998 1.6269 3 P 0 8 0;1=11
P 2.95835 0.353 4 P 0 8 0;1=9
P 3.9113 1.66626998 3 P 0 8 0;1=11
P 2.80086998 0.385 4 P 0 8 0;1=9
P 3.87193002 1.66626998 3 P 0 8 0;1=11
P 2.80086998 0.353 4 P 0 8 0;1=9
P 3.99005 1.70563996 3 P 0 8 0;1=11
P 2.64338996 0.385 4 P 0 8 0;1=9
P 3.95066998 1.70563996 3 P 0 8 0;1=11
P 2.64338996 0.353 4 P 0 8 0;1=9
P 3.9113 1.58753002 3 P 0 8 0;1=11
P 2.95835 0.481 4 P 0 8 0;1=9
P 2.95835 0.449 4 P 0 8 0;1=9
P 3.87193002 1.58753002 3 P 0 8 0;1=11
P 3.125 0.875 4 P 0 8 0;1=9
P 3.99005 1.54816004 3 P 0 8 0;1=11
P 3.14763002 0.85236998 4 P 0 8 0;1=9
P 3.95066998 1.54816004 3 P 0 8 0;1=11
P 2.81855 0.763 4 P 0 8 0;1=9
P 3.9113 1.50878996 3 P 0 8 0;1=11
P 2.85055 0.763 4 P 0 8 0;1=9
P 3.87193002 1.50878996 3 P 0 8 0;1=11
P 2.66706998 0.763 4 P 0 8 0;1=9
P 3.99005 1.46941998 3 P 0 8 0;1=11
P 2.69906998 0.763 4 P 0 8 0;1=9
P 3.95066998 1.46941998 3 P 0 8 0;1=11
P 2.47021998 0.763 4 P 0 8 0;1=9
P 3.9113 1.43005 3 P 0 8 0;1=11
P 2.50221998 0.763 4 P 0 8 0;1=9
P 3.87193002 1.43005 3 P 0 8 0;1=11
P 1.889 0.5496 6 P 0 8 0;1=2
P 2.435 0.4865 3 P 0 8 0;1=4
P 3.56 3.023 6 P 0 8 0;1=0
P 3.57 2.955 6 P 0 8 0;1=0
P 4.975 2.14 6 P 0 8 0;1=2
P 5.03005 0.99493996 6 P 0 8 0;1=0
P 5.638 3.907 6 P 0 8 0;1=0
P 1.8317 0.5639 5 P 0 8 0;1=7
P 2.68566998 1.12143002 11 P 0 8 0;1=22
P 2.68566998 2.55943002 11 P 0 8 0;1=22
P 1.46066998 2.68043002 11 P 0 8 0;1=22
P 1.43566998 1.06043002 11 P 0 8 0;1=22
P 6.40038996 0.65353996 13 P 0 8 0;1=23
P 0.29528002 3.73031004 13 P 0 8 0;1=23
P 0.29528002 0.36811004 13 P 0 8 0;1=23
P 6.40038996 4.17835 13 P 0 8 0;1=23
P 6.34055 3.34448996 12 P 0 8 0;1=24
P 6.34055 3.67518996 12 P 0 8 0;1=24
L 3.80999961 -1.25 3.80999961 -1.33 1 N 0 ;0
L 3.80999961 -1.33 3.8500003 -1.33 1 N 0 ;0
L 3.90999902 -1.25 3.90199892 -1.25266614 1 N 0 ;0
L 3.90199892 -1.25266614 3.8960002 -1.25933386 1 N 0 ;0
L 3.8960002 -1.25933386 3.89199921 -1.26733209 1 N 0 ;0
L 3.89199921 -1.26733209 3.8889999 -1.27800138 1 N 0 ;0
L 3.8889999 -1.27800138 3.8880001 -1.29000128 1 N 0 ;0
L 3.8880001 -1.29000128 3.8889999 -1.30200118 1 N 0 ;0
L 3.8889999 -1.30200118 3.89199921 -1.31266801 1 N 0 ;0
L 3.89199921 -1.31266801 3.8960002 -1.3206687 1 N 0 ;0
L 3.8960002 -1.3206687 3.90199892 -1.32733396 1 N 0 ;0
L 3.90199892 -1.32733396 3.90999902 -1.33 1 N 0 ;0
L 3.90999902 -1.33 3.91799911 -1.32733396 1 N 0 ;0
L 3.91799911 -1.32733396 3.9239997 -1.3206687 1 N 0 ;0
L 3.9239997 -1.3206687 3.92800069 -1.31266801 1 N 0 ;0
L 3.92800069 -1.31266801 3.931 -1.30200118 1 N 0 ;0
L 3.931 -1.30200118 3.9319998 -1.29000128 1 N 0 ;0
L 3.9319998 -1.29000128 3.931 -1.27800138 1 N 0 ;0
L 3.931 -1.27800138 3.92800069 -1.26733209 1 N 0 ;0
L 3.92800069 -1.26733209 3.9239997 -1.25933386 1 N 0 ;0
L 3.9239997 -1.25933386 3.91799911 -1.25266614 1 N 0 ;0
L 3.91799911 -1.25266614 3.90999902 -1.25 1 N 0 ;0
L 3.97299902 -1.3206687 3.97999931 -1.32733396 1 N 0 ;0
L 3.97999931 -1.32733396 3.98799951 -1.33 1 N 0 ;0
L 3.98799951 -1.33 3.99599961 -1.32733396 1 N 0 ;0
L 3.99599961 -1.32733396 4.0029999 -1.31933563 1 N 0 ;0
L 4.0029999 -1.31933563 4.00800069 -1.30733337 1 N 0 ;0
L 4.00800069 -1.30733337 4.0100003 -1.29533346 1 N 0 ;0
L 4.0100003 -1.29533346 4.0100003 -1.28066752 1 N 0 ;0
L 4.0100003 -1.28066752 4.00800069 -1.26866762 1 N 0 ;0
L 4.00800069 -1.26866762 4.0029999 -1.25800079 1 N 0 ;0
L 4.0029999 -1.25800079 3.99699941 -1.25266614 1 N 0 ;0
L 3.99699941 -1.25266614 3.98999902 -1.25 1 N 0 ;0
L 3.98999902 -1.25 3.98199892 -1.25266614 1 N 0 ;0
L 3.98199892 -1.25266614 3.9760002 -1.25800079 1 N 0 ;0
L 3.9760002 -1.25800079 3.97199921 -1.26599911 1 N 0 ;0
L 3.97199921 -1.26599911 3.96999961 -1.27666831 1 N 0 ;0
L 3.96999961 -1.27666831 3.97199921 -1.2859997 1 N 0 ;0
L 3.97199921 -1.2859997 3.977 -1.29533346 1 N 0 ;0
L 3.977 -1.29533346 3.98300049 -1.30066811 1 N 0 ;0
L 3.98300049 -1.30066811 3.98999902 -1.30200118 1 N 0 ;0
L 3.98999902 -1.30200118 3.99799911 -1.29933504 1 N 0 ;0
L 3.99799911 -1.29933504 4.0039997 -1.29266732 1 N 0 ;0
L 4.0039997 -1.29266732 4.0100003 -1.28066752 1 N 0 ;0
L 4.04 -1.35666585 4.1 -1.35666585 1 N 0 ;0
L 4.15599961 -1.29000128 4.17600079 -1.29000128 1 N 0 ;0
L 4.17600079 -1.29000128 4.17600079 -1.31400098 1 N 0 ;0
L 4.17600079 -1.31400098 4.1700003 -1.32200177 1 N 0 ;0
L 4.1700003 -1.32200177 4.1629999 -1.32733396 1 N 0 ;0
L 4.1629999 -1.32733396 4.1530002 -1.33 1 N 0 ;0
L 4.1530002 -1.33 4.14300049 -1.32733396 1 N 0 ;0
L 4.14300049 -1.32733396 4.1360002 -1.32200177 1 N 0 ;0
L 4.1360002 -1.32200177 4.12999961 -1.31400098 1 N 0 ;0
L 4.12999961 -1.31400098 4.12599862 -1.30466722 1 N 0 ;0
L 4.12599862 -1.30466722 4.12399911 -1.29400039 1 N 0 ;0
L 4.12399911 -1.29400039 4.12399911 -1.28466663 1 N 0 ;0
L 4.12399911 -1.28466663 4.12599862 -1.27666831 1 N 0 ;0
L 4.12599862 -1.27666831 4.12999961 -1.26733209 1 N 0 ;0
L 4.12999961 -1.26733209 4.1360002 -1.25933386 1 N 0 ;0
L 4.1360002 -1.25933386 4.14199892 -1.25400167 1 N 0 ;0
L 4.14199892 -1.25400167 4.14999902 -1.25 1 N 0 ;0
L 4.14999902 -1.25 4.15699941 -1.25 1 N 0 ;0
L 4.15699941 -1.25 4.16499951 -1.25266614 1 N 0 ;0
L 4.16499951 -1.25266614 4.171 -1.25800079 1 N 0 ;0
L 4.2070003 -1.33 4.2070003 -1.25 1 N 0 ;0
L 4.2070003 -1.25 4.25299961 -1.33 1 N 0 ;0
L 4.25299961 -1.33 4.25299961 -1.25 1 N 0 ;0
L 4.2880001 -1.33 4.2880001 -1.25 1 N 0 ;0
L 4.2880001 -1.25 4.30799951 -1.25 1 N 0 ;0
L 4.30799951 -1.25 4.31599961 -1.25400167 1 N 0 ;0
L 4.31599961 -1.25400167 4.3220001 -1.25933386 1 N 0 ;0
L 4.3220001 -1.25933386 4.32700089 -1.26733209 1 N 0 ;0
L 4.32700089 -1.26733209 4.331 -1.27666831 1 N 0 ;0
L 4.331 -1.27666831 4.3319998 -1.29000128 1 N 0 ;0
L 4.3319998 -1.29000128 4.331 -1.30333415 1 N 0 ;0
L 4.331 -1.30333415 4.32700089 -1.31266801 1 N 0 ;0
L 4.32700089 -1.31266801 4.3220001 -1.3206687 1 N 0 ;0
L 4.3220001 -1.3206687 4.31599961 -1.32600089 1 N 0 ;0
L 4.31599961 -1.32600089 4.30799951 -1.33 1 N 0 ;0
L 4.30799951 -1.33 4.2880001 -1.33 1 N 0 ;0
L 4.4020001 -1.33 4.4020001 -1.25 1 N 0 ;0
L 4.4020001 -1.25 4.36499892 -1.30733337 1 N 0 ;0
L 4.36499892 -1.30733337 4.41500098 -1.30733337 1 N 0 ;0
L 3.16 -0.655 3.16 -1.58 2 N 0 ;0
L 1.36 -0.655 1.36 -1.58 2 N 0 ;0
L 1.36 -1.58 5.06 -1.58 2 N 0 ;0
L 5.06 -1.58 5.06 -0.655 2 N 0 ;0
L 5.06 -0.655 1.36 -0.655 2 N 0 ;0
A 1.559 -1.33655 1.559 -1.33655 1.55268002 -1.33655 1 N 0 N;0
A 1.54775 -1.205 1.54775 -1.205 1.53883002 -1.205 1 N 0 N;0
A 1.54763996 -0.99775 1.54763996 -0.99775 1.53871998 -0.99775 1 N 0 N;0
A 1.54063996 -1.10118002 1.54063996 -1.10118002 1.52603996 -1.10118002 1 N 0 N;0
A 1.49695 -1.10118002 1.49695 -1.10118002 1.48656998 -1.10118002 1 N 0 N;0
A 1.45963996 -1.10118002 1.45963996 -1.10118002 1.4533 -1.10118002 1 N 0 N;0
A 1.52135 -0.98681004 1.52135 -0.98681004 1.51503002 -0.98681004 1 N 0 N;0
A 1.79433002 -1.43586998 1.79433002 -1.43586998 1.78798996 -1.43586998 1 N 0 N;0
A 1.79841004 -1.40261004 1.79841004 -1.40261004 1.78798996 -1.40261004 1 N 0 N;0
A 1.80255 -1.36311004 1.80255 -1.36311004 1.78798996 -1.36311004 1 N 0 N;0
A 1.80668996 -1.31528002 1.80668996 -1.31528002 1.78798996 -1.31528002 1 N 0 N;0
A 1.68013002 -1.37456004 1.68013002 -1.37456004 1.67378996 -1.37456004 1 N 0 N;0
A 1.69321998 -1.35033002 1.69321998 -1.35033002 1.6843 -1.35033002 1 N 0 N;0
A 1.7108 -1.31738996 1.7108 -1.31738996 1.69798002 -1.31738996 1 N 0 N;0
A 1.89666998 -1.31511004 1.89666998 -1.31511004 1.88383996 -1.31511004 1 N 0 N;0
A 1.88198996 -1.16876004 1.88198996 -1.16876004 1.85558996 -1.16876004 1 N 0 N;0
A 1.87928002 -1.27801998 1.87928002 -1.27801998 1.86343996 -1.27801998 1 N 0 N;0
A 1.86176998 -1.23075 1.86176998 -1.23075 1.84206004 -1.23075 1 N 0 N;0
A 1.80978996 -1.25916998 1.80978996 -1.25916998 1.78798996 -1.25916998 1 N 0 N;0
A 1.74681004 -1.16876004 1.74681004 -1.16876004 1.72041004 -1.16876004 1 N 0 N;0
A 1.67813002 -1.15513002 1.67813002 -1.15513002 1.65841998 -1.15513002 1 N 0 N;0
A 1.73018002 -1.27816004 1.73018002 -1.27816004 1.71433996 -1.27816004 1 N 0 N;0
A 1.75373002 -1.23081004 1.75373002 -1.23081004 1.73405 -1.23081004 1 N 0 N;0
A 1.65531004 -1.25255 1.65531004 -1.25255 1.63661998 -1.25255 1 N 0 N;0
A 1.69808996 -1.21291998 1.69808996 -1.21291998 1.67628996 -1.21291998 1 N 0 N;0
A 1.81438996 -1.1968 1.81438996 -1.1968 1.78798996 -1.1968 1 N 0 N;0
A 1.6269 -1.1749 1.6269 -1.1749 1.61106004 -1.1749 1 N 0 N;0
A 1.58461004 -1.19126004 1.58461004 -1.19126004 1.57178002 -1.19126004 1 N 0 N;0
A 1.5853 -1.31428002 1.5853 -1.31428002 1.57488996 -1.31428002 1 N 0 N;0
A 1.61735 -1.28638996 1.61735 -1.28638996 1.60276998 -1.28638996 1 N 0 N;0
A 1.88198996 -1.03361004 1.88198996 -1.03361004 1.85558996 -1.03361004 1 N 0 N;0
A 1.71881004 -1.10118002 1.71881004 -1.10118002 1.69238996 -1.10118002 1 N 0 N;0
A 1.65183002 -1.10118002 1.65183002 -1.10118002 1.63003002 -1.10118002 1 N 0 N;0
A 1.67801998 -1.04738996 1.67801998 -1.04738996 1.65831004 -1.04738996 1 N 0 N;0
A 1.74681004 -1.03361004 1.74681004 -1.03361004 1.72041004 -1.03361004 1 N 0 N;0
A 1.69811998 -0.98951004 1.69811998 -0.98951004 1.67631998 -0.98951004 1 N 0 N;0
A 1.81438996 -1.00556004 1.81438996 -1.00556004 1.78798996 -1.00556004 1 N 0 N;0
A 1.59258002 -1.10118002 1.59258002 -1.10118002 1.5739 -1.10118002 1 N 0 N;0
A 1.58451004 -1.01148996 1.58451004 -1.01148996 1.57168002 -1.01148996 1 N 0 N;0
A 1.62681004 -1.02773996 1.62681004 -1.02773996 1.61096998 -1.02773996 1 N 0 N;0
A 1.92148002 -1.21285 1.92148002 -1.21285 1.89968002 -1.21285 1 N 0 N;0
A 1.92148002 -0.98951004 1.92148002 -0.98951004 1.89968002 -0.98951004 1 N 0 N;0
A 1.80978996 -0.9432 1.80978996 -0.9432 1.78798996 -0.9432 1 N 0 N;0
A 1.80668996 -0.88708002 1.80668996 -0.88708002 1.78798996 -0.88708002 1 N 0 N;0
A 1.80255 -0.83923996 1.80255 -0.83923996 1.78798996 -0.83923996 1 N 0 N;0
A 1.8919 -0.88538002 1.8919 -0.88538002 1.87906998 -0.88538002 1 N 0 N;0
A 1.87838996 -0.92456998 1.87838996 -0.92456998 1.86255 -0.92456998 1 N 0 N;0
A 1.65531004 -0.94981004 1.65531004 -0.94981004 1.63661998 -0.94981004 1 N 0 N;0
A 1.73123002 -0.92378002 1.73123002 -0.92378002 1.71538996 -0.92378002 1 N 0 N;0
A 1.71216998 -0.88443996 1.71216998 -0.88443996 1.69935 -0.88443996 1 N 0 N;0
A 1.86225 -0.97178002 1.86225 -0.97178002 1.84253996 -0.97178002 1 N 0 N;0
A 1.75451998 -0.97123996 1.75451998 -0.97123996 1.73483996 -0.97123996 1 N 0 N;0
A 1.61741998 -0.91601004 1.61741998 -0.91601004 1.60283996 -0.91601004 1 N 0 N;0
A 1.5853 -0.88808996 1.5853 -0.88808996 1.57488996 -0.88808996 1 N 0 N;0
A 1.79841004 -0.79975 1.79841004 -0.79975 1.78798996 -0.79975 1 N 0 N;0
A 1.79433002 -0.76648002 1.79433002 -0.76648002 1.78798996 -0.76648002 1 N 0 N;0
A 1.92135 -1.36781004 1.92135 -1.36781004 1.91503996 -1.36781004 1 N 0 N;0
A 1.91096004 -1.34658002 1.91096004 -1.34658002 1.90203996 -1.34658002 1 N 0 N;0
A 2.19078996 -1.1806 2.26591004 -1.16473002 2.21741014 -1.12088169 1 N 0 N;0
A 2.15903002 -1.1402 2.19078996 -1.18061004 2.22093406 -1.12423278 1 N 0 N;0
A 2.05721004 -1.16178996 2.08853002 -1.16658996 2.08281614 -1.09929134 1 N 0 N;0
A 2.00546998 -1.13951998 2.03345 -1.17196004 2.07793927 -1.10530069 1 N 0 N;0
A 2.03346004 -1.17195 2.0847 -1.18461004 2.07891181 -1.09801299 1 N 0 N;0
A 2.0847 -1.18461998 2.14261004 -1.15663002 2.07348435 -1.08751378 1 N 0 N;0
A 2.08853996 -1.16658002 2.13313002 -1.14451998 2.06368967 -1.06025512 1 N 0 N;0
A 1.95808002 -1.25255 1.95808002 -1.25255 1.93938996 -1.25255 1 N 0 N;0
A 1.98775 -1.28635 1.98775 -1.28635 1.97316998 -1.28635 1 N 0 N;0
A 2.27411998 -1.11835 2.15906004 -1.11835 2.21658996 -1.11611998 1 N 0 N;0
L 2.25188002 -1.11418002 2.1807 -1.11418002 1 N 0 ;0
L 2.1807 -1.11418002 2.1807 -1.11398996 1 N 8191 ;0
A 2.25188996 -1.11398996 2.18071004 -1.11398996 2.2163 -1.1124 1 N 0 N;0
A 2.08028996 -1.03428996 2.02048996 -1.08258996 2.0798126 -1.09486801 1 N 0 N;0
A 2.13151998 -1.05146004 2.0803 -1.0343 2.0802999 -1.11932195 1 N 0 N;0
A 2.1315 -1.05146998 2.14175 -1.03951004 2.1356003 -1.04461171 1 N 0 N;0
A 2.14175 -1.03951004 2.08283002 -1.01613002 2.07772461 -1.11492805 1 N 0 N;0
A 2.08283996 -1.01611998 2.00698002 -1.05835 2.08064724 -1.10143169 1 N 0 N;0
L 2.27413002 -1.12868996 2.18073996 -1.12868996 1 N 0 ;0
A 2.18075 -1.12868996 2.19083002 -1.15751998 2.22417795 -1.12968307 1 N 0 N;0
A 2.19083002 -1.15753002 2.25311004 -1.15211004 2.21927195 -1.12381791 1 N 0 N;0
L 2.15903996 -1.1402 2.15903996 -1.11835 1 N 8191 ;0
A 2.02048996 -1.0826 2.05721998 -1.16181004 2.09087933 -1.0980811 1 N 0 N;0
A 2.00698996 -1.05836004 2.00546998 -1.13953002 2.09672953 -1.10063967 1 N 0 N;0
A 2.14258996 -1.15661004 2.13313996 -1.14453002 2.13544892 -1.15246004 1 N 0 N;0
A 1.95808002 -0.94981004 1.95808002 -0.94981004 1.93938996 -0.94981004 1 N 0 N;0
A 1.90183996 -0.8525 1.90183996 -0.8525 1.89291004 -0.8525 1 N 0 N;0
A 1.91108002 -0.82726998 1.91108002 -0.82726998 1.90473996 -0.82726998 1 N 0 N;0
L 2.32081004 -1.02041004 2.32081004 -1.17625 1 N 0 ;0
A 2.49568002 -1.15528996 2.47898002 -1.16443002 2.4882003 -1.1614502 1 N 0 N;0
A 2.47896998 -1.16443996 2.50283002 -1.18086004 2.51649242 -1.13546152 1 N 0 N;0
A 2.50281998 -1.18086998 2.54318002 -1.1834 2.52887392 -1.08843022 1 N 0 N;0
A 2.52306998 -1.16761004 2.52848996 -1.16771998 2.52673258 -1.12070098 1 N 0 N;0
A 2.49566004 -1.15528996 2.52306998 -1.1676 2.5255122 -1.12549094 1 N 0 N;0
A 2.37851998 -1.15753002 2.4408 -1.15211004 2.40696191 -1.12381791 1 N 0 N;0
A 2.45358002 -1.16471998 2.44078996 -1.1521 2.44541191 -1.16020689 1 N 0 N;0
A 2.37848002 -1.1806 2.4536 -1.16473002 2.4051001 -1.12088169 1 N 0 N;0
A 2.34673002 -1.1402 2.37848996 -1.18061004 2.40863406 -1.12423278 1 N 0 N;0
A 2.2659 -1.16471998 2.25311004 -1.1521 2.25773199 -1.16020689 1 N 0 N;0
A 2.3006 -1.17626004 2.3208 -1.17626004 2.3107 -1.17386841 1 N 0 N;0
L 2.30058996 -1.17625 2.30058996 -1.02033996 1 N 0 ;0
A 2.50836998 -1.10106004 2.54306004 -1.11513002 2.56106673 -1.02093386 1 N 0 N;0
A 2.51081004 -1.07948002 2.50836998 -1.10103996 2.51886093 -1.09130915 1 N 0 N;0
A 2.53611004 -1.07688996 2.5108 -1.07948996 2.52742205 -1.11680827 1 N 0 N;0
A 2.56883996 -1.07368002 2.50178002 -1.06358996 2.5273123 -1.12178858 1 N 0 N;0
A 2.50178996 -1.06358996 2.48536998 -1.08248996 2.52926211 -1.10403986 1 N 0 N;0
L 2.48536998 -1.0825 2.48536998 -1.09748002 1 N 8191 ;0
A 2.48536998 -1.09748002 2.49956004 -1.12031004 2.51189104 -1.09682067 1 N 0 N;0
A 2.46181004 -1.11835 2.34675 -1.11835 2.40428002 -1.11611998 1 N 0 N;0
L 2.43956998 -1.11418002 2.36841004 -1.11418002 1 N 0 ;0
L 2.36841004 -1.11418002 2.36841004 -1.11398996 1 N 8191 ;0
A 2.43958002 -1.11398996 2.3684 -1.11398996 2.40398996 -1.1124 1 N 0 N;0
L 2.43956998 -1.11398996 2.43956998 -1.11418002 1 N 8191 ;0
A 2.49955 -1.1203 2.52723002 -1.12985 2.58163209 -0.92727982 1 N 0 N;0
A 2.55001998 -1.14328002 2.52723002 -1.12986004 2.51462185 -1.17733228 1 N 0 N;0
L 2.46181004 -1.12868996 2.36843996 -1.12868996 1 N 0 ;0
A 2.36843996 -1.12868996 2.37851998 -1.15751998 2.41186801 -1.12968307 1 N 0 N;0
L 2.34675 -1.1402 2.34675 -1.11835 1 N 8191 ;0
L 2.46181004 -1.11835 2.46181004 -1.12868996 1 N 8191 ;0
L 2.25188002 -1.11398996 2.25188002 -1.11418002 1 N 8191 ;0
A 2.3208 -1.02041004 2.3006 -1.02033996 2.31069163 -1.02276978 1 N 0 N;0
L 2.27413002 -1.11835 2.27413002 -1.12868996 1 N 8191 ;0
A 2.52848996 -1.16771004 2.54891998 -1.15895 2.52774557 -1.13777087 1 N 0 N;0
A 2.55608002 -1.08618002 2.53611998 -1.07688996 2.5249185 -1.12704419 1 N 0 N;0
L 2.71926004 -1.06796998 2.71926004 -1.17483996 1 N 0 ;0
A 2.78888996 -1.16296998 2.81508002 -1.16676998 2.8083499 -1.12100167 1 N 0 N;0
A 2.8151 -1.16675 2.83966004 -1.15211998 2.80521398 -1.12222392 1 N 0 N;0
A 2.85201004 -1.16508002 2.83966004 -1.15211004 2.84505768 -1.15933514 1 N 0 N;0
L 2.85201004 -1.16508002 2.84523996 -1.17161004 1 N 8191 ;0
A 2.81425 -1.1835 2.84525 -1.17161004 2.81425 -1.13714291 1 N 0 N;0
L 2.81425 -1.1835 2.79571004 -1.1835 1 N 8191 ;0
A 2.75886998 -1.16443002 2.79571998 -1.18351998 2.80278976 -1.12476142 1 N 0 N;0
A 2.74528996 -1.13568002 2.75888002 -1.16443002 2.80246565 -1.12624016 1 N 0 N;0
A 2.54316998 -1.1834 2.56906004 -1.1647 2.5305814 -1.13869892 1 N 0 N;0
A 2.56906004 -1.1647 2.57053996 -1.13728002 2.53763041 -1.14925374 1 N 0 N;0
A 2.65463996 -1.18351998 2.66863996 -1.17373996 2.65440246 -1.16826969 1 N 0 N;0
L 2.65463002 -1.1835 2.64165 -1.1835 1 N 8191 ;0
A 2.60955 -1.16043002 2.64163996 -1.18351004 2.63911063 -1.15317815 1 N 0 N;0
A 2.62978002 -1.15461998 2.66001998 -1.16328996 2.6502374 -1.14033868 1 N 0 N;0
A 2.66863996 -1.17375 2.66001998 -1.16328996 2.66100344 -1.17126132 1 N 0 N;0
A 2.6962 -1.17483996 2.71926004 -1.17483996 2.70773002 -1.17286427 1 N 0 N;0
L 2.69618996 -1.17483996 2.69618996 -1.06796998 1 N 0 ;0
A 2.83833002 -1.09275 2.82661998 -1.08201998 2.74555758 -1.18224094 1 N 0 N;0
A 2.82661998 -1.08198996 2.80036998 -1.07538996 2.80348839 -1.11848878 1 N 0 N;0
A 2.80036004 -1.07541998 2.76848996 -1.09933002 2.80700217 -1.1174685 1 N 0 N;0
A 2.76848996 -1.09931998 2.76446004 -1.12066004 2.82315728 -1.120694 1 N 0 N;0
A 2.74998002 -1.09273996 2.74528996 -1.11838996 2.8498563 -1.12425591 1 N 0 N;0
A 2.7954 -1.05776998 2.74998996 -1.09273996 2.80799961 -1.12109961 1 N 0 N;0
L 2.79541004 -1.05776998 2.80918996 -1.05776998 1 N 8191 ;0
A 2.85401998 -1.08106004 2.80918996 -1.05776998 2.80626024 -1.1181998 1 N 0 N;0
A 2.83833002 -1.09273996 2.85403002 -1.08106004 2.84418386 -1.08421683 1 N 0 N;0
L 2.76445 -1.12066004 2.76445 -1.12943002 1 N 8191 ;0
A 2.76446004 -1.12943002 2.76836998 -1.14305 2.80607844 -1.12485364 1 N 0 N;0
A 2.76836998 -1.14305 2.78891004 -1.16296998 2.80906152 -1.12164144 1 N 0 N;0
L 2.74528996 -1.13566004 2.74528996 -1.11838996 1 N 8191 ;0
A 2.55606004 -1.0862 2.56885 -1.07366998 2.56205354 -1.0795252 1 N 0 N;0
L 2.60953996 -1.07953996 2.59981998 -1.07953996 1 N 8191 ;0
A 2.5993 -1.05931998 2.59981004 -1.07955 2.6022813 -1.06936624 1 N 0 N;0
L 2.5993 -1.05931998 2.60953996 -1.05931998 1 N 8191 ;0
L 2.60953996 -1.05931998 2.60953996 -1.03491998 1 N 8191 ;0
A 2.62971998 -1.03418002 2.60953996 -1.03491004 2.61966791 -1.03559478 1 N 0 N;0
L 2.62971004 -1.03418996 2.62978002 -1.05931998 1 N 8191 ;0
L 2.62978002 -1.05931998 2.66008002 -1.05931998 1 N 8191 ;0
A 2.66003996 -1.07955 2.66008002 -1.05931998 2.65827421 -1.0694314 1 N 0 N;0
L 2.66003002 -1.07953996 2.62978002 -1.07953996 1 N 8191 ;0
A 2.71926004 -1.06796998 2.6962 -1.06796998 2.70773002 -1.0720561 1 N 0 N;0
A 2.71968996 -1.02341998 2.71968996 -1.02341998 2.70775 -1.02341998 1 N 0 N;0
A 2.57053996 -1.13728996 2.54306998 -1.11513002 2.53584449 -1.15219301 1 N 0 N;0
A 2.54891998 -1.15895 2.55001004 -1.14328002 2.54127923 -1.15054557 1 N 0 N;0
L 2.60953996 -1.16041004 2.60953996 -1.07953996 1 N 0 ;0
L 2.62978002 -1.07953996 2.62978002 -1.15463002 1 N 0 ;0
L 2.98495 -1.09393996 2.98495 -1.17625 1 N 0 ;0
A 2.96473996 -1.17626998 2.98493996 -1.17626998 2.97483996 -1.17442303 1 N 0 N;0
L 2.96473002 -1.17625 2.96473002 -1.17226004 1 N 8191 ;0
A 2.94165 -1.1835 2.96471004 -1.17226004 2.93076516 -1.1318935 1 N 0 N;0
L 2.94165 -1.1835 2.90701004 -1.1835 1 N 8191 ;0
A 2.90671004 -1.10841998 2.90703002 -1.18351004 2.9153065 -1.14592904 1 N 0 N;0
A 2.91853002 -1.12288996 2.91853002 -1.16618996 2.92048209 -1.14453996 1 N 0 N;0
L 2.91853002 -1.1662 2.94456004 -1.1662 1 N 8191 ;0
A 2.94456998 -1.16618996 2.94456998 -1.12288996 2.94406004 -1.14453996 1 N 0 N;0
A 2.96473002 -1.09686004 2.94741998 -1.07955 2.94874833 -1.09553169 1 N 0 N;0
L 2.9474 -1.07953996 2.90986998 -1.07953996 1 N 8191 ;0
A 2.90986998 -1.07953996 2.89821004 -1.0852 2.92433445 -1.12417766 1 N 0 N;0
A 2.89111998 -1.07086004 2.8982 -1.0852 2.8969689 -1.07688996 1 N 0 N;0
A 2.91561998 -1.05931998 2.89111998 -1.07085 2.92146033 -1.103525 1 N 0 N;0
L 2.91563002 -1.05931998 2.95031004 -1.05931998 1 N 8191 ;0
A 2.98496004 -1.09393996 2.95031004 -1.05933002 2.9453438 -1.09895197 1 N 0 N;0
A 2.92878996 -1.10535 2.9067 -1.10841998 2.93158484 -1.20646998 1 N 0 N;0
A 2.96471998 -1.10841004 2.92878002 -1.10536004 2.93215738 -1.27883829 1 N 0 N;0
L 2.96473002 -1.10841004 2.96473002 -1.09686004 1 N 8191 ;0
L 2.94456004 -1.12288002 2.91853002 -1.12288002 1 N 8191 ;0
L 3.04731004 -1.06001004 3.04191998 -1.07631998 1 N 8191 ;0
L 3.04191998 -1.07631998 3.03648002 -1.06001004 1 N 8191 ;0
L 3.03648002 -1.06001004 3.03243002 -1.06001004 1 N 8191 ;0
L 3.03243002 -1.06001004 3.02698002 -1.08543996 1 N 8191 ;0
L 3.02698002 -1.08543996 3.03226004 -1.08543996 1 N 8191 ;0
L 3.03226004 -1.08543996 3.03501004 -1.06886998 1 N 8191 ;0
L 3.03501004 -1.06886998 3.04086004 -1.08543996 1 N 8191 ;0
L 3.04086004 -1.08543996 3.04308996 -1.08543996 1 N 8191 ;0
L 3.04308996 -1.08543996 3.04888996 -1.06871004 1 N 8191 ;0
L 3.04888996 -1.06871004 3.05171004 -1.08543996 1 N 8191 ;0
L 3.05171004 -1.08543996 3.05713002 -1.08543996 1 N 8191 ;0
L 3.05713002 -1.08543996 3.05163996 -1.06001004 1 N 8191 ;0
L 3.05163996 -1.06001004 3.04731004 -1.06001004 1 N 8191 ;0
L 3.01066998 -1.06508002 3.00223002 -1.06508002 1 N 8191 ;0
L 3.00223002 -1.06508002 3.00223002 -1.06001004 1 N 8191 ;0
L 3.00223002 -1.06001004 3.02461004 -1.06001004 1 N 8191 ;0
L 3.02461004 -1.06001004 3.02461004 -1.06508002 1 N 8191 ;0
L 3.02461004 -1.06508002 3.01615 -1.06508002 1 N 8191 ;0
L 3.01615 -1.06508002 3.01615 -1.08533996 1 N 8191 ;0
L 3.01615 -1.08533996 3.01066998 -1.08533996 1 N 8191 ;0
L 3.01066998 -1.08533996 3.01066998 -1.06508002 1 N 8191 ;0
L 3.36933297 -0.955 3.36933297 -0.88 0 N 0 ;0
L 3.36933297 -0.88 3.39173337 -0.88 0 N 0 ;0
L 3.39173337 -0.88 3.3992001 -0.88375157 0 N 0 ;0
L 3.3992001 -0.88375157 3.40480059 -0.8924997 0 N 0 ;0
L 3.40480059 -0.8924997 3.40666693 -0.9024998 0 N 0 ;0
L 3.40666693 -0.9024998 3.40480059 -0.9125 0 N 0 ;0
L 3.40480059 -0.9125 3.40013327 -0.92000069 0 N 0 ;0
L 3.40013327 -0.92000069 3.39173337 -0.92375217 0 N 0 ;0
L 3.39173337 -0.92375217 3.36933297 -0.92375217 0 N 0 ;0
L 3.44619931 -0.95749941 3.47980059 -0.88 0 N 0 ;0
L 3.51653356 -0.955 3.51653356 -0.88 0 N 0 ;0
L 3.51653356 -0.88 3.55946634 -0.955 0 N 0 ;0
L 3.55946634 -0.955 3.55946634 -0.88 0 N 0 ;0
L 3.68799911 -0.95749941 3.68613287 -0.9562497 0 N 0 ;0
L 3.68613287 -0.9562497 3.68613287 -0.9537503 0 N 0 ;0
L 3.68613287 -0.9537503 3.68799911 -0.95250059 0 N 0 ;0
L 3.68799911 -0.95250059 3.68986703 -0.9537503 0 N 0 ;0
L 3.68986703 -0.9537503 3.68986703 -0.9562497 0 N 0 ;0
L 3.68986703 -0.9562497 3.68799911 -0.95749941 0 N 0 ;0
L 3.68799911 -0.92375217 3.68613287 -0.9225001 0 N 0 ;0
L 3.68613287 -0.9225001 3.68613287 -0.92000069 0 N 0 ;0
L 3.68613287 -0.92000069 3.68799911 -0.91875089 0 N 0 ;0
L 3.68799911 -0.91875089 3.68986703 -0.92000069 0 N 0 ;0
L 3.68986703 -0.92000069 3.68986703 -0.9225001 0 N 0 ;0
L 3.68986703 -0.9225001 3.68799911 -0.92375217 0 N 0 ;0
L 3.81933297 -0.955 3.81933297 -0.88 0 N 0 ;0
L 3.81933297 -0.88 3.84266644 -0.88 0 N 0 ;0
L 3.84266644 -0.88 3.85013327 -0.88375157 0 N 0 ;0
L 3.85013327 -0.88375157 3.85480059 -0.88875049 0 N 0 ;0
L 3.85480059 -0.88875049 3.85666693 -0.89875059 0 N 0 ;0
L 3.85666693 -0.89875059 3.85480059 -0.90875079 0 N 0 ;0
L 3.85480059 -0.90875079 3.8492001 -0.91499941 0 N 0 ;0
L 3.8492001 -0.91499941 3.84266644 -0.91875089 0 N 0 ;0
L 3.84266644 -0.91875089 3.81933297 -0.91875089 0 N 0 ;0
L 3.84266644 -0.91875089 3.85666693 -0.955 0 N 0 ;0
L 3.9242001 -0.955 3.9242001 -0.88 0 N 0 ;0
L 3.9242001 -0.88 3.88966565 -0.93375 0 N 0 ;0
L 3.88966565 -0.93375 3.93633425 -0.93375 0 N 0 ;0
L 3.98799911 -0.88 3.98053228 -0.88249951 0 N 0 ;0
L 3.98053228 -0.88249951 3.97493346 -0.88875049 0 N 0 ;0
L 3.97493346 -0.88875049 3.97119931 -0.89624882 0 N 0 ;0
L 3.97119931 -0.89624882 3.9683999 -0.90625128 0 N 0 ;0
L 3.9683999 -0.90625128 3.96746673 -0.91750118 0 N 0 ;0
L 3.96746673 -0.91750118 3.9683999 -0.92875108 0 N 0 ;0
L 3.9683999 -0.92875108 3.97119931 -0.93875128 0 N 0 ;0
L 3.97119931 -0.93875128 3.97493346 -0.94625187 0 N 0 ;0
L 3.97493346 -0.94625187 3.98053228 -0.95250059 0 N 0 ;0
L 3.98053228 -0.95250059 3.98799911 -0.955 0 N 0 ;0
L 3.98799911 -0.955 3.99546585 -0.95250059 0 N 0 ;0
L 3.99546585 -0.95250059 4.00106644 -0.94625187 0 N 0 ;0
L 4.00106644 -0.94625187 4.00480059 -0.93875128 0 N 0 ;0
L 4.00480059 -0.93875128 4.0076 -0.92875108 0 N 0 ;0
L 4.0076 -0.92875108 4.00853317 -0.91750118 0 N 0 ;0
L 4.00853317 -0.91750118 4.0076 -0.90625128 0 N 0 ;0
L 4.0076 -0.90625128 4.00480059 -0.89624882 0 N 0 ;0
L 4.00480059 -0.89624882 4.00106644 -0.88875049 0 N 0 ;0
L 4.00106644 -0.88875049 3.99546585 -0.88249951 0 N 0 ;0
L 3.99546585 -0.88249951 3.98799911 -0.88 0 N 0 ;0
L 4.06299911 -0.88 4.05553228 -0.88249951 0 N 0 ;0
L 4.05553228 -0.88249951 4.04993346 -0.88875049 0 N 0 ;0
L 4.04993346 -0.88875049 4.04619931 -0.89624882 0 N 0 ;0
L 4.04619931 -0.89624882 4.0433999 -0.90625128 0 N 0 ;0
L 4.0433999 -0.90625128 4.04246673 -0.91750118 0 N 0 ;0
L 4.04246673 -0.91750118 4.0433999 -0.92875108 0 N 0 ;0
L 4.0433999 -0.92875108 4.04619931 -0.93875128 0 N 0 ;0
L 4.04619931 -0.93875128 4.04993346 -0.94625187 0 N 0 ;0
L 4.04993346 -0.94625187 4.05553228 -0.95250059 0 N 0 ;0
L 4.05553228 -0.95250059 4.06299911 -0.955 0 N 0 ;0
L 4.06299911 -0.955 4.07046585 -0.95250059 0 N 0 ;0
L 4.07046585 -0.95250059 4.07606644 -0.94625187 0 N 0 ;0
L 4.07606644 -0.94625187 4.07980059 -0.93875128 0 N 0 ;0
L 4.07980059 -0.93875128 4.0826 -0.92875108 0 N 0 ;0
L 4.0826 -0.92875108 4.08353317 -0.91750118 0 N 0 ;0
L 4.08353317 -0.91750118 4.0826 -0.90625128 0 N 0 ;0
L 4.0826 -0.90625128 4.07980059 -0.89624882 0 N 0 ;0
L 4.07980059 -0.89624882 4.07606644 -0.88875049 0 N 0 ;0
L 4.07606644 -0.88875049 4.07046585 -0.88249951 0 N 0 ;0
L 4.07046585 -0.88249951 4.06299911 -0.88 0 N 0 ;0
L 4.12026614 -0.92375217 4.1267998 -0.91499941 0 N 0 ;0
L 4.1267998 -0.91499941 4.1324003 -0.91000049 0 N 0 ;0
L 4.1324003 -0.91000049 4.13986703 -0.90750108 0 N 0 ;0
L 4.13986703 -0.90750108 4.14640069 -0.91000049 0 N 0 ;0
L 4.14640069 -0.91000049 4.15106644 -0.91499941 0 N 0 ;0
L 4.15106644 -0.91499941 4.15480059 -0.9225001 0 N 0 ;0
L 4.15480059 -0.9225001 4.15573376 -0.93125059 0 N 0 ;0
L 4.15573376 -0.93125059 4.15480059 -0.93875128 0 N 0 ;0
L 4.15480059 -0.93875128 4.15106644 -0.94625187 0 N 0 ;0
L 4.15106644 -0.94625187 4.14546585 -0.95250059 0 N 0 ;0
L 4.14546585 -0.95250059 4.13893396 -0.955 0 N 0 ;0
L 4.13893396 -0.955 4.13146713 -0.95250059 0 N 0 ;0
L 4.13146713 -0.95250059 4.12493346 -0.94500217 0 N 0 ;0
L 4.12493346 -0.94500217 4.12119931 -0.93375 0 N 0 ;0
L 4.12119931 -0.93375 4.12026614 -0.92125039 0 N 0 ;0
L 4.12026614 -0.92125039 4.12213238 -0.90500157 0 N 0 ;0
L 4.12213238 -0.90500157 4.12493346 -0.89624882 0 N 0 ;0
L 4.12493346 -0.89624882 4.12959921 -0.88750069 0 N 0 ;0
L 4.12959921 -0.88750069 4.13613287 -0.8812498 0 N 0 ;0
L 4.13613287 -0.8812498 4.14266644 -0.88 0 N 0 ;0
L 4.14266644 -0.88 4.1492001 -0.88249951 0 N 0 ;0
L 4.1492001 -0.88249951 4.15386752 -0.88875049 0 N 0 ;0
L 4.20086663 -0.93000079 4.22513327 -0.93000079 0 N 0 ;0
L 4.29546585 -0.91499941 4.2992001 -0.9112502 0 N 0 ;0
L 4.2992001 -0.9112502 4.30199951 -0.90500157 0 N 0 ;0
L 4.30199951 -0.90500157 4.30386752 -0.89624882 0 N 0 ;0
L 4.30386752 -0.89624882 4.30199951 -0.88875049 0 N 0 ;0
L 4.30199951 -0.88875049 4.29826703 -0.88375157 0 N 0 ;0
L 4.29826703 -0.88375157 4.29173337 -0.88 0 N 0 ;0
L 4.29173337 -0.88 4.26653356 -0.88 0 N 0 ;0
L 4.26653356 -0.88 4.26653356 -0.955 0 N 0 ;0
L 4.26653356 -0.955 4.29733386 -0.955 0 N 0 ;0
L 4.29733386 -0.955 4.30386752 -0.95000108 0 N 0 ;0
L 4.30386752 -0.95000108 4.3076 -0.94250039 0 N 0 ;0
L 4.3076 -0.94250039 4.30946634 -0.93375 0 N 0 ;0
L 4.30946634 -0.93375 4.3076 -0.92500187 0 N 0 ;0
L 4.3076 -0.92500187 4.30199951 -0.91750118 0 N 0 ;0
L 4.30199951 -0.91750118 4.29546585 -0.91499941 0 N 0 ;0
L 4.29546585 -0.91499941 4.26653356 -0.91499941 0 N 0 ;0
L 4.36299911 -0.88 4.35553228 -0.88249951 0 N 0 ;0
L 4.35553228 -0.88249951 4.34993346 -0.88875049 0 N 0 ;0
L 4.34993346 -0.88875049 4.34619931 -0.89624882 0 N 0 ;0
L 4.34619931 -0.89624882 4.3433999 -0.90625128 0 N 0 ;0
L 4.3433999 -0.90625128 4.34246673 -0.91750118 0 N 0 ;0
L 4.34246673 -0.91750118 4.3433999 -0.92875108 0 N 0 ;0
L 4.3433999 -0.92875108 4.34619931 -0.93875128 0 N 0 ;0
L 4.34619931 -0.93875128 4.34993346 -0.94625187 0 N 0 ;0
L 4.34993346 -0.94625187 4.35553228 -0.95250059 0 N 0 ;0
L 4.35553228 -0.95250059 4.36299911 -0.955 0 N 0 ;0
L 4.36299911 -0.955 4.37046585 -0.95250059 0 N 0 ;0
L 4.37046585 -0.95250059 4.37606644 -0.94625187 0 N 0 ;0
L 4.37606644 -0.94625187 4.37980059 -0.93875128 0 N 0 ;0
L 4.37980059 -0.93875128 4.3826 -0.92875108 0 N 0 ;0
L 4.3826 -0.92875108 4.38353317 -0.91750118 0 N 0 ;0
L 4.38353317 -0.91750118 4.3826 -0.90625128 0 N 0 ;0
L 4.3826 -0.90625128 4.37980059 -0.89624882 0 N 0 ;0
L 4.37980059 -0.89624882 4.37606644 -0.88875049 0 N 0 ;0
L 4.37606644 -0.88875049 4.37046585 -0.88249951 0 N 0 ;0
L 4.37046585 -0.88249951 4.36299911 -0.88 0 N 0 ;0
L 4.43799911 -0.88 4.43053228 -0.88249951 0 N 0 ;0
L 4.43053228 -0.88249951 4.42493346 -0.88875049 0 N 0 ;0
L 4.42493346 -0.88875049 4.42119931 -0.89624882 0 N 0 ;0
L 4.42119931 -0.89624882 4.4183999 -0.90625128 0 N 0 ;0
L 4.4183999 -0.90625128 4.41746673 -0.91750118 0 N 0 ;0
L 4.41746673 -0.91750118 4.4183999 -0.92875108 0 N 0 ;0
L 4.4183999 -0.92875108 4.42119931 -0.93875128 0 N 0 ;0
L 4.42119931 -0.93875128 4.42493346 -0.94625187 0 N 0 ;0
L 4.42493346 -0.94625187 4.43053228 -0.95250059 0 N 0 ;0
L 4.43053228 -0.95250059 4.43799911 -0.955 0 N 0 ;0
L 4.43799911 -0.955 4.44546585 -0.95250059 0 N 0 ;0
L 4.44546585 -0.95250059 4.45106644 -0.94625187 0 N 0 ;0
L 4.45106644 -0.94625187 4.45480059 -0.93875128 0 N 0 ;0
L 4.45480059 -0.93875128 4.4576 -0.92875108 0 N 0 ;0
L 4.4576 -0.92875108 4.45853317 -0.91750118 0 N 0 ;0
L 4.45853317 -0.91750118 4.4576 -0.90625128 0 N 0 ;0
L 4.4576 -0.90625128 4.45480059 -0.89624882 0 N 0 ;0
L 4.45480059 -0.89624882 4.45106644 -0.88875049 0 N 0 ;0
L 4.45106644 -0.88875049 4.44546585 -0.88249951 0 N 0 ;0
L 4.44546585 -0.88249951 4.43799911 -0.88 0 N 0 ;0
L 4.51299911 -0.88 4.50553228 -0.88249951 0 N 0 ;0
L 4.50553228 -0.88249951 4.49993346 -0.88875049 0 N 0 ;0
L 4.49993346 -0.88875049 4.49619931 -0.89624882 0 N 0 ;0
L 4.49619931 -0.89624882 4.4933999 -0.90625128 0 N 0 ;0
L 4.4933999 -0.90625128 4.49246673 -0.91750118 0 N 0 ;0
L 4.49246673 -0.91750118 4.4933999 -0.92875108 0 N 0 ;0
L 4.4933999 -0.92875108 4.49619931 -0.93875128 0 N 0 ;0
L 4.49619931 -0.93875128 4.49993346 -0.94625187 0 N 0 ;0
L 4.49993346 -0.94625187 4.50553228 -0.95250059 0 N 0 ;0
L 4.50553228 -0.95250059 4.51299911 -0.955 0 N 0 ;0
L 4.51299911 -0.955 4.52046585 -0.95250059 0 N 0 ;0
L 4.52046585 -0.95250059 4.52606644 -0.94625187 0 N 0 ;0
L 4.52606644 -0.94625187 4.52980059 -0.93875128 0 N 0 ;0
L 4.52980059 -0.93875128 4.5326 -0.92875108 0 N 0 ;0
L 4.5326 -0.92875108 4.53353317 -0.91750118 0 N 0 ;0
L 4.53353317 -0.91750118 4.5326 -0.90625128 0 N 0 ;0
L 4.5326 -0.90625128 4.52980059 -0.89624882 0 N 0 ;0
L 4.52980059 -0.89624882 4.52606644 -0.88875049 0 N 0 ;0
L 4.52606644 -0.88875049 4.52046585 -0.88249951 0 N 0 ;0
L 4.52046585 -0.88249951 4.51299911 -0.88 0 N 0 ;0
L 4.58799911 -0.955 4.58799911 -0.88 0 N 0 ;0
L 4.58799911 -0.88 4.5767998 -0.89499911 0 N 0 ;0
L 4.5767998 -0.955 4.59919843 -0.955 0 N 0 ;0
L 4.65086663 -0.93000079 4.67513327 -0.93000079 0 N 0 ;0
L 4.73799911 -0.88 4.73053228 -0.88249951 0 N 0 ;0
L 4.73053228 -0.88249951 4.72493346 -0.88875049 0 N 0 ;0
L 4.72493346 -0.88875049 4.72119931 -0.89624882 0 N 0 ;0
L 4.72119931 -0.89624882 4.7183999 -0.90625128 0 N 0 ;0
L 4.7183999 -0.90625128 4.71746673 -0.91750118 0 N 0 ;0
L 4.71746673 -0.91750118 4.7183999 -0.92875108 0 N 0 ;0
L 4.7183999 -0.92875108 4.72119931 -0.93875128 0 N 0 ;0
L 4.72119931 -0.93875128 4.72493346 -0.94625187 0 N 0 ;0
L 4.72493346 -0.94625187 4.73053228 -0.95250059 0 N 0 ;0
L 4.73053228 -0.95250059 4.73799911 -0.955 0 N 0 ;0
L 4.73799911 -0.955 4.74546585 -0.95250059 0 N 0 ;0
L 4.74546585 -0.95250059 4.75106644 -0.94625187 0 N 0 ;0
L 4.75106644 -0.94625187 4.75480059 -0.93875128 0 N 0 ;0
L 4.75480059 -0.93875128 4.7576 -0.92875108 0 N 0 ;0
L 4.7576 -0.92875108 4.75853317 -0.91750118 0 N 0 ;0
L 4.75853317 -0.91750118 4.7576 -0.90625128 0 N 0 ;0
L 4.7576 -0.90625128 4.75480059 -0.89624882 0 N 0 ;0
L 4.75480059 -0.89624882 4.75106644 -0.88875049 0 N 0 ;0
L 4.75106644 -0.88875049 4.74546585 -0.88249951 0 N 0 ;0
L 4.74546585 -0.88249951 4.73799911 -0.88 0 N 0 ;0
L 4.79526614 -0.8924997 4.80086663 -0.88500128 0 N 0 ;0
L 4.80086663 -0.88500128 4.8074003 -0.8812498 0 N 0 ;0
L 4.8074003 -0.8812498 4.81486703 -0.88 0 N 0 ;0
L 4.81486703 -0.88 4.8242001 -0.88249951 0 N 0 ;0
L 4.8242001 -0.88249951 4.83073376 -0.88875049 0 N 0 ;0
L 4.83073376 -0.88875049 4.8326 -0.89624882 0 N 0 ;0
L 4.8326 -0.89624882 4.83166693 -0.90375187 0 N 0 ;0
L 4.83166693 -0.90375187 4.82793268 -0.91000049 0 N 0 ;0
L 4.82793268 -0.91000049 4.80926654 -0.9225001 0 N 0 ;0
L 4.80926654 -0.9225001 4.80086663 -0.93125059 0 N 0 ;0
L 4.80086663 -0.93125059 4.79526614 -0.94375246 0 N 0 ;0
L 4.79526614 -0.94375246 4.7933999 -0.955 0 N 0 ;0
L 4.7933999 -0.955 4.8326 -0.955 0 N 0 ;0
L 3.36746673 -1.205 3.36746673 -1.13 0 N 0 ;0
L 3.36746673 -1.13 3.38613287 -1.13 0 N 0 ;0
L 3.38613287 -1.13 3.39359961 -1.13375157 0 N 0 ;0
L 3.39359961 -1.13375157 3.3992001 -1.13875049 0 N 0 ;0
L 3.3992001 -1.13875049 3.40386752 -1.14624882 0 N 0 ;0
L 3.40386752 -1.14624882 3.4076 -1.15500157 0 N 0 ;0
L 3.4076 -1.15500157 3.40853317 -1.16750118 0 N 0 ;0
L 3.40853317 -1.16750118 3.4076 -1.18000079 0 N 0 ;0
L 3.4076 -1.18000079 3.40386752 -1.18875128 0 N 0 ;0
L 3.40386752 -1.18875128 3.3992001 -1.19625187 0 N 0 ;0
L 3.3992001 -1.19625187 3.39359961 -1.20125089 0 N 0 ;0
L 3.39359961 -1.20125089 3.38613287 -1.205 0 N 0 ;0
L 3.38613287 -1.205 3.36746673 -1.205 0 N 0 ;0
L 3.47980059 -1.205 3.47980059 -1.15500157 0 N 0 ;0
L 3.47980059 -1.1637497 3.47606644 -1.15875079 0 N 0 ;0
L 3.47606644 -1.15875079 3.47046585 -1.15625128 0 N 0 ;0
L 3.47046585 -1.15625128 3.46393396 -1.15500157 0 N 0 ;0
L 3.46393396 -1.15500157 3.4574003 -1.15750108 0 N 0 ;0
L 3.4574003 -1.15750108 3.4517998 -1.1625 0 N 0 ;0
L 3.4517998 -1.1625 3.44806555 -1.17000069 0 N 0 ;0
L 3.44806555 -1.17000069 3.44619931 -1.18000079 0 N 0 ;0
L 3.44619931 -1.18000079 3.44806555 -1.19000098 0 N 0 ;0
L 3.44806555 -1.19000098 3.4517998 -1.19750167 0 N 0 ;0
L 3.4517998 -1.19750167 3.4574003 -1.20250059 0 N 0 ;0
L 3.4574003 -1.20250059 3.46393396 -1.205 0 N 0 ;0
L 3.46393396 -1.205 3.47046585 -1.2037503 0 N 0 ;0
L 3.47046585 -1.2037503 3.47606644 -1.20000108 0 N 0 ;0
L 3.47606644 -1.20000108 3.47980059 -1.19500217 0 N 0 ;0
L 3.53799911 -1.13 3.53799911 -1.205 0 N 0 ;0
L 3.52493346 -1.15500157 3.55106644 -1.15500157 0 N 0 ;0
L 3.59900039 -1.17125039 3.62886752 -1.17125039 0 N 0 ;0
L 3.62886752 -1.17125039 3.62606644 -1.1625 0 N 0 ;0
L 3.62606644 -1.1625 3.62140069 -1.15750108 0 N 0 ;0
L 3.62140069 -1.15750108 3.61486703 -1.15500157 0 N 0 ;0
L 3.61486703 -1.15500157 3.60833346 -1.15625128 0 N 0 ;0
L 3.60833346 -1.15625128 3.60273287 -1.16000049 0 N 0 ;0
L 3.60273287 -1.16000049 3.59900039 -1.16875089 0 N 0 ;0
L 3.59900039 -1.16875089 3.59713238 -1.17625157 0 N 0 ;0
L 3.59713238 -1.17625157 3.59713238 -1.18375 0 N 0 ;0
L 3.59713238 -1.18375 3.59900039 -1.19125069 0 N 0 ;0
L 3.59900039 -1.19125069 3.60366604 -1.19875138 0 N 0 ;0
L 3.60366604 -1.19875138 3.60926654 -1.2037503 0 N 0 ;0
L 3.60926654 -1.2037503 3.6158002 -1.205 0 N 0 ;0
L 3.6158002 -1.205 3.62233386 -1.20250059 0 N 0 ;0
L 3.62233386 -1.20250059 3.62886752 -1.19500217 0 N 0 ;0
L 3.68799911 -1.20749941 3.68613287 -1.2062497 0 N 0 ;0
L 3.68613287 -1.2062497 3.68613287 -1.2037503 0 N 0 ;0
L 3.68613287 -1.2037503 3.68799911 -1.20250059 0 N 0 ;0
L 3.68799911 -1.20250059 3.68986703 -1.2037503 0 N 0 ;0
L 3.68986703 -1.2037503 3.68986703 -1.2062497 0 N 0 ;0
L 3.68986703 -1.2062497 3.68799911 -1.20749941 0 N 0 ;0
L 3.68799911 -1.17375217 3.68613287 -1.1725001 0 N 0 ;0
L 3.68613287 -1.1725001 3.68613287 -1.17000069 0 N 0 ;0
L 3.68613287 -1.17000069 3.68799911 -1.16875089 0 N 0 ;0
L 3.68799911 -1.16875089 3.68986703 -1.17000069 0 N 0 ;0
L 3.68986703 -1.17000069 3.68986703 -1.1725001 0 N 0 ;0
L 3.68986703 -1.1725001 3.68799911 -1.17375217 0 N 0 ;0
L 3.82026614 -1.1424997 3.82586663 -1.13500128 0 N 0 ;0
L 3.82586663 -1.13500128 3.8324003 -1.1312498 0 N 0 ;0
L 3.8324003 -1.1312498 3.83986703 -1.13 0 N 0 ;0
L 3.83986703 -1.13 3.8492001 -1.13249951 0 N 0 ;0
L 3.8492001 -1.13249951 3.85573376 -1.13875049 0 N 0 ;0
L 3.85573376 -1.13875049 3.8576 -1.14624882 0 N 0 ;0
L 3.8576 -1.14624882 3.85666693 -1.15375187 0 N 0 ;0
L 3.85666693 -1.15375187 3.85293268 -1.16000049 0 N 0 ;0
L 3.85293268 -1.16000049 3.83426654 -1.1725001 0 N 0 ;0
L 3.83426654 -1.1725001 3.82586663 -1.18125059 0 N 0 ;0
L 3.82586663 -1.18125059 3.82026614 -1.19375246 0 N 0 ;0
L 3.82026614 -1.19375246 3.8183999 -1.205 0 N 0 ;0
L 3.8183999 -1.205 3.8576 -1.205 0 N 0 ;0
L 3.91299911 -1.13 3.90553228 -1.13249951 0 N 0 ;0
L 3.90553228 -1.13249951 3.89993346 -1.13875049 0 N 0 ;0
L 3.89993346 -1.13875049 3.89619931 -1.14624882 0 N 0 ;0
L 3.89619931 -1.14624882 3.8933999 -1.15625128 0 N 0 ;0
L 3.8933999 -1.15625128 3.89246673 -1.16750118 0 N 0 ;0
L 3.89246673 -1.16750118 3.8933999 -1.17875108 0 N 0 ;0
L 3.8933999 -1.17875108 3.89619931 -1.18875128 0 N 0 ;0
L 3.89619931 -1.18875128 3.89993346 -1.19625187 0 N 0 ;0
L 3.89993346 -1.19625187 3.90553228 -1.20250059 0 N 0 ;0
L 3.90553228 -1.20250059 3.91299911 -1.205 0 N 0 ;0
L 3.91299911 -1.205 3.92046585 -1.20250059 0 N 0 ;0
L 3.92046585 -1.20250059 3.92606644 -1.19625187 0 N 0 ;0
L 3.92606644 -1.19625187 3.92980059 -1.18875128 0 N 0 ;0
L 3.92980059 -1.18875128 3.9326 -1.17875108 0 N 0 ;0
L 3.9326 -1.17875108 3.93353317 -1.16750118 0 N 0 ;0
L 3.93353317 -1.16750118 3.9326 -1.15625128 0 N 0 ;0
L 3.9326 -1.15625128 3.92980059 -1.14624882 0 N 0 ;0
L 3.92980059 -1.14624882 3.92606644 -1.13875049 0 N 0 ;0
L 3.92606644 -1.13875049 3.92046585 -1.13249951 0 N 0 ;0
L 3.92046585 -1.13249951 3.91299911 -1.13 0 N 0 ;0
L 3.97026614 -1.1424997 3.97586663 -1.13500128 0 N 0 ;0
L 3.97586663 -1.13500128 3.9824003 -1.1312498 0 N 0 ;0
L 3.9824003 -1.1312498 3.98986703 -1.13 0 N 0 ;0
L 3.98986703 -1.13 3.9992001 -1.13249951 0 N 0 ;0
L 3.9992001 -1.13249951 4.00573376 -1.13875049 0 N 0 ;0
L 4.00573376 -1.13875049 4.0076 -1.14624882 0 N 0 ;0
L 4.0076 -1.14624882 4.00666693 -1.15375187 0 N 0 ;0
L 4.00666693 -1.15375187 4.00293268 -1.16000049 0 N 0 ;0
L 4.00293268 -1.16000049 3.98426654 -1.1725001 0 N 0 ;0
L 3.98426654 -1.1725001 3.97586663 -1.18125059 0 N 0 ;0
L 3.97586663 -1.18125059 3.97026614 -1.19375246 0 N 0 ;0
L 3.97026614 -1.19375246 3.9683999 -1.205 0 N 0 ;0
L 3.9683999 -1.205 4.0076 -1.205 0 N 0 ;0
L 4.04526614 -1.1424997 4.05086663 -1.13500128 0 N 0 ;0
L 4.05086663 -1.13500128 4.0574003 -1.1312498 0 N 0 ;0
L 4.0574003 -1.1312498 4.06486703 -1.13 0 N 0 ;0
L 4.06486703 -1.13 4.0742001 -1.13249951 0 N 0 ;0
L 4.0742001 -1.13249951 4.08073376 -1.13875049 0 N 0 ;0
L 4.08073376 -1.13875049 4.0826 -1.14624882 0 N 0 ;0
L 4.0826 -1.14624882 4.08166693 -1.15375187 0 N 0 ;0
L 4.08166693 -1.15375187 4.07793268 -1.16000049 0 N 0 ;0
L 4.07793268 -1.16000049 4.05926654 -1.1725001 0 N 0 ;0
L 4.05926654 -1.1725001 4.05086663 -1.18125059 0 N 0 ;0
L 4.05086663 -1.18125059 4.04526614 -1.19375246 0 N 0 ;0
L 4.04526614 -1.19375246 4.0433999 -1.205 0 N 0 ;0
L 4.0433999 -1.205 4.0826 -1.205 0 N 0 ;0
L 4.12586663 -1.18000079 4.15013327 -1.18000079 0 N 0 ;0
L 4.21299911 -1.13 4.20553228 -1.13249951 0 N 0 ;0
L 4.20553228 -1.13249951 4.19993346 -1.13875049 0 N 0 ;0
L 4.19993346 -1.13875049 4.19619931 -1.14624882 0 N 0 ;0
L 4.19619931 -1.14624882 4.1933999 -1.15625128 0 N 0 ;0
L 4.1933999 -1.15625128 4.19246673 -1.16750118 0 N 0 ;0
L 4.19246673 -1.16750118 4.1933999 -1.17875108 0 N 0 ;0
L 4.1933999 -1.17875108 4.19619931 -1.18875128 0 N 0 ;0
L 4.19619931 -1.18875128 4.19993346 -1.19625187 0 N 0 ;0
L 4.19993346 -1.19625187 4.20553228 -1.20250059 0 N 0 ;0
L 4.20553228 -1.20250059 4.21299911 -1.205 0 N 0 ;0
L 4.21299911 -1.205 4.22046585 -1.20250059 0 N 0 ;0
L 4.22046585 -1.20250059 4.22606644 -1.19625187 0 N 0 ;0
L 4.22606644 -1.19625187 4.22980059 -1.18875128 0 N 0 ;0
L 4.22980059 -1.18875128 4.2326 -1.17875108 0 N 0 ;0
L 4.2326 -1.17875108 4.23353317 -1.16750118 0 N 0 ;0
L 4.23353317 -1.16750118 4.2326 -1.15625128 0 N 0 ;0
L 4.2326 -1.15625128 4.22980059 -1.14624882 0 N 0 ;0
L 4.22980059 -1.14624882 4.22606644 -1.13875049 0 N 0 ;0
L 4.22606644 -1.13875049 4.22046585 -1.13249951 0 N 0 ;0
L 4.22046585 -1.13249951 4.21299911 -1.13 0 N 0 ;0
L 4.27026614 -1.1424997 4.27586663 -1.13500128 0 N 0 ;0
L 4.27586663 -1.13500128 4.2824003 -1.1312498 0 N 0 ;0
L 4.2824003 -1.1312498 4.28986703 -1.13 0 N 0 ;0
L 4.28986703 -1.13 4.2992001 -1.13249951 0 N 0 ;0
L 4.2992001 -1.13249951 4.30573376 -1.13875049 0 N 0 ;0
L 4.30573376 -1.13875049 4.3076 -1.14624882 0 N 0 ;0
L 4.3076 -1.14624882 4.30666693 -1.15375187 0 N 0 ;0
L 4.30666693 -1.15375187 4.30293268 -1.16000049 0 N 0 ;0
L 4.30293268 -1.16000049 4.28426654 -1.1725001 0 N 0 ;0
L 4.28426654 -1.1725001 4.27586663 -1.18125059 0 N 0 ;0
L 4.27586663 -1.18125059 4.27026614 -1.19375246 0 N 0 ;0
L 4.27026614 -1.19375246 4.2683999 -1.205 0 N 0 ;0
L 4.2683999 -1.205 4.3076 -1.205 0 N 0 ;0
L 4.35086663 -1.18000079 4.37513327 -1.18000079 0 N 0 ;0
L 4.42026614 -1.1424997 4.42586663 -1.13500128 0 N 0 ;0
L 4.42586663 -1.13500128 4.4324003 -1.1312498 0 N 0 ;0
L 4.4324003 -1.1312498 4.43986703 -1.13 0 N 0 ;0
L 4.43986703 -1.13 4.4492001 -1.13249951 0 N 0 ;0
L 4.4492001 -1.13249951 4.45573376 -1.13875049 0 N 0 ;0
L 4.45573376 -1.13875049 4.4576 -1.14624882 0 N 0 ;0
L 4.4576 -1.14624882 4.45666693 -1.15375187 0 N 0 ;0
L 4.45666693 -1.15375187 4.45293268 -1.16000049 0 N 0 ;0
L 4.45293268 -1.16000049 4.43426654 -1.1725001 0 N 0 ;0
L 4.43426654 -1.1725001 4.42586663 -1.18125059 0 N 0 ;0
L 4.42586663 -1.18125059 4.42026614 -1.19375246 0 N 0 ;0
L 4.42026614 -1.19375246 4.4183999 -1.205 0 N 0 ;0
L 4.4183999 -1.205 4.4576 -1.205 0 N 0 ;0
L 4.49246673 -1.19375246 4.49806555 -1.20000108 0 N 0 ;0
L 4.49806555 -1.20000108 4.50459921 -1.2037503 0 N 0 ;0
L 4.50459921 -1.2037503 4.51299911 -1.205 0 N 0 ;0
L 4.51299911 -1.205 4.52140069 -1.20250059 0 N 0 ;0
L 4.52140069 -1.20250059 4.52793268 -1.19750167 0 N 0 ;0
L 4.52793268 -1.19750167 4.5326 -1.18875128 0 N 0 ;0
L 4.5326 -1.18875128 4.53353317 -1.17875108 0 N 0 ;0
L 4.53353317 -1.17875108 4.53166693 -1.16875089 0 N 0 ;0
L 4.53166693 -1.16875089 4.52699951 -1.1625 0 N 0 ;0
L 4.52699951 -1.1625 4.52046585 -1.15750108 0 N 0 ;0
L 4.52046585 -1.15750108 4.51393396 -1.15625128 0 N 0 ;0
L 4.51393396 -1.15625128 4.5074003 -1.15750108 0 N 0 ;0
L 4.5074003 -1.15750108 4.49900039 -1.1625 0 N 0 ;0
L 4.49900039 -1.1625 4.5017998 -1.13 0 N 0 ;0
L 4.5017998 -1.13 4.52699951 -1.13 0 N 0 ;0
L 3.29433297 -1.255 3.29433297 -1.33 0 N 0 ;0
L 3.29433297 -1.33 3.33166693 -1.33 0 N 0 ;0
L 3.40480059 -1.33 3.40480059 -1.28000157 0 N 0 ;0
L 3.40480059 -1.2887497 3.40106644 -1.28375079 0 N 0 ;0
L 3.40106644 -1.28375079 3.39546585 -1.28125128 0 N 0 ;0
L 3.39546585 -1.28125128 3.38893396 -1.28000157 0 N 0 ;0
L 3.38893396 -1.28000157 3.3824003 -1.28250108 0 N 0 ;0
L 3.3824003 -1.28250108 3.3767998 -1.2875 0 N 0 ;0
L 3.3767998 -1.2875 3.37306555 -1.29500069 0 N 0 ;0
L 3.37306555 -1.29500069 3.37119931 -1.30500079 0 N 0 ;0
L 3.37119931 -1.30500079 3.37306555 -1.31500098 0 N 0 ;0
L 3.37306555 -1.31500098 3.3767998 -1.32250167 0 N 0 ;0
L 3.3767998 -1.32250167 3.3824003 -1.32750059 0 N 0 ;0
L 3.3824003 -1.32750059 3.38893396 -1.33 0 N 0 ;0
L 3.38893396 -1.33 3.39546585 -1.3287503 0 N 0 ;0
L 3.39546585 -1.3287503 3.40106644 -1.32500108 0 N 0 ;0
L 3.40106644 -1.32500108 3.40480059 -1.32000217 0 N 0 ;0
L 3.4433999 -1.3524997 3.44900039 -1.35499921 0 N 0 ;0
L 3.44900039 -1.35499921 3.45646713 -1.3524997 0 N 0 ;0
L 3.45646713 -1.3524997 3.46113287 -1.34750079 0 N 0 ;0
L 3.46113287 -1.34750079 3.46486703 -1.3412498 0 N 0 ;0
L 3.46486703 -1.3412498 3.47046585 -1.32125187 0 N 0 ;0
L 3.47046585 -1.32125187 3.4826 -1.28000157 0 N 0 ;0
L 3.45273287 -1.28000157 3.47046585 -1.32125187 0 N 0 ;0
L 3.52400039 -1.29625039 3.55386752 -1.29625039 0 N 0 ;0
L 3.55386752 -1.29625039 3.55106644 -1.2875 0 N 0 ;0
L 3.55106644 -1.2875 3.54640069 -1.28250108 0 N 0 ;0
L 3.54640069 -1.28250108 3.53986703 -1.28000157 0 N 0 ;0
L 3.53986703 -1.28000157 3.53333346 -1.28125128 0 N 0 ;0
L 3.53333346 -1.28125128 3.52773287 -1.28500049 0 N 0 ;0
L 3.52773287 -1.28500049 3.52400039 -1.29375089 0 N 0 ;0
L 3.52400039 -1.29375089 3.52213238 -1.30125157 0 N 0 ;0
L 3.52213238 -1.30125157 3.52213238 -1.30875 0 N 0 ;0
L 3.52213238 -1.30875 3.52400039 -1.31625069 0 N 0 ;0
L 3.52400039 -1.31625069 3.52866604 -1.32375138 0 N 0 ;0
L 3.52866604 -1.32375138 3.53426654 -1.3287503 0 N 0 ;0
L 3.53426654 -1.3287503 3.5408002 -1.33 0 N 0 ;0
L 3.5408002 -1.33 3.54733386 -1.32750059 0 N 0 ;0
L 3.54733386 -1.32750059 3.55386752 -1.32000217 0 N 0 ;0
L 3.59993346 -1.33 3.59993346 -1.28000157 0 N 0 ;0
L 3.59993346 -1.28999941 3.60459921 -1.28500049 0 N 0 ;0
L 3.60459921 -1.28500049 3.60926654 -1.28125128 0 N 0 ;0
L 3.60926654 -1.28125128 3.6158002 -1.28000157 0 N 0 ;0
L 3.6158002 -1.28000157 3.62046585 -1.28125128 0 N 0 ;0
L 3.62046585 -1.28125128 3.62606644 -1.28500049 0 N 0 ;0
L 3.68799911 -1.33249941 3.68613287 -1.3312497 0 N 0 ;0
L 3.68613287 -1.3312497 3.68613287 -1.3287503 0 N 0 ;0
L 3.68613287 -1.3287503 3.68799911 -1.32750059 0 N 0 ;0
L 3.68799911 -1.32750059 3.68986703 -1.3287503 0 N 0 ;0
L 3.68986703 -1.3287503 3.68986703 -1.3312497 0 N 0 ;0
L 3.68986703 -1.3312497 3.68799911 -1.33249941 0 N 0 ;0
L 3.68799911 -1.29875217 3.68613287 -1.2975001 0 N 0 ;0
L 3.68613287 -1.2975001 3.68613287 -1.29500069 0 N 0 ;0
L 3.68613287 -1.29500069 3.68799911 -1.29375089 0 N 0 ;0
L 3.68799911 -1.29375089 3.68986703 -1.29500069 0 N 0 ;0
L 3.68986703 -1.29500069 3.68986703 -1.2975001 0 N 0 ;0
L 3.68986703 -1.2975001 3.68799911 -1.29875217 0 N 0 ;0
L 3.36933297 -1.08 3.36933297 -1.005 0 N 0 ;0
L 3.36933297 -1.005 3.39266644 -1.005 0 N 0 ;0
L 3.39266644 -1.005 3.40013327 -1.00875157 0 N 0 ;0
L 3.40013327 -1.00875157 3.40480059 -1.01375049 0 N 0 ;0
L 3.40480059 -1.01375049 3.40666693 -1.02375059 0 N 0 ;0
L 3.40666693 -1.02375059 3.40480059 -1.03375079 0 N 0 ;0
L 3.40480059 -1.03375079 3.3992001 -1.03999941 0 N 0 ;0
L 3.3992001 -1.03999941 3.39266644 -1.04375089 0 N 0 ;0
L 3.39266644 -1.04375089 3.36933297 -1.04375089 0 N 0 ;0
L 3.39266644 -1.04375089 3.40666693 -1.08 0 N 0 ;0
L 3.44900039 -1.04625039 3.47886752 -1.04625039 0 N 0 ;0
L 3.47886752 -1.04625039 3.47606644 -1.0375 0 N 0 ;0
L 3.47606644 -1.0375 3.47140069 -1.03250108 0 N 0 ;0
L 3.47140069 -1.03250108 3.46486703 -1.03000157 0 N 0 ;0
L 3.46486703 -1.03000157 3.45833346 -1.03125128 0 N 0 ;0
L 3.45833346 -1.03125128 3.45273287 -1.03500049 0 N 0 ;0
L 3.45273287 -1.03500049 3.44900039 -1.04375089 0 N 0 ;0
L 3.44900039 -1.04375089 3.44713238 -1.05125157 0 N 0 ;0
L 3.44713238 -1.05125157 3.44713238 -1.05875 0 N 0 ;0
L 3.44713238 -1.05875 3.44900039 -1.06625069 0 N 0 ;0
L 3.44900039 -1.06625069 3.45366604 -1.07375138 0 N 0 ;0
L 3.45366604 -1.07375138 3.45926654 -1.0787503 0 N 0 ;0
L 3.45926654 -1.0787503 3.4658002 -1.08 0 N 0 ;0
L 3.4658002 -1.08 3.47233386 -1.07750059 0 N 0 ;0
L 3.47233386 -1.07750059 3.47886752 -1.07000217 0 N 0 ;0
L 3.52119931 -1.03000157 3.53799911 -1.08 0 N 0 ;0
L 3.53799911 -1.08 3.55480059 -1.03000157 0 N 0 ;0
L 3.68799911 -1.08249941 3.68613287 -1.0812497 0 N 0 ;0
L 3.68613287 -1.0812497 3.68613287 -1.0787503 0 N 0 ;0
L 3.68613287 -1.0787503 3.68799911 -1.07750059 0 N 0 ;0
L 3.68799911 -1.07750059 3.68986703 -1.0787503 0 N 0 ;0
L 3.68986703 -1.0787503 3.68986703 -1.0812497 0 N 0 ;0
L 3.68986703 -1.0812497 3.68799911 -1.08249941 0 N 0 ;0
L 3.68799911 -1.04875217 3.68613287 -1.0475001 0 N 0 ;0
L 3.68613287 -1.0475001 3.68613287 -1.04500069 0 N 0 ;0
L 3.68613287 -1.04500069 3.68799911 -1.04375089 0 N 0 ;0
L 3.68799911 -1.04375089 3.68986703 -1.04500069 0 N 0 ;0
L 3.68986703 -1.04500069 3.68986703 -1.0475001 0 N 0 ;0
L 3.68986703 -1.0475001 3.68799911 -1.04875217 0 N 0 ;0
L 3.83799911 -1.005 3.83053228 -1.00749951 0 N 0 ;0
L 3.83053228 -1.00749951 3.82493346 -1.01375049 0 N 0 ;0
L 3.82493346 -1.01375049 3.82119931 -1.02124882 0 N 0 ;0
L 3.82119931 -1.02124882 3.8183999 -1.03125128 0 N 0 ;0
L 3.8183999 -1.03125128 3.81746673 -1.04250118 0 N 0 ;0
L 3.81746673 -1.04250118 3.8183999 -1.05375108 0 N 0 ;0
L 3.8183999 -1.05375108 3.82119931 -1.06375128 0 N 0 ;0
L 3.82119931 -1.06375128 3.82493346 -1.07125187 0 N 0 ;0
L 3.82493346 -1.07125187 3.83053228 -1.07750059 0 N 0 ;0
L 3.83053228 -1.07750059 3.83799911 -1.08 0 N 0 ;0
L 3.83799911 -1.08 3.84546585 -1.07750059 0 N 0 ;0
L 3.84546585 -1.07750059 3.85106644 -1.07125187 0 N 0 ;0
L 3.85106644 -1.07125187 3.85480059 -1.06375128 0 N 0 ;0
L 3.85480059 -1.06375128 3.8576 -1.05375108 0 N 0 ;0
L 3.8576 -1.05375108 3.85853317 -1.04250118 0 N 0 ;0
L 3.85853317 -1.04250118 3.8576 -1.03125128 0 N 0 ;0
L 3.8576 -1.03125128 3.85480059 -1.02124882 0 N 0 ;0
L 3.85480059 -1.02124882 3.85106644 -1.01375049 0 N 0 ;0
L 3.85106644 -1.01375049 3.84546585 -1.00749951 0 N 0 ;0
L 3.84546585 -1.00749951 3.83799911 -1.005 0 N 0 ;0
L 3.91299911 -1.08 3.91299911 -1.005 0 N 0 ;0
L 3.91299911 -1.005 3.9017998 -1.01999911 0 N 0 ;0
L 3.9017998 -1.08 3.92419843 -1.08 0 N 0 ;0

### steps/pcb/layers/rout/features
#
#Num Features
#
F 40

#
#Units
#
U INCH

#
#Feature symbol names
#
$0 r0

#
#Layer features
#
A 6.58071004 2.84646004 6.60038996 2.86613996 6.58071004 2.86613996 0 P 0 N
L 6.60038996 2.86613996 6.60038996 4.33661004 0 P 0 
A 6.60038996 4.33661004 6.56101998 4.37598002 6.56101998 4.33661004 0 P 0 N
L 6.56101998 4.37598002 0.03936998 4.37598002 0 P 0 
A 0.03936998 4.37598002 0 4.33661004 0.03936998 4.33661004 0 P 0 N
L 0 4.33661004 0 0.21653996 0 P 0 
A 0 0.21653996 0.03936998 0.17716998 0.03936998 0.21653996 0 P 0 N
L 0.03936998 0.17716998 0.55118002 0.17716998 0 P 0 
A 0.55118002 0.17716998 0.59055 0.21653996 0.55118002 0.21653996 0 P 0 N
L 0.59055 0.21653996 0.59055 0.4626 0 P 0 
A 0.59055 0.4626 0.62991998 0.50196998 0.62991998 0.4626 0 P 0 Y
L 0.62991998 0.50196998 1.27361998 0.50196998 0 P 0 
A 1.27361998 0.50196998 1.31298996 0.4626 1.27361998 0.4626 0 P 0 Y
L 1.31298996 0.4626 1.31298996 0.21653996 0 P 0 
A 1.31298996 0.21653996 1.35236004 0.17716998 1.35235994 0.21653996 0 P 0 N
L 1.35236004 0.17716998 1.58858002 0.17716998 0 P 0 
A 1.58858002 0.17716998 1.62795 0.21653996 1.58858002 0.21653996 0 P 0 N
L 1.62795 0.21653996 1.62795 0.43011998 0 P 0 
A 1.62795 0.43011998 1.77165 0.43011998 1.6998 0.43011998 0 P 0 Y
L 1.77165 0.43011998 1.77165 0.01968996 0 P 0 
L 1.77165 0.01968996 1.79133996 0 0 P 8191 
L 1.79133996 0 2.19291004 0 0 P 0 
L 2.19291004 0 2.2126 0.01968996 0 P 8191 
L 2.2126 0.01968996 2.2126 0.29331004 0 P 0 
A 2.2126 0.29331004 2.2874 0.29331004 2.25 0.29331004 0 P 0 Y
L 2.2874 0.29331004 2.2874 0.01968996 0 P 0 
L 2.2874 0.01968996 2.30708996 0 0 P 8191 
L 2.30708996 0 3.10236004 0 0 P 0 
L 3.10236004 0 3.12205 0.01968996 0 P 8191 
L 3.12205 0.01968996 3.12205 0.4626 0 P 0 
A 3.12205 0.4626 3.16141998 0.50196998 3.16141998 0.4626 0 P 0 Y
L 3.16141998 0.50196998 6.56101998 0.50196998 0 P 0 
A 6.56101998 0.50196998 6.60038996 0.54133996 6.56101998 0.54133996 0 P 0 N
L 6.60038996 0.54133996 6.60038996 2.375 0 P 0 
A 6.60038996 2.375 6.58071004 2.39468996 6.58070502 2.37500502 0 P 0 N
L 6.58071004 2.39468996 6.57211004 2.39468996 0 P 8191 
A 6.57211004 2.39468996 6.55243002 2.41436998 6.57211004 2.41436998 0 P 0 Y
L 6.55243002 2.41436998 6.55243002 2.82676998 0 P 0 
A 6.55243002 2.82676998 6.57211004 2.84646004 6.57211496 2.826775 0 P 0 Y
L 6.57211004 2.84646004 6.58071004 2.84646004 0 P 8191 

### steps/pcb/layers/smb/features
#
#Num Features
#
F 4045

#
#Units
#
U INCH

#
#Feature symbol names
#
$0 r5
$1 r10
$2 r12
$3 r14
$4 r28
$5 r29
$6 r34
$7 r40
$8 r61
$9 r90
$10 r94
$11 r104
$12 r108
$13 r110
$14 r120
$15 r128
$16 r135
$17 r202
$18 s108
$19 oval79x39 I
$20 oval79x52 I
$21 rect112x89 I
$22 rect14x28 I
$23 rect17x42 I
$24 rect19x16 I
$25 rect24x51 I
$26 rect28x14 I
$27 rect28x32 I
$28 rect32x130 I
$29 rect32x169 I
$30 rect32x28 I
$31 rect34x38 I
$32 rect38x34 I
$33 rect42x58 I
$34 rect43x61 I
$35 rect47x61 I
$36 rect49x108 I
$37 rect58x42 I
$38 rect59x43 I
$39 rect64x22 I
$40 rect69x24 I

#
#Feature attribute names
#
@0 .smd
@1 .test_point
@2 .nomenclature
@3 .geometry
@4 .string
@5 .pad_usage
@6 .string_angle

#
#Feature attribute text strings
#
&0 S028X024
&1 V010C020P_TP030B
&2 V010C020P
&3 TPV010CT020B030
&4 V008C018P_ANTI026_TP030B
&5 V008C018P_NATI28_TP030B_NSMT
&6 016C024P
&7 S030X034
&8 S020X065
&9 V008C018P_TP030B
&10 V008C018P
&11 S038X054
&12 V008C018P_ANTI28
&13 TP030C_B
&14 S057X039
&15 059C086P
&16 S039X055
&17 S018X060
&18 S025C
&19 S020X047
&20 S045X104
&21 S013X038
&22 S012X015
&23 076S104P
&24 076C104P
&25 S085X108
&26 079C100P
&27 EFB028X165
&28 V010C020P_SM014-NTH
&29 V012C024-NTH
&30 024X063OB035X075P
&31 166CT244CB198P
&32 S057X043
&33 024X051OB071X075P_R
&34 024X051OB071X075P_L
&35 033C057P
&36 063C090P
&37 EFB028X126
&38 FID040
&39 MTH100C090N
&40 MTH125C115N
&41 MTH118C108N
&42 SOLDERMASK BOT
&43 P/N : R4006-B0001-02
&44 Date: 2022-02-25
&45 Layer:
&46 Rev : 01

#
#Layer features
#
P 4.266 4.065 30 P 0 8 0;0,3=0,5=0
P 4.354 4.065 30 P 0 8 0;0,3=0,5=0
P 4.31 4.065 6 P 0 8 0;1,3=1,5=1
P 4.266 4.115 30 P 0 8 0;0,3=0,5=0
P 4.354 4.115 30 P 0 8 0;0,3=0,5=0
P 4.31 4.115 6 P 0 8 0;1,3=1,5=1
P 4.61 2.3 6 P 0 8 0;1,3=1,5=1
P 4.49 2.275 6 P 0 8 0;1,3=1,5=1
P 4.435 2.315 6 P 0 8 0;1,3=1,5=1
P 4.49 2.325 6 P 0 8 0;1,3=1,5=1
P 4.435 2.365 6 P 0 8 0;1,3=1,5=1
P 3.655 2.465 6 P 0 8 0;1,3=1,5=1
P 3.125 1.605 6 P 0 8 0;1,3=1,5=1
P 3.65 2.68 3 P 0 8 0;3=2,5=1
P 3.12 2.645 3 P 0 8 0;3=2,5=1
P 3.765 2.69 6 P 0 8 0;1,3=1,5=1
P 4.3 3.865 6 P 0 8 0;1,3=3,5=0
P 4.354 3.865 30 P 0 8 0;0,3=0,5=0
P 4.24 3.941 27 P 0 8 0;0,3=0,5=0
P 3.36525 3.305 6 P 0 8 0;1,3=4,5=1
P 3.37 3.44 6 P 0 8 0;3=3,5=0
P 3.298 3.385 30 P 0 8 0;0,3=0,5=0
P 3.298 3.475 30 P 0 8 0;0,3=0,5=0
P 3.298 3.43 30 P 0 8 0;0,3=0,5=0
P 4.795 0.925 6 P 0 8 0;1,3=3,5=0
P 4.736 0.965 30 P 0 8 0;0,3=0,5=0
P 4.736 0.915 30 P 0 8 0;0,3=0,5=0
P 4.08 3.27 6 P 0 8 0;1,3=3,5=0
P 4.015 3.291 30 P 0 8 0;0,3=0,5=0
P 4.015 3.239 30 P 0 8 0;0,3=0,5=0
P 3.95 3.82 6 P 0 8 0;1,3=3,5=0
P 3.881 3.81 30 P 0 8 0;0,3=0,5=0
P 3.881 3.758 30 P 0 8 0;0,3=0,5=0
P 3.746 1.72 30 P 0 8 0;0,3=0,5=0
P 3.746 1.782 6 P 0 8 0;1,3=3,5=0
P 4.205 0.82 6 P 0 8 0;1,3=3,5=0
P 3.82286004 0.86213996 6 P 0 8 0;1,3=1,5=1
P 3.705 0.84 6 P 0 8 0;3=3,5=0
P 0.496 2.13455 6 P 0 8 0;1,3=1,5=1
P 0.53 2.091 27 P 0 8 0;0,3=0,5=0
P 0.528 2.72 6 P 0 8 0;1,3=1,5=1
P 0.53 2.626 27 P 0 8 0;0,3=0,5=0
P 0.535 0.926 27 P 0 8 0;0,3=0,5=0
P 0.575 1.015 6 P 0 8 0;1,3=1,5=1
P 0.53 1.486 27 P 0 8 0;0,3=0,5=0
P 0.48956998 1.53618996 6 P 0 8 0;1,3=1,5=1
P 4.06878996 2.09933002 6 P 0 8 0;1,3=5,5=1
P 3.99005 2.09933002 6 P 0 8 0;1,3=5,5=1
P 4.26563996 1.43005 6 P 0 8 0;1,3=5,5=1
P 1.055 3.731 27 P 0 8 0;0,3=0,5=0
P 1.45 3.59 6 P 0 8 0;1,3=1,5=1
P 1.56 3.165 3 P 0 8 0;3=2,5=1
P 1.56 3.205 6 P 0 8 0;1,3=1,5=1
P 0.7 3.426 27 P 0 8 0;0,3=0,5=0
P 0.72 3.463 3 P 0 8 0;3=2,5=1
P 0.42326004 3.4315 4 P 0 8 0;3=6,5=0
P 0.40553996 3.4008 4 P 0 8 0;3=6,5=0
P 0.2815 3.4315 4 P 0 8 0;3=6,5=0
P 0.26378002 3.4008 4 P 0 8 0;3=6,5=0
P 0.71 3.305 6 P 0 8 0;1,3=3,5=0
P 1.085 3.564 27 P 0 8 0;0,3=0,5=0
P 1.13 3.564 27 P 0 8 0;0,3=0,5=0
P 1.09 3.512 32 P 0 8 0;0,3=7,5=0
P 1.14 3.52 6 P 0 8 0;1,3=1,5=1
P 1.245 3.52 6 P 0 8 0;1,3=1,5=1
P 1.22 3.564 27 P 0 8 0;0,3=0,5=0
P 1.265 3.564 27 P 0 8 0;0,3=0,5=0
P 1.32 3.548 32 P 0 8 0;0,3=7,5=0
P 4.705 3.95 6 P 0 8 0;1,3=4,5=1
P 4.778 3.551 30 P 0 8 0;0,3=0,5=0
P 4.705 3.91 3 P 0 8 0;3=2,5=1
P 4.656 3.895 30 P 0 8 0;0,3=0,5=0
P 4.656 3.94 30 P 0 8 0;0,3=0,5=0
P 1.566 2.95 6 P 0 8 0;1,3=1,5=1
P 1.045 3.77 3 P 0 8 0;3=2,5=1
P 1.515 3.58 3 P 0 8 0;3=2,5=1
P 6.145 4.035 6 P 0 8 0;1,3=1,5=1
P 6.145 4.094 27 P 0 8 0;0,3=0,5=0
P 1.37 3.64 3 P 0 8 0;3=2,5=1
P 1.32 3.602 32 P 0 8 0;0,3=7,5=0
P 1.375 3.601 27 P 0 8 0;0,3=0,5=0
P 1.667 3.438 3 P 0 8 0;3=2,5=1
P 1.7485 3.438 40 P 0 8 0;0,3=8,5=0
P 1.591 3.546 3 P 0 8 0;3=2,5=1
P 1.7485 3.538 40 P 0 8 0;0,3=8,5=0
P 1.63 3.546 27 P 0 8 0;0,3=0,5=0
P 1.13 3.445 3 P 0 8 0;3=2,5=1
P 1.09 3.458 32 P 0 8 0;0,3=7,5=0
P 1.154 3.475 30 P 0 8 0;0,3=0,5=0
P 0.95 3.445 3 P 0 8 0;3=2,5=1
P 0.911 3.455 30 P 0 8 0;0,3=0,5=0
P 2.146 3.36 30 P 0 8 0;0,3=0,5=0
P 2.146 3.55 30 P 0 8 0;0,3=0,5=0
P 2.19 3.488 3 P 0 8 0;3=2,5=1
P 2.146 3.5 30 P 0 8 0;0,3=0,5=0
P 2.192 3.388 3 P 0 8 0;3=2,5=1
P 1.41916004 3.33916004 3 P 0 8 0;3=2,5=1
P 1.407 3.2 3 P 0 8 0;3=2,5=1
P 1.381 3.235 30 P 0 8 0;0,3=0,5=0
P 1.495 3.11033996 3 P 0 8 0;3=2,5=1
P 1.535 3.105 6 P 0 8 0;1,3=3,5=0
P 1.15253002 3.06246998 3 P 0 8 0;3=2,5=1
P 0.95 3.215 3 P 0 8 0;3=2,5=1
P 0.945 3.125 3 P 0 8 0;3=2,5=1
P 0.746 3.245 30 P 0 8 0;0,3=0,5=0
P 0.746 3.2 30 P 0 8 0;0,3=0,5=0
P 1.175 2.9 3 P 0 8 0;3=2,5=1
P 1.025 3.02 3 P 0 8 0;3=2,5=1
P 5.275 3.891 6 P 0 8 0;1,3=1,5=1
P 5.275 3.931 3 P 0 8 0;3=2,5=1
P 5.275 3.971 6 P 0 8 0;1,3=1,5=1
P 5.321 3.99 3 P 0 8 0;3=2,5=1
P 5.762 3.425 6 P 0 8 0;3=9,5=1
P 5.567 3.203 3 P 0 8 0;3=2,5=1
P 5.617 3.203 6 P 0 8 0;1,3=1,5=1
P 5.62 3.316 3 P 0 8 0;3=2,5=1
P 5.625 3.261 6 P 0 8 0;1,3=1,5=1
P 5.625 3.361 3 P 0 8 0;3=2,5=1
P 5.6 3.421 6 P 0 8 0;1,3=1,5=1
P 5.552 3.71141004 2 P 0 8 0;3=10,5=1
P 5.552 3.74683996 2 P 0 8 0;3=10,5=1
P 5.552 3.78226998 2 P 0 8 0;3=10,5=1
P 5.552 3.67596998 2 P 0 8 0;3=10,5=1
P 5.527 3.206 33 P 0 8 0;0,3=11,5=0
P 5.531 3.364 33 P 0 8 0;0,3=11,5=0
P 5.531 3.288 33 P 0 8 0;0,3=11,5=0
P 5.531 3.441 33 P 0 8 0;0,3=11,5=0
P 5.52 3.78226998 2 P 0 8 0;3=10,5=1
P 5.52 3.74683996 2 P 0 8 0;3=10,5=1
P 5.52 3.71141004 2 P 0 8 0;3=10,5=1
P 5.52 3.67596998 2 P 0 8 0;3=10,5=1
P 0.978 3.918 6 P 0 8 0;3=3,5=0
P 0.928 3.961 3 P 0 8 0;3=2,5=1
P 0.968 3.961 3 P 0 8 0;3=2,5=1
P 0.968 4.021 3 P 0 8 0;3=2,5=1
P 0.928 4.021 6 P 0 8 0;3=1,5=1
P 0.928 4.081 3 P 0 8 0;3=2,5=1
P 0.968 4.081 6 P 0 8 0;3=1,5=1
P 0.928 4.141 6 P 0 8 0;3=1,5=1
P 0.968 4.141 3 P 0 8 0;3=2,5=1
P 0.603 3.951 6 P 0 8 0;3=1,5=1
P 0.643 3.956 3 P 0 8 0;3=2,5=1
P 0.603 4.011 3 P 0 8 0;3=2,5=1
P 0.643 4.016 6 P 0 8 0;3=1,5=1
P 0.603 4.071 6 P 0 8 0;3=1,5=1
P 0.643 4.076 3 P 0 8 0;3=2,5=1
P 0.603 4.131 3 P 0 8 0;3=2,5=1
P 0.643 4.136 6 P 0 8 0;3=1,5=1
P 0.854 3.942 3 P 0 8 0;3=2,5=1
P 0.807 3.942 3 P 0 8 0;3=2,5=1
P 0.76 3.942 3 P 0 8 0;3=2,5=1
P 0.713 3.942 3 P 0 8 0;3=2,5=1
P 0.76 4.042 3 P 0 8 0;3=2,5=1
P 0.76 3.992 3 P 0 8 0;3=2,5=1
P 0.713 3.992 3 P 0 8 0;3=2,5=1
P 0.713 4.042 3 P 0 8 0;3=2,5=1
P 0.713 4.092 3 P 0 8 0;3=2,5=1
P 0.76 4.092 3 P 0 8 0;3=2,5=1
P 0.807 4.092 3 P 0 8 0;3=2,5=1
P 0.807 4.042 3 P 0 8 0;3=2,5=1
P 0.807 3.992 3 P 0 8 0;3=2,5=1
P 0.854 3.992 3 P 0 8 0;3=2,5=1
P 0.854 4.042 3 P 0 8 0;3=2,5=1
P 0.854 4.092 3 P 0 8 0;3=2,5=1
P 0.698 0.953 27 P 0 8 0;0,3=0,5=0
P 0.743 0.953 27 P 0 8 0;0,3=0,5=0
P 0.74 1.005 6 P 0 8 0;1,3=1,5=1
P 0.79 1.005 6 P 0 8 0;1,3=1,5=1
P 0.833 0.953 27 P 0 8 0;0,3=0,5=0
P 0.788 0.953 27 P 0 8 0;0,3=0,5=0
P 0.84 1.005 6 P 0 8 0;1,3=1,5=1
P 0.878 0.953 27 P 0 8 0;0,3=0,5=0
P 1.351 0.753 30 P 0 8 0;0,3=0,5=0
P 1.521 3 30 P 0 8 0;0,3=0,5=0
P 1.568 3.011 6 P 0 8 0;1,3=1,5=1
P 1.738 3.241 6 P 0 8 0;1,3=1,5=1
P 1.765 2.9 6 P 0 8 0;1,3=1,5=1
P 1.78 3.095 6 P 0 8 0;1,3=1,5=1
P 1.885 2.939 27 P 0 8 0;0,3=0,5=0
P 1.795 2.946 6 P 0 8 0;1,3=1,5=1
P 5.2 0.87 6 P 0 8 0;1,3=1,5=1
P 4.47 3.21998002 6 P 0 8 0;1,3=1,5=1
P 4.385 3.645 6 P 0 8 0;1,3=1,5=1
P 0.78 3.305 6 P 0 8 0;1,3=3,5=0
P 1.04 3.564 27 P 0 8 0;0,3=0,5=0
P 1.03 3.515 6 P 0 8 0;1,3=1,5=1
P 1.175 3.564 27 P 0 8 0;0,3=0,5=0
P 1.19 3.52 6 P 0 8 0;1,3=1,5=1
P 0.95 2.915 6 P 0 8 0;1,3=3,5=0
P 0.945 2.99 6 P 0 8 0;1,3=3,5=0
P 0.885 3.03 6 P 0 8 0;1,3=3,5=0
P 0.875 2.955 6 P 0 8 0;1,3=3,5=0
P 0.795 3.085 6 P 0 8 0;1,3=3,5=0
P 0.55 3.36 6 P 0 8 0;1,3=1,5=1
P 0.3701 3.4008 4 P 0 8 0;3=6,5=0
P 0.55 3.554 6 P 0 8 0;1,3=1,5=1
P 0.31693996 3.4315 4 P 0 8 0;3=6,5=0
P 5.98 1.581 27 P 0 8 0;0,3=0,5=0
P 5.92 1.57063002 6 P 0 8 0;1,3=1,5=1
P 6.17 1.576 27 P 0 8 0;0,3=0,5=0
P 6.22 1.57 6 P 0 8 0;1,3=1,5=1
P 5.98 1.461 27 P 0 8 0;0,3=0,5=0
P 5.92 1.46 6 P 0 8 0;1,3=1,5=1
P 6.17 1.476 27 P 0 8 0;0,3=0,5=0
P 6.22 1.465 6 P 0 8 0;1,3=1,5=1
P 5.98 1.676 27 P 0 8 0;0,3=0,5=0
P 5.92 1.68 6 P 0 8 0;1,3=1,5=1
P 6.17 1.676 27 P 0 8 0;0,3=0,5=0
P 6.22035 1.67063002 6 P 0 8 0;1,3=1,5=1
P 5.98 1.781 27 P 0 8 0;0,3=0,5=0
P 5.92 1.78 6 P 0 8 0;1,3=1,5=1
P 6.155 1.769 27 P 0 8 0;0,3=0,5=0
P 6.22 1.755 6 P 0 8 0;1,3=1,5=1
P 6.145 4.136 27 P 0 8 0;0,3=0,5=0
P 6.09423996 4.13778996 6 P 0 8 0;1,3=1,5=1
P 3.51 3.08 6 P 0 8 0;1,3=1,5=1
P 1.025 2.9 3 P 0 8 0;3=2,5=1
P 3.46 3.065 6 P 0 8 0;1,3=1,5=1
P 1.125 2.9 3 P 0 8 0;3=2,5=1
P 3.035 1.64 3 P 0 8 0;3=2,5=1
P 3.445 2.65 6 P 0 8 0;1,3=3,5=0
P 1.1737 0.7086 30 P 0 8 0;0,3=0,5=0
P 1.08 0.718 30 P 0 8 0;0,3=0,5=0
P 1.1288 0.7302 6 P 0 8 0;1,3=9,5=1
P 3.075 1.605 3 P 0 8 0;3=2,5=1
P 3.365 2.95 6 P 0 8 0;1,3=4,5=1
P 0.847 0.71 30 P 0 8 0;0,3=0,5=0
P 0.755 0.62 6 P 0 8 0;3=3,5=0
P 0.799 0.711 27 P 0 8 0;0,3=0,5=0
P 0.809 0.665 30 P 0 8 0;0,3=0,5=0
P 0.721 0.817 27 P 0 8 0;0,3=0,5=0
P 0.715 0.77 6 P 0 8 0;1,3=1,5=1
P 0.869 3.41 30 P 0 8 0;0,3=0,5=0
P 0.83 3.445 6 P 0 8 0;1,3=1,5=1
P 0.869 3.455 30 P 0 8 0;0,3=0,5=0
P 0.869 3.5 30 P 0 8 0;0,3=0,5=0
P 0.795 3.485 6 P 0 8 0;1,3=1,5=1
P 0.882 3.553 27 P 0 8 0;0,3=0,5=0
P 0.83 3.525 6 P 0 8 0;1,3=1,5=1
P 0.95 3.564 27 P 0 8 0;0,3=0,5=0
P 0.951 3.519 6 P 0 8 0;1,3=1,5=1
P 0.82951004 3.2794 6 P 0 8 0;1,3=1,5=1
P 0.746 3.155 30 P 0 8 0;0,3=0,5=0
P 0.79 3.155 6 P 0 8 0;1,3=1,5=1
P 0.78635 3.24491998 6 P 0 8 0;1,3=1,5=1
P 1.28 3.136 27 P 0 8 0;0,3=0,5=0
P 1.26 3.18 6 P 0 8 0;1,3=1,5=1
P 1.339 3.235 30 P 0 8 0;0,3=0,5=0
P 1.339 3.28 30 P 0 8 0;0,3=0,5=0
P 1.295 3.28 6 P 0 8 0;1,3=1,5=1
P 1.075 3.02 6 P 0 8 0;1,3=1,5=1
P 1.125 3.02 6 P 0 8 0;1,3=1,5=1
P 1.073 3.825 2 P 0 8 0;3=12,5=1
P 0.703 3.575 2 P 0 8 0;3=12,5=1
P 0.35238002 3.4315 4 P 0 8 0;3=6,5=0
P 0.33466004 3.4008 4 P 0 8 0;3=6,5=0
P 0.735 3.575 2 P 0 8 0;3=12,5=1
P 1.105 3.825 2 P 0 8 0;3=12,5=1
P 0.38781998 3.4315 4 P 0 8 0;3=6,5=0
P 0.29921998 3.4008 4 P 0 8 0;3=6,5=0
P 1.04 3.606 27 P 0 8 0;0,3=0,5=0
P 1.055 3.689 27 P 0 8 0;0,3=0,5=0
P 0.995 3.7 6 P 0 8 0;1,3=3,5=0
P 0.995 3.606 27 P 0 8 0;0,3=0,5=0
P 4.285 3.46 3 P 0 8 0;3=2,5=1
P 2.05 3.375 6 P 0 8 0;1,3=13,5=1
P 2.105 3.409 27 P 0 8 0;0,3=0,5=0
P 2.104 3.36 30 P 0 8 0;0,3=0,5=0
P 1.9695 3.388 40 P 0 8 0;0,3=8,5=0
P 2.105 3.451 27 P 0 8 0;0,3=0,5=0
P 2.15 3.438 6 P 0 8 0;1,3=1,5=1
P 1.9695 3.438 40 P 0 8 0;0,3=8,5=0
P 2.05 3.538 6 P 0 8 0;1,3=1,5=1
P 1.9695 3.538 40 P 0 8 0;0,3=8,5=0
P 2.104 3.55 30 P 0 8 0;0,3=0,5=0
P 2.05 3.488 6 P 0 8 0;1,3=1,5=1
P 1.9695 3.488 40 P 0 8 0;0,3=8,5=0
P 2.104 3.5 30 P 0 8 0;0,3=0,5=0
P 1.29 3.215 3 P 0 8 0;3=2,5=1
P 1.035 3.136 27 P 0 8 0;0,3=0,5=0
P 1.0541 3.185 6 P 0 8 0;1,3=1,5=1
P 1.334 3.5 30 P 0 8 0;0,3=0,5=0
P 1.3 3.49663996 3 P 0 8 0;3=2,5=1
P 1.04018996 3.47425 3 P 0 8 0;3=2,5=1
P 4.205 3.66 6 P 0 8 0;1,3=1,5=1
P 0.911 3.41 30 P 0 8 0;0,3=0,5=0
P 0.975 3.41 3 P 0 8 0;3=2,5=1
P 4.225 3.545 6 P 0 8 0;1,3=1,5=1
P 1.015 3.41 3 P 0 8 0;3=2,5=1
P 0.911 3.5 30 P 0 8 0;0,3=0,5=0
P 3.95 3.6 6 P 0 8 0;1,3=1,5=1
P 0.835 3.6 3 P 0 8 0;3=2,5=1
P 0.882 3.595 27 P 0 8 0;0,3=0,5=0
P 3.95 3.7 6 P 0 8 0;1,3=1,5=1
P 0.95 3.606 27 P 0 8 0;0,3=0,5=0
P 0.915 3.595 3 P 0 8 0;3=2,5=1
P 4.1184 3.5362 3 P 0 8 0;3=2,5=1
P 4.085 3.11 6 P 0 8 0;1,3=1,5=1
P 4.51 3.065 3 P 0 8 0;3=2,5=1
P 4.33381998 3.60466004 6 P 0 8 0;1,3=1,5=1
P 4.34 3.28 3 P 0 8 0;3=2,5=1
P 4.335 3.665 6 P 0 8 0;1,3=1,5=1
P 4.09 3.71338996 6 P 0 8 0;1,3=1,5=1
P 3.38 1.025 3 P 0 8 0;3=2,5=1
P 4.585 0.865 6 P 0 8 0;1,3=1,5=1
P 0.62 3.235 3 P 0 8 0;3=2,5=1
P 3.925 3.239 6 P 0 8 0;1,3=1,5=1
P 0.825 3.39 3 P 0 8 0;3=2,5=1
P 0.795 3.4179 3 P 0 8 0;3=2,5=1
P 3.795 3.758 6 P 0 8 0;1,3=1,5=1
P 3.62 1.28 3 P 0 8 0;3=2,5=1
P 5.195 0.755 6 P 0 8 0;1,3=1,5=1
P 4.96 0.85 3 P 0 8 0;3=2,5=1
P 0.66 3.185 3 P 0 8 0;3=2,5=1
P 0.704 3.155 30 P 0 8 0;0,3=0,5=0
P 0.704 3.2 30 P 0 8 0;0,3=0,5=0
P 3.62 1.235 3 P 0 8 0;3=2,5=1
P 5.195 0.815 6 P 0 8 0;1,3=1,5=1
P 4.937 0.79161004 3 P 0 8 0;3=2,5=1
P 0.704 3.245 30 P 0 8 0;0,3=0,5=0
P 0.66 3.235 3 P 0 8 0;3=2,5=1
P 4.205 3.81 3 P 0 8 0;3=2,5=1
P 5.814 2.821 6 P 0 8 0;1,3=9,5=1
P 5.6705 2.9225 34 P 0 8 0;0,3=14,5=0
P 5.544 2.9225 30 P 0 8 0;0,3=0,5=0
P 4.19 3.735 3 P 0 8 0;3=2,5=1
P 5.546 2.77 30 P 0 8 0;0,3=0,5=0
P 5.6755 2.7245 34 P 0 8 0;0,3=14,5=0
P 5.814 2.721 6 P 0 8 0;1,3=9,5=1
P 3.895 3.7 3 P 0 8 0;3=2,5=1
P 5.546 3.02 30 P 0 8 0;0,3=0,5=0
P 5.6705 3.0095 34 P 0 8 0;0,3=14,5=0
P 5.815 3.021 6 P 0 8 0;1,3=9,5=1
P 4.135 3.735 3 P 0 8 0;3=2,5=1
P 5.6755 2.6375 34 P 0 8 0;0,3=14,5=0
P 5.546 2.64 30 P 0 8 0;0,3=0,5=0
P 5.814 2.621 6 P 0 8 0;1,3=9,5=1
P 2.3 3.475 3 P 0 8 0;3=2,5=1
P 5.045 3.405 3 P 0 8 0;3=2,5=1
P 6.33 2.67 6 P 0 8 0;1,3=9,5=1
P 1.28 3.094 27 P 0 8 0;0,3=0,5=0
P 1.35 3.12 3 P 0 8 0;3=2,5=1
P 2.255 3.475 3 P 0 8 0;3=2,5=1
P 5.09 3.405 3 P 0 8 0;3=2,5=1
P 6.33 2.865 6 P 0 8 0;1,3=1,5=1
P 1.381 3.28 30 P 0 8 0;0,3=0,5=0
P 1.46 3.34 3 P 0 8 0;3=2,5=1
P 4.575 2.235 3 P 0 8 0;3=2,5=1
P 4.705 0.825 6 P 0 8 0;1,3=1,5=1
P 4.575 2.275 3 P 0 8 0;3=2,5=1
P 4.755 0.825 6 P 0 8 0;1,3=1,5=1
P 1.26 0.72 6 P 0 8 0;1,3=1,5=1
P 1.2157 0.7086 30 P 0 8 0;0,3=0,5=0
P 0.842 0.75 6 P 0 8 0;1,3=1,5=1
P 0.799 0.753 27 P 0 8 0;0,3=0,5=0
P 4.10816004 1.90248002 6 P 0 8 0;1,3=5,5=1
P 3.73648996 1.85735 3 P 0 8 0;3=2,5=1
P 4.345 3.02 3 P 0 8 0;3=2,5=1
P 4.075 3.005 3 P 0 8 0;3=2,5=1
P 3.925 3.291 6 P 0 8 0;1,3=1,5=1
P 4.39 3.02 3 P 0 8 0;3=2,5=1
P 4.13 3.005 3 P 0 8 0;3=2,5=1
P 3.795 3.81 6 P 0 8 0;1,3=1,5=1
P 4.615 3.11 3 P 0 8 0;3=2,5=1
P 4.4 3.325 6 P 0 8 0;1,3=1,5=1
P 4.615 2.68408996 3 P 0 8 0;3=2,5=1
P 4.15 2.51 27 P 0 8 0;0,3=0,5=0
P 4.15 2.468 3 P 0 8 0;3=2,5=1
P 6.17 1.434 27 P 0 8 0;0,3=0,5=0
P 6.22 1.415 6 P 0 8 0;1,3=1,5=1
P 4.685 2.7 3 P 0 8 0;3=2,5=1
P 4.209 2.468 3 P 0 8 0;3=2,5=1
P 4.209 2.51 27 P 0 8 0;0,3=0,5=0
P 6.22 1.516 6 P 0 8 0;1,3=1,5=1
P 6.17 1.534 27 P 0 8 0;0,3=0,5=0
P 4.975 2.26 3 P 0 8 0;3=2,5=1
P 4.093 2.468 3 P 0 8 0;3=2,5=1
P 4.093 2.51 27 P 0 8 0;0,3=0,5=0
P 6.17 1.634 27 P 0 8 0;0,3=0,5=0
P 6.22 1.62 6 P 0 8 0;1,3=1,5=1
P 4.925 2.26 6 P 0 8 0;1,3=1,5=1
P 4.037 2.468 3 P 0 8 0;3=2,5=1
P 4.037 2.51 27 P 0 8 0;0,3=0,5=0
P 6.155 1.811 27 P 0 8 0;0,3=0,5=0
P 6.22 1.815 6 P 0 8 0;1,3=1,5=1
P 5.92 1.41 6 P 0 8 0;1,3=1,5=1
P 5.98 1.419 27 P 0 8 0;0,3=0,5=0
P 5.09 2.155 3 P 0 8 0;3=2,5=1
P 3.801 2.468 3 P 0 8 0;3=2,5=1
P 3.801 2.51 27 P 0 8 0;0,3=0,5=0
P 5.98 1.539 27 P 0 8 0;0,3=0,5=0
P 5.92 1.515 6 P 0 8 0;1,3=1,5=1
P 5.135 2.155 3 P 0 8 0;3=2,5=1
P 3.86 2.468 3 P 0 8 0;3=2,5=1
P 3.86 2.51 27 P 0 8 0;0,3=0,5=0
P 5.92 1.63 6 P 0 8 0;1,3=1,5=1
P 5.98 1.634 27 P 0 8 0;0,3=0,5=0
P 5.115 2.065 3 P 0 8 0;3=2,5=1
P 3.919 2.468 3 P 0 8 0;3=2,5=1
P 3.919 2.51 27 P 0 8 0;0,3=0,5=0
P 5.98 1.739 27 P 0 8 0;0,3=0,5=0
P 5.92 1.73 6 P 0 8 0;1,3=1,5=1
P 5.13 2.105 3 P 0 8 0;3=2,5=1
P 3.978 2.468 3 P 0 8 0;3=2,5=1
P 3.978 2.51 27 P 0 8 0;0,3=0,5=0
P 4.685 2.645 3 P 0 8 0;3=2,5=1
P 4.1 3.38 6 P 0 8 0;1,3=1,5=1
P 4.53 2.5 3 P 0 8 0;3=2,5=1
P 3.9 3.385 6 P 0 8 0;1,3=1,5=1
P 4.485 3.115 6 P 0 8 0;1,3=1,5=1
P 4.575 2.374 3 P 0 8 0;3=2,5=1
P 4.485 2.5 3 P 0 8 0;3=2,5=1
P 4.29441998 3.10075 6 P 0 8 0;1,3=1,5=1
P 4.61 2.345 3 P 0 8 0;3=2,5=1
P 4.54 3.125 6 P 0 8 0;1,3=1,5=1
P 4.085 3.21998002 6 P 0 8 0;1,3=1,5=1
P 4.35 2.461 27 P 0 8 0;0,3=0,5=0
P 4.35 2.505 3 P 0 8 0;3=2,5=1
P 5.365 0.79 6 P 0 8 0;1,3=1,5=1
P 5.365 0.845 6 P 0 8 0;1,3=1,5=1
P 4.0661 3.5341 6 P 0 8 0;1,3=1,5=1
P 3.506 3.235 30 P 0 8 0;0,3=0,5=0
P 3.744 3.415 30 P 0 8 0;0,3=0,5=0
P 3.83 3.466 6 P 0 8 0;1,3=9,5=1
P 4.35143002 3.06643002 3 P 0 8 0;3=2,5=1
P 3.7 3.325 6 P 0 8 0;1,3=1,5=1
P 3.744 3.325 30 P 0 8 0;0,3=0,5=0
P 3.5825 3.4005 6 P 0 8 0;1,3=4,5=1
P 3.506 3.415 30 P 0 8 0;0,3=0,5=0
P 4.33 3.1432 3 P 0 8 0;3=2,5=1
P 3.786 3.235 30 P 0 8 0;0,3=0,5=0
P 3.83 3.235 6 P 0 8 0;1,3=1,5=1
P 4.085 3.165 3 P 0 8 0;3=2,5=1
P 3.464 3.325 30 P 0 8 0;0,3=0,5=0
P 3.415 3.335 6 P 0 8 0;1,3=4,5=1
P 0.74 1.3 3 P 0 8 0;3=2,5=1
P 1.3085 0.658 30 P 0 8 0;0,3=0,5=0
P 1.2158 0.6587 30 P 0 8 0;0,3=0,5=0
P 1.26 0.62 6 P 0 8 0;1,3=9,5=1
P 0.721 0.859 27 P 0 8 0;0,3=0,5=0
P 0.785 0.8225 3 P 0 8 0;3=2,5=1
P 0.695 1.3 3 P 0 8 0;3=2,5=1
P 1.3087 0.708 30 P 0 8 0;0,3=0,5=0
P 1.26 0.67 6 P 0 8 0;1,3=9,5=1
P 0.76321004 0.783 3 P 0 8 0;3=2,5=1
P 3.32 3.015 6 P 0 8 0;1,3=3,5=0
P 3.485 2.864 27 P 0 8 0;0,3=0,5=0
P 3.44 2.864 27 P 0 8 0;0,3=0,5=0
P 3.24 3.01 6 P 0 8 0;1,3=3,5=0
P 3.395 2.906 27 P 0 8 0;0,3=0,5=0
P 3.35 2.906 27 P 0 8 0;0,3=0,5=0
P 1.7485 3.488 40 P 0 8 0;0,3=8,5=0
P 0.606 1.57 6 P 0 8 0;1,3=1,5=1
P 0.674 1.495 30 P 0 8 0;0,3=0,5=0
P 0.835 1.73 6 P 0 8 0;1,3=1,5=1
P 0.85 1.684 30 P 0 8 0;0,3=0,5=0
P 0.355 3.27 6 P 0 8 0;1,3=1,5=1
P 0.28 3.27 6 P 0 8 0;1,3=1,5=1
P 0.13 3.187 6 P 0 8 0;1,3=1,5=1
P 0.69023002 1.98523996 3 P 0 8 0;3=2,5=1
P 0.125 2.195 6 P 0 8 0;1,3=1,5=1
P 0.69 1.93 3 P 0 8 0;3=2,5=1
P 0.125 2.145 6 P 0 8 0;1,3=1,5=1
P 0.69 1.875 3 P 0 8 0;3=2,5=1
P 0.125 2.045 6 P 0 8 0;1,3=1,5=1
P 0.13 2.73326998 6 P 0 8 0;1,3=1,5=1
P 0.287 2.743 6 P 0 8 0;1,3=1,5=1
P 0.125 2.615 6 P 0 8 0;1,3=1,5=1
P 0.735 1.19 3 P 0 8 0;3=2,5=1
P 0.125 1.06 6 P 0 8 0;1,3=1,5=1
P 0.68 1.19 3 P 0 8 0;3=2,5=1
P 0.125 1.01 6 P 0 8 0;1,3=1,5=1
P 0.675 1.145 3 P 0 8 0;3=2,5=1
P 0.125 0.91 6 P 0 8 0;1,3=1,5=1
P 0.125 1.62 6 P 0 8 0;1,3=1,5=1
P 0.13 1.57 6 P 0 8 0;1,3=1,5=1
P 0.1362 1.4872 6 P 0 8 0;1,3=1,5=1
P 2.937 3.173 6 P 0 8 0;1,3=1,5=1
P 3.01 3.17 3 P 0 8 0;3=2,5=1
P 3.026 3.21 30 P 0 8 0;0,3=0,5=0
P 3.026 3.26 30 P 0 8 0;0,3=0,5=0
P 0.896 2.489 6 P 0 8 0;1,3=4,5=1
P 0.896 2.444 27 P 0 8 0;0,3=0,5=0
P 4.31168996 4.01168996 6 P 0 8 0;1,3=4,5=1
P 4.319 3.922 6 P 0 8 0;1,3=4,5=1
P 4.5 4.115 6 P 0 8 0;1,3=1,5=1
P 1.315 2.905 2 P 0 8 0;3=10,5=1
P 2.932 3.295 2 P 0 8 0;3=10,5=1
P 0.915 1.4 3 P 0 8 0;3=2,5=1
P 1.42 0.69535 6 P 0 8 0;1,3=9,5=1
P 4.5 4.165 6 P 0 8 0;1,3=1,5=1
P 1.36 2.905 2 P 0 8 0;3=10,5=1
P 2.896 3.301 2 P 0 8 0;3=10,5=1
P 0.965 1.4 3 P 0 8 0;3=2,5=1
P 1.4207 0.779 6 P 0 8 0;1,3=9,5=1
P 4.65933002 2.02058996 6 P 0 8 0;1,3=5,5=1
P 4.33 3.535 3 P 0 8 0;3=2,5=1
P 4.396 3.865 30 P 0 8 0;0,3=0,5=0
P 4.396 4.065 30 P 0 8 0;0,3=0,5=0
P 4.44 4.065 6 P 0 8 0;1,3=4,5=1
P 4.395 3.415 2 P 0 8 0;3=10,5=1
P 4.396 4.115 30 P 0 8 0;0,3=0,5=0
P 4.44 4.115 6 P 0 8 0;1,3=4,5=1
P 4.425 3.36088996 2 P 0 8 0;3=10,5=1
P 0.638 2.74 2 P 0 8 0;3=10,5=1
P 0.805 2.402 27 P 0 8 0;0,3=0,5=0
P 0.825 2.305 6 P 0 8 0;1,3=4,5=1
P 0.755 2.825 2 P 0 8 0;3=10,5=1
P 0.76 2.402 27 P 0 8 0;0,3=0,5=0
P 0.795 2.345 6 P 0 8 0;1,3=4,5=1
P 6.025 4.131 27 P 0 8 0;0,3=0,5=0
P 5.97613002 4.13778996 6 P 0 8 0;1,3=1,5=1
P 5.91 4.131 27 P 0 8 0;0,3=0,5=0
P 5.90748002 4.18725 6 P 0 8 0;1,3=1,5=1
P 0.905 1.935 6 P 0 8 0;1,3=1,5=1
P 0.945 1.97 6 P 0 8 0;1,3=1,5=1
P 0.905 1.885 6 P 0 8 0;1,3=1,5=1
P 0.63 2.15 3 P 0 8 0;3=2,5=1
P 0.985 2.185 6 P 0 8 0;1,3=1,5=1
P 0.287 2.62508002 3 P 0 8 0;3=2,5=1
P 0.43 2.555 6 P 0 8 0;1,3=1,5=1
P 0.63 2.105 3 P 0 8 0;3=2,5=1
P 0.99 2.015 3 P 0 8 0;3=2,5=1
P 0.242 2.62508002 6 P 0 8 0;1,3=1,5=1
P 0.63 2.06 3 P 0 8 0;3=2,5=1
P 0.99 1.975 3 P 0 8 0;3=2,5=1
P 0.935 1.3 6 P 0 8 0;1,3=1,5=1
P 0.87 1.255 6 P 0 8 0;1,3=1,5=1
P 0.935 1.25 6 P 0 8 0;1,3=1,5=1
P 0.92 1.73 6 P 0 8 0;1,3=1,5=1
P 0.281 1.48798002 3 P 0 8 0;3=2,5=1
P 0.985 1.655 6 P 0 8 0;1,3=1,5=1
P 0.371 1.48798002 3 P 0 8 0;3=2,5=1
P 0.985 1.59 6 P 0 8 0;1,3=1,5=1
P 0.236 1.48798002 3 P 0 8 0;3=2,5=1
P 0.345 3.09 3 P 0 8 0;3=2,5=1
P 3.84091004 2.00091004 6 P 0 8 0;1,3=1,5=1
P 0.99 1.885 3 P 0 8 0;3=2,5=1
P 0.395 3.09 3 P 0 8 0;3=2,5=1
P 3.87193002 2.09933002 6 P 0 8 0;1,3=5,5=1
P 0.99 2.065 3 P 0 8 0;3=2,5=1
P 0.445 3.09 6 P 0 8 0;1,3=1,5=1
P 0.975 2.14 3 P 0 8 0;3=2,5=1
P 0.53 2.049 27 P 0 8 0;0,3=0,5=0
P 0.53 2.005 6 P 0 8 0;1,3=1,5=1
P 0.53 2.584 27 P 0 8 0;0,3=0,5=0
P 0.552 2.535 6 P 0 8 0;1,3=1,5=1
P 0.455 1.825 6 P 0 8 0;1,3=1,5=1
P 0.16038996 1.85433002 9 P 0 8 0;3=15,5=0
P 0.46 2.195 6 P 0 8 0;1,3=1,5=1
P 0.16038996 2.4252 9 P 0 8 0;1,3=15,5=0
P 0.445 0.735 6 P 0 8 0;1,3=1,5=1
P 0.53 0.697 27 P 0 8 0;0,3=0,5=0
P 0.16038996 0.7126 9 P 0 8 0;1,3=15,5=0
P 0.455 1.0439 6 P 0 8 0;1,3=1,5=1
P 0.16038996 1.28346004 9 P 0 8 0;3=15,5=0
P 0.535 1.835 6 P 0 8 0;1,3=1,5=1
P 0.532 2.40186998 6 P 0 8 0;1,3=1,5=1
P 0.53 0.655 27 P 0 8 0;0,3=0,5=0
P 0.505 0.60228002 6 P 0 8 0;1,3=1,5=1
P 0.5374 1.26 6 P 0 8 0;1,3=1,5=1
P 0.48 2.005 6 P 0 8 0;1,3=1,5=1
P 0.485 2.525 6 P 0 8 0;1,3=1,5=1
P 0.515 0.835 6 P 0 8 0;1,3=1,5=1
P 0.475 1.405 6 P 0 8 0;1,3=1,5=1
P 6.379 0.965 30 P 0 8 0;0,3=0,5=0
P 6.335 0.965 6 P 0 8 0;1,3=1,5=1
P 6.379 1.02 30 P 0 8 0;0,3=0,5=0
P 6.335 1.02 6 P 0 8 0;1,3=1,5=1
P 6.379 1.08 30 P 0 8 0;0,3=0,5=0
P 6.335 1.08 6 P 0 8 0;1,3=1,5=1
P 2.085 3.017 6 P 0 8 0;1,3=9,5=1
P 2.083 2.973 27 P 0 8 0;0,3=0,5=0
P 2.135 3.017 6 P 0 8 0;1,3=9,5=1
P 2.128 2.973 27 P 0 8 0;0,3=0,5=0
P 2.185 3.017 6 P 0 8 0;1,3=9,5=1
P 2.173 2.973 27 P 0 8 0;0,3=0,5=0
P 2.9715 2.278 38 P 0 8 0;0,3=16,5=0
P 2.9665 2.18 38 P 0 8 0;0,3=16,5=0
P 2.925 2.2285 6 P 0 8 0;1,3=13,5=1
P 2.91 2.299 27 P 0 8 0;0,3=0,5=0
P 3.0585 2.315 38 P 0 8 0;0,3=16,5=0
P 2.95 2.13 6 P 0 8 0;1,3=13,5=1
P 2.845 2.222 32 P 0 8 0;0,3=7,5=0
P 2.85 2.277 37 P 0 8 0;0,3=11,5=0
P 6.0085 1.1235 6 P 0 8 0;1,3=1,5=1
P 2.22 3.3 6 P 0 8 0;1,3=9,5=1
P 5.8 1.048 6 P 0 8 0;1,3=3,5=0
P 5.285 2.99 2 P 0 8 0;3=10,5=1
P 3.125 3.075 3 P 0 8 0;3=2,5=1
P 2.017 3.279 6 P 0 8 0;1,3=3,5=0
P 0.636 2.915 6 P 0 8 0;3=3,5=0
P 0.5505 2.9772 39 P 0 8 0;0,3=17,5=0
P 0.699 2.915 30 P 0 8 0;0,3=0,5=0
P 2.97 3.105 6 P 0 8 0;1,3=1,5=1
P 5.91 2.785 6 P 0 8 0;1,3=1,5=1
P 5.994 2.79 30 P 0 8 0;0,3=0,5=0
P 5.994 2.615 30 P 0 8 0;0,3=0,5=0
P 5.91 2.615 6 P 0 8 0;1,3=9,5=1
P 5.91 2.915 6 P 0 8 0;1,3=1,5=1
P 5.91 2.715 6 P 0 8 0;1,3=1,5=1
P 0.54 2.135 3 P 0 8 0;3=2,5=1
P 0.67 1.09 6 P 0 8 0;1,3=1,5=1
P 4.67901998 2.07965 5 P 0 8 0;0,3=18,5=0
P 0.45 2.13 3 P 0 8 0;3=2,5=1
P 0.965 2.355 6 P 0 8 0;1,3=1,5=1
P 0.735 1.125 6 P 0 8 0;1,3=1,5=1
P 0.48231998 2.6453 3 P 0 8 0;3=2,5=1
P 4.71838996 2.11901998 5 P 0 8 0;0,3=18,5=0
P 1.005 2.8473 6 P 0 8 0;1,3=13,5=1
P 3.755 3.505 2 P 0 8 0;3=10,5=1
P 0.525 2.78 3 P 0 8 0;3=2,5=1
P 4.6 0.76 3 P 0 8 0;3=2,5=1
P 0.905 1.05 3 P 0 8 0;3=2,5=1
P 4.175 0.75 3 P 0 8 0;3=2,5=1
P 0.51765 0.966 6 P 0 8 0;1,3=4,5=1
P 2.078 0.8301 3 P 0 8 0;3=2,5=1
P 4.639 1.755 30 P 0 8 0;0,3=0,5=0
P 0.46 0.82 6 P 0 8 0;1,3=4,5=1
P 0.5413 1.525 6 P 0 8 0;1,3=1,5=1
P 0.625 1.005 3 P 0 8 0;3=2,5=1
P 4.67901004 1.68595 5 P 0 8 0;0,3=18,5=0
P 0.935 1.105 6 P 0 8 0;1,3=1,5=1
P 0.4839 1.28311998 3 P 0 8 0;3=2,5=1
P 1.128 0.666 6 P 0 8 0;1,3=4,5=1
P 6.027 4.261 27 P 0 8 0;0,3=0,5=0
P 5.97613002 4.27558002 6 P 0 8 0;1,3=1,5=1
P 0.945 1.63 3 P 0 8 0;3=2,5=1
P 0.635 0.845 6 P 0 8 0;1,3=3,5=0
P 0.975 1.72 3 P 0 8 0;3=2,5=1
P 0.644 0.7 6 P 0 8 0;1,3=3,5=0
P 0.555 0.59 6 P 0 8 0;1,3=1,5=1
P 0.577 0.655 27 P 0 8 0;0,3=0,5=0
P 3.935 3.91 6 P 0 8 0;1,3=9,5=1
P 0.835 1.885 3 P 0 8 0;3=2,5=1
P 3.885 3.91 6 P 0 8 0;1,3=9,5=1
P 0.835 1.93 3 P 0 8 0;3=2,5=1
P 3.985 3.91 6 P 0 8 0;1,3=9,5=1
P 0.835 1.78 3 P 0 8 0;3=2,5=1
P 0.645 1.295 6 P 0 8 0;1,3=3,5=0
P 0.955 1.92 3 P 0 8 0;3=2,5=1
P 0.565 1.13 6 P 0 8 0;3=3,5=0
P 0.885 1.49 6 P 0 8 0;1,3=1,5=1
P 0.99 1.755 3 P 0 8 0;3=2,5=1
P 3.935 4 2 P 0 8 0;3=10,5=1
P 0.332 2.62508002 6 P 0 8 0;1,3=1,5=1
P 3.885 4 2 P 0 8 0;3=10,5=1
P 0.405 2.62 6 P 0 8 0;1,3=1,5=1
P 3.985 4 2 P 0 8 0;3=10,5=1
P 0.19 2.625 6 P 0 8 0;1,3=1,5=1
P 0.62 1.995 6 P 0 8 0;1,3=3,5=0
P 0.75 1.417 3 P 0 8 0;3=2,5=1
P 0.952 1.51 6 P 0 8 0;1,3=1,5=1
P 0.545 1.71 6 P 0 8 0;3=3,5=0
P 0.415 1.275 3 P 0 8 0;3=2,5=1
P 0.87 1.2 3 P 0 8 0;3=2,5=1
P 0.7558 4.19003996 6 P 0 8 0;1,3=9,5=1
P 3.98 4.185 2 P 0 8 0;3=10,5=1
P 0.465 1.33 3 P 0 8 0;3=2,5=1
P 0.87 1.3 3 P 0 8 0;3=2,5=1
P 0.705 4.19 6 P 0 8 0;1,3=9,5=1
P 4.03 4.185 2 P 0 8 0;3=10,5=1
P 0.41408996 1.32591004 3 P 0 8 0;3=2,5=1
P 0.89 1.105 3 P 0 8 0;3=2,5=1
P 0.805 4.205 6 P 0 8 0;1,3=1,5=1
P 3.93 4.185 2 P 0 8 0;3=10,5=1
P 0.647 2.517 6 P 0 8 0;1,3=3,5=0
P 0.939 1.552 3 P 0 8 0;3=2,5=1
P 0.575 2.265 6 P 0 8 0;3=3,5=0
P 0.957 2.275 6 P 0 8 0;1,3=1,5=1
P 4.168 4.24 2 P 0 8 0;3=10,5=1
P 0.855 4.205 2 P 0 8 0;3=10,5=1
P 0.15 2.79 6 P 0 8 0;1,3=1,5=1
P 0.326 1.487 3 P 0 8 0;3=2,5=1
P 0.09 2.86 6 P 0 8 0;1,3=1,5=1
P 0.9 4.205 2 P 0 8 0;3=10,5=1
P 4.22336998 4.24 2 P 0 8 0;3=10,5=1
P 0.416 1.48798002 3 P 0 8 0;3=2,5=1
P 0.09 2.79 6 P 0 8 0;1,3=1,5=1
P 0.98 4.2 2 P 0 8 0;3=10,5=1
P 4.14 4.19 2 P 0 8 0;3=10,5=1
P 0.191 1.48798002 3 P 0 8 0;3=2,5=1
P 4.10463002 3.83 6 P 0 8 0;1,3=9,5=1
P 0.33 3.145 3 P 0 8 0;3=2,5=1
P 4.05463002 3.83 6 P 0 8 0;1,3=9,5=1
P 0.43 3.145 3 P 0 8 0;3=2,5=1
P 4.15463002 3.83 6 P 0 8 0;1,3=9,5=1
P 0.18 3.145 3 P 0 8 0;3=2,5=1
P 0.869 2.672 3 P 0 8 0;3=2,5=1
P 0.871 2.713 6 P 0 8 0;1,3=4,5=1
P 0.686 2.74 2 P 0 8 0;3=10,5=1
P 0.64248002 2.58 3 P 0 8 0;3=2,5=1
P 0.736 2.525 2 P 0 8 0;3=10,5=1
P 0.714 2.329 3 P 0 8 0;3=2,5=1
P 3.429 2.468 6 P 0 8 0;1,3=4,5=1
P 3.47 2.334 27 P 0 8 0;0,3=0,5=0
P 3.51 2.33243002 3 P 0 8 0;3=2,5=1
P 3.278 2.468 6 P 0 8 0;1,3=4,5=1
P 3.243 2.547 6 P 0 8 0;1,3=4,5=1
P 3.385 2.135 6 P 0 8 0;1,3=3,5=0
P 3.24 2.36 6 P 0 8 0;1,3=4,5=1
P 3.285 2.38645 6 P 0 8 0;1,3=4,5=1
P 0.832 2.603 6 P 0 8 0;1,3=1,5=1
P 0.77963996 2.601 6 P 0 8 0;1,3=4,5=1
P 0.695 2.578 6 P 0 8 0;1,3=1,5=1
P 0.72 2.714 6 P 0 8 0;1,3=4,5=1
P 0.858 2.789 27 P 0 8 0;0,3=0,5=0
P 0.825 2.732 6 P 0 8 0;1,3=4,5=1
P 6.01953002 2.18853002 6 P 0 8 0;1,3=1,5=1
P 4.366 2.975 30 P 0 8 0;0,3=0,5=0
P 4.415 2.975 6 P 0 8 0;1,3=4,5=1
P 6.14 4.261 27 P 0 8 0;0,3=0,5=0
P 6.09423996 4.27558002 6 P 0 8 0;1,3=1,5=1
P 2.645 2.14 6 P 0 8 0;1,3=13,5=1
P 2.6526 2.1935 25 P 0 8 0;0,3=19,5=0
P 2.641 2.375 30 P 0 8 0;0,3=0,5=0
P 0.959 2.789 3 P 0 8 0;3=2,5=1
P 0.845 2.18 6 P 0 8 0;1,3=1,5=1
P 0.908 2.789 27 P 0 8 0;0,3=0,5=0
P 5.955 2.39 6 P 0 8 0;1,3=3,5=0
P 5.94153002 2.205 6 P 0 8 0;1,3=9,5=1
P 6.01901998 2.001 6 P 0 8 0;1,3=9,5=1
P 5.87 1.84 6 P 0 8 0;3=3,5=0
P 3.4593 2.17 6 P 0 8 0;1,3=9,5=1
P 3.419 2.21 30 P 0 8 0;0,3=0,5=0
P 3.44 2.12 6 P 0 8 0;1,3=1,5=1
P 3.371 2.21 30 P 0 8 0;0,3=0,5=0
P 3.18 2.685 6 P 0 8 0;1,3=4,5=1
P 3.523 1.75 2 P 0 8 0;3=10,5=1
P 4.712 1.157 6 P 0 8 0;1,3=3,5=0
P 4.61996004 1.6269 6 P 0 8 0;1,3=3,5=0
P 4.29 1.235 6 P 0 8 0;1,3=3,5=0
P 4.15 1.235 6 P 0 8 0;1,3=3,5=0
P 5.035 1.49 6 P 0 8 0;1,3=3,5=0
P 4.185 1.17 6 P 0 8 0;1,3=3,5=0
P 4.816 1.258 6 P 0 8 0;1,3=3,5=0
P 4.665 1.104 6 P 0 8 0;1,3=3,5=0
P 4.91 1.54 6 P 0 8 0;1,3=3,5=0
P 4.768 1.207 6 P 0 8 0;1,3=3,5=0
P 5.03 1.55 6 P 0 8 0;1,3=3,5=0
P 4.828 1.103 6 P 0 8 0;1,3=3,5=0
P 4.83 1.33 6 P 0 8 0;1,3=3,5=0
P 4.22 1.235 6 P 0 8 0;1,3=3,5=0
P 3.83128002 1.78371998 2 P 0 8 0;3=10,5=1
P 6.02558996 4.175 6 P 0 8 0;1,3=1,5=1
P 6.1437 4.175 6 P 0 8 0;1,3=1,5=1
P 5.83 2.97 3 P 0 8 0;3=2,5=1
P 5.89953002 2.366 6 P 0 8 0;1,3=9,5=1
P 3.256 3.475 30 P 0 8 0;0,3=0,5=0
P 3.61123996 3.49876004 6 P 0 8 0;1,3=4,5=1
P 1.96496998 0.76501998 6 P 0 8 0;1,3=9,5=1
P 3.12 2.565 3 P 0 8 0;3=2,5=1
P 3.119 2.299 6 P 0 8 0;1,3=1,5=1
P 3.335 2.553 27 P 0 8 0;0,3=0,5=0
P 3.385 2.59 6 P 0 8 0;1,3=1,5=1
P 5.155 2.01 3 P 0 8 0;3=2,5=1
P 6.025 1.83 6 P 0 8 0;1,3=1,5=1
P 6.01901998 1.90865 27 P 0 8 0;0,3=0,5=0
P 2.599 2.375 30 P 0 8 0;0,3=0,5=0
P 2.551 2.375 30 P 0 8 0;0,3=0,5=0
P 2.554 2.901 6 P 0 8 0;1,3=1,5=1
P 4.75 1.63 6 P 0 8 0;1,3=5,5=1
P 3.205 1.7 6 P 0 8 0;1,3=1,5=1
P 4.775 1.705 3 P 0 8 0;3=2,5=1
P 4.884 1.855 30 P 0 8 0;0,3=0,5=0
P 4.84 1.855 6 P 0 8 0;1,3=1,5=1
P 4.5609 1.84343002 5 P 0 8 0;0,3=18,5=0
P 4.67901998 1.88281004 5 P 0 8 0;0,3=18,5=0
P 4.885 3.504 27 P 0 8 0;0,3=0,5=0
P 4.815 1.93 6 P 0 8 0;1,3=1,5=1
P 4.885 3.46 3 P 0 8 0;3=2,5=1
P 4.60028996 1.8828 5 P 0 8 0;0,3=18,5=0
P 4.83501004 3.46 6 P 0 8 0;1,3=1,5=1
P 3.125 2.254 3 P 0 8 0;3=2,5=1
P 4.26563996 1.86311004 6 P 0 8 0;1,3=5,5=1
P 3.12 2.69 3 P 0 8 0;3=2,5=1
P 4.565 3.055 3 P 0 8 0;3=2,5=1
P 4.3 3.81 6 P 0 8 0;1,3=1,5=1
P 1.3825 3.7225 2 P 0 8 0;3=10,5=1
P 5.905 3.015 6 P 0 8 0;1,3=9,5=1
P 5.41 0.96 6 P 0 8 0;3=3,5=0
P 5.404 0.64 30 P 0 8 0;0,3=0,5=0
P 4.884 1.765 30 P 0 8 0;0,3=0,5=0
P 4.85033002 1.74933996 3 P 0 8 0;3=2,5=1
P 5.26 2.955 3 P 0 8 0;3=2,5=1
P 3.625 0.92 2 P 0 8 0;3=12,5=1
P 6.19961004 2.27673996 2 P 0 8 0;3=12,5=1
P 3.657 0.92 2 P 0 8 0;3=12,5=1
P 6.19961004 2.24473996 2 P 0 8 0;3=12,5=1
P 3.3255 2.1355 6 P 0 8 0;1,3=1,5=1
P 3.35153002 2.17875 3 P 0 8 0;3=2,5=1
P 3.44 2.95 6 P 0 8 0;1,3=4,5=1
P 3.44 2.906 27 P 0 8 0;0,3=0,5=0
P 3.35 2.864 27 P 0 8 0;0,3=0,5=0
P 3.27923002 2.21576998 3 P 0 8 0;3=2,5=1
P 3.3435 2.82 6 P 0 8 0;1,3=4,5=1
P 4.46 2.94 6 P 0 8 0;1,3=1,5=1
P 4.47 2.83 6 P 0 8 0;1,3=1,5=1
P 4.524 2.945 30 P 0 8 0;0,3=0,5=0
P 4.524 2.795 30 P 0 8 0;0,3=0,5=0
P 4.524 2.845 30 P 0 8 0;0,3=0,5=0
P 4.524 2.895 30 P 0 8 0;0,3=0,5=0
P 5.995 1.165 3 P 0 8 0;3=2,5=1
P 3.106 3.26 3 P 0 8 0;3=2,5=1
P 3.068 3.26 30 P 0 8 0;0,3=0,5=0
P 3.256 3.385 30 P 0 8 0;0,3=0,5=0
P 3.256 3.34 30 P 0 8 0;0,3=0,5=0
P 3.222 3.385 2 P 0 8 0;3=10,5=1
P 3.068 3.35 30 P 0 8 0;0,3=0,5=0
P 3.106 3.35 2 P 0 8 0;3=10,5=1
P 1.959 3.325 3 P 0 8 0;3=2,5=1
P 3.256 3.205 30 P 0 8 0;0,3=0,5=0
P 3.222 3.205 2 P 0 8 0;3=10,5=1
P 3.485 2.906 27 P 0 8 0;0,3=0,5=0
P 3.49 2.955 3 P 0 8 0;3=2,5=1
P 3.98 3.429 27 P 0 8 0;0,3=0,5=0
P 3.98 3.365 3 P 0 8 0;3=2,5=1
P 3.744 3.37 30 P 0 8 0;0,3=0,5=0
P 3.7 3.37 3 P 0 8 0;3=2,5=1
P 3.506 3.37 30 P 0 8 0;0,3=0,5=0
P 3.55 3.37 3 P 0 8 0;3=2,5=1
P 4.17 3.429 27 P 0 8 0;0,3=0,5=0
P 4.175 3.37 3 P 0 8 0;3=2,5=1
P 3.973 3.291 30 P 0 8 0;0,3=0,5=0
P 3.744 3.28 30 P 0 8 0;0,3=0,5=0
P 3.744 3.235 30 P 0 8 0;0,3=0,5=0
P 3.71 3.26 3 P 0 8 0;3=2,5=1
P 3.506 3.28 30 P 0 8 0;0,3=0,5=0
P 3.55 3.28 2 P 0 8 0;3=10,5=1
P 3.414 3.235 3 P 0 8 0;3=2,5=1
P 3.41 3.04 3 P 0 8 0;3=2,5=1
P 3.548 2.856 2 P 0 8 0;3=10,5=1
P 3.5768 2.7178 3 P 0 8 0;3=2,5=1
P 3.395 2.864 27 P 0 8 0;0,3=0,5=0
P 3.395 2.82 3 P 0 8 0;3=2,5=1
P 3.58 2.615 6 P 0 8 0;1,3=3,5=0
P 3.485 2.6 3 P 0 8 0;3=2,5=1
P 3.525 2.6 3 P 0 8 0;3=2,5=1
P 3.335 2.589 3 P 0 8 0;3=2,5=1
P 3.24 2.2075 3 P 0 8 0;3=2,5=1
P 3.419 2.255 30 P 0 8 0;0,3=0,5=0
P 3.371 2.255 30 P 0 8 0;0,3=0,5=0
P 4.905 2.1675 3 P 0 8 0;3=2,5=1
P 4.884 2.025 30 P 0 8 0;0,3=0,5=0
P 4.85 2.02738996 3 P 0 8 0;3=2,5=1
P 4.926 1.975 30 P 0 8 0;0,3=0,5=0
P 4.965 1.975 3 P 0 8 0;3=2,5=1
P 3.49128002 1.86628002 3 P 0 8 0;3=2,5=1
P 3.505 1.831 27 P 0 8 0;0,3=0,5=0
P 4.63965 1.68595 5 P 0 8 0;0,3=18,5=0
P 3.795 2.375 3 P 0 8 0;3=2,5=1
P 3.97036004 2.00091004 5 P 0 8 0;0,3=18,5=0
P 3.97035 2.04028002 5 P 0 8 0;0,3=18,5=0
P 4.306 1.837 27 P 0 8 0;0,3=0,5=0
P 4.31006004 1.8978 5 P 0 8 0;0,3=18,5=0
P 4.0491 1.92216998 5 P 0 8 0;0,3=18,5=0
P 4.00973002 1.92216998 5 P 0 8 0;0,3=18,5=0
P 3.93098002 1.84343002 5 P 0 8 0;0,3=18,5=0
P 4.20658002 1.84343002 5 P 0 8 0;0,3=18,5=0
P 3.86 2.5925 3 P 0 8 0;3=2,5=1
P 4.60028002 1.84343002 5 P 0 8 0;0,3=18,5=0
P 4.324 2.975 30 P 0 8 0;0,3=0,5=0
P 4.48216004 1.92216004 5 P 0 8 0;0,3=18,5=0
P 3.758 2.552 3 P 0 8 0;3=2,5=1
P 4.209 2.59 3 P 0 8 0;3=2,5=1
P 4.2 2.936 33 P 0 8 0;0,3=11,5=0
P 4.2 2.855 33 P 0 8 0;0,3=11,5=0
P 4.249 2.929 6 P 0 8 0;1,3=1,5=1
P 4.239 2.785 6 P 0 8 0;1,3=1,5=1
P 4.249 2.843 6 P 0 8 0;1,3=1,5=1
P 4.575 2.461 27 P 0 8 0;0,3=0,5=0
P 4.53 2.461 27 P 0 8 0;0,3=0,5=0
P 4.575 2.5 3 P 0 8 0;3=2,5=1
P 4.395 2.461 27 P 0 8 0;0,3=0,5=0
P 4.395 2.5 3 P 0 8 0;3=2,5=1
P 4.77 2.39 3 P 0 8 0;3=2,5=1
P 4.71 2.39 3 P 0 8 0;3=2,5=1
P 4.51311004 1.755 30 P 0 8 0;0,3=0,5=0
P 4.52153996 1.80406004 5 P 0 8 0;0,3=18,5=0
P 4.63965 1.84343002 5 P 0 8 0;0,3=18,5=0
P 4.63965 1.80406004 5 P 0 8 0;0,3=18,5=0
P 4.12783996 1.96153996 5 P 0 8 0;0,3=18,5=0
P 4.16721004 1.96153996 5 P 0 8 0;0,3=18,5=0
P 4.3 1.987 27 P 0 8 0;0,3=0,5=0
P 4.4428 1.92216998 5 P 0 8 0;0,3=18,5=0
P 4.60028002 1.92216998 5 P 0 8 0;0,3=18,5=0
P 4.60028002 1.96153996 5 P 0 8 0;0,3=18,5=0
P 4.78 1.86311004 27 P 0 8 0;0,3=0,5=0
P 4.71838996 2.00091004 5 P 0 8 0;0,3=18,5=0
P 3.93098002 2.15838996 5 P 0 8 0;0,3=18,5=0
P 3.93098002 2.11901998 5 P 0 8 0;0,3=18,5=0
P 4.066 2.215 30 P 0 8 0;0,3=0,5=0
P 4.12783996 2.04028002 5 P 0 8 0;0,3=18,5=0
P 4.24595 2.11901998 5 P 0 8 0;0,3=18,5=0
P 4.40343002 2.15838996 5 P 0 8 0;0,3=18,5=0
P 4.49685 2.22 30 P 0 8 0;0,3=0,5=0
P 4.52153996 2.07965 5 P 0 8 0;0,3=18,5=0
P 4.67901998 2.11901998 5 P 0 8 0;0,3=18,5=0
P 4.0875 2.325 36 P 0 8 0;0,3=20,5=0
P 4.075 2.25 3 P 0 8 0;3=2,5=1
P 3.735 2.47 3 P 0 8 0;3=2,5=1
P 5.0395 1.335 3 P 0 8 0;3=2,5=1
P 4.926 1.765 30 P 0 8 0;0,3=0,5=0
P 4.97 1.75 6 P 0 8 0;1,3=1,5=1
P 4.926 1.63 30 P 0 8 0;0,3=0,5=0
P 4.96 1.63 3 P 0 8 0;3=2,5=1
P 6.22 1.27063002 3 P 0 8 0;3=2,5=1
P 3.839 3.846 3 P 0 8 0;3=2,5=1
P 3.839 3.81 30 P 0 8 0;0,3=0,5=0
P 4.384 3.824 3 P 0 8 0;3=2,5=1
P 4.989 3.455 30 P 0 8 0;0,3=0,5=0
P 4.95 3.46 3 P 0 8 0;3=2,5=1
P 5.94003002 1.87 3 P 0 8 0;3=2,5=1
P 6.379 1.169 3 P 0 8 0;3=2,5=1
P 6.105 1.905 3 P 0 8 0;3=2,5=1
P 6.01901998 1.95065 27 P 0 8 0;0,3=0,5=0
P 6.06901998 1.95065 27 P 0 8 0;0,3=0,5=0
P 5.92 1.27063002 3 P 0 8 0;3=2,5=1
P 5.88 0.965 3 P 0 8 0;3=2,5=1
P 6.47 1.08 3 P 0 8 0;3=2,5=1
P 5.19 3.075 3 P 0 8 0;3=2,5=1
P 5.375 3.04 3 P 0 8 0;3=2,5=1
P 5.452 3.061 27 P 0 8 0;0,3=0,5=0
P 5.41 2.815 3 P 0 8 0;3=2,5=1
P 5.452 2.813 27 P 0 8 0;0,3=0,5=0
P 5.544 2.675 3 P 0 8 0;3=2,5=1
P 5.544 2.721 30 P 0 8 0;0,3=0,5=0
P 6.1865 2.493 3 P 0 8 0;3=2,5=1
P 6.141 2.364 3 P 0 8 0;3=2,5=1
P 5.85 2.265 3 P 0 8 0;3=2,5=1
P 5.62 2.5487 3 P 0 8 0;3=2,5=1
P 5.42 2.9645 3 P 0 8 0;3=2,5=1
P 5.452 2.9645 27 P 0 8 0;0,3=0,5=0
P 5.91901998 1.90865 27 P 0 8 0;0,3=0,5=0
P 4.645 2.985 3 P 0 8 0;3=2,5=1
P 4.61 3.025 3 P 0 8 0;3=2,5=1
P 4.43 3.865 2 P 0 8 0;3=10,5=1
P 5.273 4.20101004 27 P 0 8 0;0,3=0,5=0
P 5.221 4.165 3 P 0 8 0;3=2,5=1
P 4.354 3.965 30 P 0 8 0;0,3=0,5=0
P 4.32 3.965 2 P 0 8 0;3=10,5=1
P 4.535 3.815 3 P 0 8 0;3=2,5=1
P 4.509 3.309 3 P 0 8 0;3=2,5=1
P 4.235 4.155 3 P 0 8 0;3=2,5=1
P 4.224 4.065 30 P 0 8 0;0,3=0,5=0
P 4.224 4.115 30 P 0 8 0;0,3=0,5=0
P 4.505 3.685 3 P 0 8 0;3=2,5=1
P 5.975 4.219 3 P 0 8 0;3=2,5=1
P 6.14 4.219 27 P 0 8 0;0,3=0,5=0
P 6.027 4.219 27 P 0 8 0;0,3=0,5=0
P 5.84 4.219 3 P 0 8 0;3=2,5=1
P 5.79 4.219 27 P 0 8 0;0,3=0,5=0
P 5.67 4.219 27 P 0 8 0;0,3=0,5=0
P 5.555 4.219 27 P 0 8 0;0,3=0,5=0
P 5.435 4.219 27 P 0 8 0;0,3=0,5=0
P 5.435 4.166 27 P 0 8 0;0,3=0,5=0
P 6.145 3.98 3 P 0 8 0;3=2,5=1
P 4.655 0.785 3 P 0 8 0;3=2,5=1
P 4.694 0.965 30 P 0 8 0;0,3=0,5=0
P 4.635 0.92 3 P 0 8 0;3=2,5=1
P 5.249 0.99 3 P 0 8 0;3=2,5=1
P 5.53 1.085 3 P 0 8 0;3=2,5=1
P 5.33 0.82 3 P 0 8 0;3=2,5=1
P 5.265 0.675 3 P 0 8 0;3=2,5=1
P 2.964 0.702 3 P 0 8 0;3=2,5=1
P 5.555 0.608 27 P 0 8 0;0,3=0,5=0
P 5.515 0.59596998 3 P 0 8 0;3=2,5=1
P 2.0477 0.6778 3 P 0 8 0;3=2,5=1
P 2.285 0.79 3 P 0 8 0;3=2,5=1
P 2.285 0.755 3 P 0 8 0;3=2,5=1
P 3.09 1.645 3 P 0 8 0;3=2,5=1
P 1.605 0.715 3 P 0 8 0;3=2,5=1
P 1.605 0.755 3 P 0 8 0;3=2,5=1
P 1.826 2.895 3 P 0 8 0;3=2,5=1
P 1.401 3.069 3 P 0 8 0;3=2,5=1
P 3.119 2.434 3 P 0 8 0;3=2,5=1
P 2.245 3.02 2 P 0 8 0;3=10,5=1
P 2.49 2.903 3 P 0 8 0;3=2,5=1
P 2.509 2.375 30 P 0 8 0;0,3=0,5=0
P 2.46558996 2.287 23 P 0 8 0;0,3=21,5=0
P 2.461 2.355 30 P 0 8 0;0,3=0,5=0
P 2.128 2.895 2 P 0 8 0;3=10,5=1
P 0.11976004 3.23523996 3 P 0 8 0;3=2,5=1
P 0.78 2.915 3 P 0 8 0;3=2,5=1
P 0.741 2.915 30 P 0 8 0;0,3=0,5=0
P 0.241 3.075 30 P 0 8 0;0,3=0,5=0
P 0.3695 3.0284 39 P 0 8 0;0,3=17,5=0
P 0.241 3.109 3 P 0 8 0;3=2,5=1
P 0.199 2.975 30 P 0 8 0;0,3=0,5=0
P 0.16 2.975 3 P 0 8 0;3=2,5=1
P 0.199 2.925 30 P 0 8 0;0,3=0,5=0
P 0.335 2.829 27 P 0 8 0;0,3=0,5=0
P 0.374 2.829 3 P 0 8 0;3=2,5=1
P 0.5459 2.6687 3 P 0 8 0;3=2,5=1
P 0.674 2.271 3 P 0 8 0;3=2,5=1
P 0.85 2.402 27 P 0 8 0;0,3=0,5=0
P 0.896 2.402 27 P 0 8 0;0,3=0,5=0
P 0.857 2.365 3 P 0 8 0;3=2,5=1
P 0.677 2.402 3 P 0 8 0;3=2,5=1
P 0.715 2.402 27 P 0 8 0;0,3=0,5=0
P 0.11963002 2.66436998 3 P 0 8 0;3=2,5=1
P 0.51451998 2.199 3 P 0 8 0;3=2,5=1
P 0.58 2.135 3 P 0 8 0;3=2,5=1
P 0.125 2.095 3 P 0 8 0;3=2,5=1
P 0.64445 1.68945 3 P 0 8 0;3=2,5=1
P 0.884 1.549 3 P 0 8 0;3=2,5=1
P 0.85 1.549 30 P 0 8 0;0,3=0,5=0
P 0.883 1.639 2 P 0 8 0;3=10,5=1
P 0.85 1.639 30 P 0 8 0;0,3=0,5=0
P 0.514 1.616 3 P 0 8 0;3=2,5=1
P 0.605 1.52 3 P 0 8 0;3=2,5=1
P 0.11263996 1.52263996 3 P 0 8 0;3=2,5=1
P 0.625 1.17 3 P 0 8 0;3=2,5=1
P 0.59 0.965 6 P 0 8 0;1,3=1,5=1
P 0.505 1.048 3 P 0 8 0;3=2,5=1
P 0.125 0.96 3 P 0 8 0;3=2,5=1
P 0.821 0.793 3 P 0 8 0;3=2,5=1
P 0.86 0.791 27 P 0 8 0;0,3=0,5=0
P 0.743 0.911 27 P 0 8 0;0,3=0,5=0
P 0.788 0.911 27 P 0 8 0;0,3=0,5=0
P 0.764 0.872 3 P 0 8 0;3=2,5=1
P 1.25 0.765 3 P 0 8 0;3=2,5=1
P 1.309 0.753 30 P 0 8 0;0,3=0,5=0
P 1.1133 0.5981 3 P 0 8 0;3=2,5=1
P 1.1738 0.6587 30 P 0 8 0;0,3=0,5=0
P 0.851 0.665 30 P 0 8 0;0,3=0,5=0
P 0.86 0.631 3 P 0 8 0;3=2,5=1
P 0.577 0.697 27 P 0 8 0;0,3=0,5=0
P 0.601 0.73 3 P 0 8 0;3=2,5=1
P 0.596 0.602 3 P 0 8 0;3=2,5=1
P 0.635 0.615 30 P 0 8 0;0,3=0,5=0
P 1.5327 0.584 3 P 0 8 0;3=2,5=1
P 4.67901998 1.56783996 5 P 0 8 0;0,3=18,5=0
P 4.60028002 1.52846998 5 P 0 8 0;0,3=18,5=0
P 4.16721004 1.52846998 5 P 0 8 0;0,3=18,5=0
P 4.16721004 1.4891 5 P 0 8 0;0,3=18,5=0
P 4.76666004 1.42805 5 P 0 8 0;0,3=18,5=0
P 4.60028002 1.41035 5 P 0 8 0;0,3=18,5=0
P 4.52153996 1.37096998 5 P 0 8 0;0,3=18,5=0
P 4.4428 1.44973002 5 P 0 8 0;0,3=18,5=0
P 4.40343002 1.33161004 5 P 0 8 0;0,3=18,5=0
P 4.36406004 1.44973002 5 P 0 8 0;0,3=18,5=0
P 4.309 1.44531004 5 P 0 8 0;0,3=18,5=0
P 4.20658002 1.41035 5 P 0 8 0;0,3=18,5=0
P 4.0491 1.37098002 5 P 0 8 0;0,3=18,5=0
P 3.91828996 1.29361004 30 P 0 8 0;0,3=0,5=0
P 4.999 1.263 33 P 0 8 0;0,3=11,5=0
P 5.039 1.2869 3 P 0 8 0;3=2,5=1
P 5.0386 1.2415 3 P 0 8 0;3=2,5=1
P 4.625 1.17 3 P 0 8 0;3=2,5=1
P 4.37 1.079 27 P 0 8 0;0,3=0,5=0
P 4.415 1.079 27 P 0 8 0;0,3=0,5=0
P 4.485 1.005 3 P 0 8 0;3=2,5=1
P 3.69171998 1.02828002 3 P 0 8 0;3=2,5=1
P 3.732 1.06 33 P 0 8 0;0,3=11,5=0
P 3.6931 1.095 3 P 0 8 0;3=2,5=1
P 6.04 3.98 3 P 0 8 0;3=2,5=1
P 5.445 0.795 6 P 0 8 0;1,3=3,5=0
P 5.494 0.816 3 P 0 8 0;3=2,5=1
P 5.443 0.871 3 P 0 8 0;3=2,5=1
P 5.49 0.78223002 3 P 0 8 0;3=2,5=1
P 3.795 4.175 3 P 0 8 0;3=2,5=1
P 3.66 3.5085 3 P 0 8 0;3=2,5=1
P 3.105 3.21 3 P 0 8 0;3=2,5=1
P 3.068 3.21 30 P 0 8 0;0,3=0,5=0
P 5.55 4.02 3 P 0 8 0;3=2,5=1
P 5.529 4.07 30 P 0 8 0;0,3=0,5=0
P 5.01 2.635 6 P 0 8 0;1,3=1,5=1
P 5 2.78798996 6 P 0 8 0;1,3=9,5=1
P 5.226 2.762 6 P 0 8 0;1,3=9,5=1
P 3.775 2.235 3 P 0 8 0;3=2,5=1
P 3.775 2.265 6 P 0 8 0;1,3=1,5=1
P 3.775 2.21 3 P 0 8 0;3=2,5=1
P 3.775 2.185 3 P 0 8 0;3=2,5=1
P 4.42311004 1.755 30 P 0 8 0;0,3=0,5=0
P 4.4428 1.68595 5 P 0 8 0;0,3=18,5=0
P 4.36406004 1.80406004 5 P 0 8 0;0,3=18,5=0
P 4.365 1.741 30 P 0 8 0;0,3=0,5=0
P 4.24595 1.80406004 5 P 0 8 0;0,3=18,5=0
P 4.241 1.75 30 P 0 8 0;0,3=0,5=0
P 4.20658002 1.64658002 5 P 0 8 0;0,3=18,5=0
P 4.14 1.75 30 P 0 8 0;0,3=0,5=0
P 4.0491 1.80406004 5 P 0 8 0;0,3=18,5=0
P 5.775 0.796 27 P 0 8 0;0,3=0,5=0
P 5.765 0.98 6 P 0 8 0;1,3=3,5=0
P 1.385 3.875 6 P 0 8 0;1,3=9,5=1
P 4.566 2.945 30 P 0 8 0;0,3=0,5=0
P 5.31 2.855 3 P 0 8 0;3=2,5=1
P 4.608 2.942 3 P 0 8 0;3=2,5=1
P 4.25 3.81 3 P 0 8 0;3=2,5=1
P 1.435 3.901 30 P 0 8 0;0,3=0,5=0
P 0.99 2.60025 3 P 0 8 0;3=2,5=1
P 0.985 2.56661004 3 P 0 8 0;3=2,5=1
P 3.555 2.23 3 P 0 8 0;3=2,5=1
P 3.555 2.255 3 P 0 8 0;3=2,5=1
P 3.612 2.23 33 P 0 8 0;0,3=11,5=0
P 3.609 2.17 30 P 0 8 0;0,3=0,5=0
P 3.555 2.205 3 P 0 8 0;3=2,5=1
P 3.555 2.18 3 P 0 8 0;3=2,5=1
P 5.345 2.536 6 P 0 8 0;1,3=3,5=0
P 5.22 2.47 3 P 0 8 0;3=2,5=1
P 5.254 2.47 3 P 0 8 0;3=2,5=1
P 5.239 2.571 3 P 0 8 0;3=2,5=1
P 5.243 2.617 3 P 0 8 0;3=2,5=1
P 5.224 2.707 6 P 0 8 0;1,3=9,5=1
P 5.278 2.653 27 P 0 8 0;0,3=0,5=0
P 5.005 2.711 6 P 0 8 0;1,3=9,5=1
P 4.961 2.686 27 P 0 8 0;0,3=0,5=0
P 3.793 3.05 6 P 0 8 0;1,3=4,5=1
P 3.793 3.092 30 P 0 8 0;0,3=0,5=0
P 3.96981004 3.04481998 6 P 0 8 0;1,3=1,5=1
P 3.948 2.813 6 P 0 8 0;1,3=1,5=1
P 4.831 2.728 6 P 0 8 0;1,3=3,5=0
P 3.52 1.376 27 P 0 8 0;0,3=0,5=0
P 3.618 1.395 31 P 0 8 0;0,3=7,5=0
P 3.46 1.378 37 P 0 8 0;0,3=11,5=0
P 3.55 1.415 3 P 0 8 0;3=2,5=1
P 3.525 1.415 3 P 0 8 0;3=2,5=1
P 3.5 1.415 3 P 0 8 0;3=2,5=1
P 3.475 1.415 3 P 0 8 0;3=2,5=1
P 3.655 2.795 6 P 0 8 0;1,3=3,5=0
P 3.745 2.76 3 P 0 8 0;3=2,5=1
P 3.7 2.76 3 P 0 8 0;3=2,5=1
P 3.822 2.81 3 P 0 8 0;3=2,5=1
P 3.78 2.81 3 P 0 8 0;3=2,5=1
P 3.894 2.811 6 P 0 8 0;1,3=1,5=1
P 3.835 3.092 30 P 0 8 0;0,3=0,5=0
P 3.891 3.092 30 P 0 8 0;0,3=0,5=0
P 3.916 3.048 6 P 0 8 0;1,3=4,5=1
P 5.589 2.025 6 P 0 8 0;1,3=1,5=1
P 5.546 2.024 3 P 0 8 0;3=2,5=1
P 5.51 2.024 27 P 0 8 0;0,3=0,5=0
P 5.589 1.98 30 P 0 8 0;0,3=0,5=0
P 5.69943002 2.233 6 P 0 8 0;1,3=1,5=1
P 5.431 2.275 30 P 0 8 0;0,3=0,5=0
P 5.48158002 2.28033002 6 P 0 8 0;1,3=9,5=1
P 4.52153996 1.68595 5 P 0 8 0;0,3=18,5=0
P 4.40343002 1.68595 5 P 0 8 0;0,3=18,5=0
P 4.305 1.691 27 P 0 8 0;0,3=0,5=0
P 4.24595 1.68595 5 P 0 8 0;0,3=18,5=0
P 4.12783996 1.68595 5 P 0 8 0;0,3=18,5=0
P 4.48216998 1.60721004 5 P 0 8 0;0,3=18,5=0
P 4.4428 1.64658002 5 P 0 8 0;0,3=18,5=0
P 4.4428 1.56783996 5 P 0 8 0;0,3=18,5=0
P 4.36406004 1.56783996 5 P 0 8 0;0,3=18,5=0
P 4.40343002 1.60721004 5 P 0 8 0;0,3=18,5=0
P 4.36406004 1.60721004 5 P 0 8 0;0,3=18,5=0
P 4.305 1.549 27 P 0 8 0;0,3=0,5=0
P 4.24595 1.60721004 5 P 0 8 0;0,3=18,5=0
P 4.16721004 1.60721004 5 P 0 8 0;0,3=18,5=0
P 4.16721004 1.64658002 5 P 0 8 0;0,3=18,5=0
P 4.20658002 1.52846998 5 P 0 8 0;0,3=18,5=0
P 4.20658002 1.56783996 5 P 0 8 0;0,3=18,5=0
P 5.145 1.57 3 P 0 8 0;3=2,5=1
P 5.145 1.54 3 P 0 8 0;3=2,5=1
P 5.145 1.44 6 P 0 8 0;1,3=1,5=1
P 5.145 1.48 3 P 0 8 0;3=2,5=1
P 5.145 1.51 3 P 0 8 0;3=2,5=1
P 5.76 2.465 6 P 0 8 0;3=3,5=0
P 4.2136 3.5997 6 P 0 8 0;1,3=4,5=1
P 3.755 3.092 3 P 0 8 0;3=2,5=1
P 4.00973002 1.64658002 5 P 0 8 0;0,3=18,5=0
P 4.08846998 1.56783996 5 P 0 8 0;0,3=18,5=0
P 4.08846998 1.60721004 5 P 0 8 0;0,3=18,5=0
P 4.0491 1.60721004 5 P 0 8 0;0,3=18,5=0
P 4.00973002 1.4891 5 P 0 8 0;0,3=18,5=0
P 4.00973002 1.52846998 5 P 0 8 0;0,3=18,5=0
P 3.679 1.54228002 3 P 0 8 0;3=2,5=1
P 3.714 1.543 3 P 0 8 0;3=2,5=1
P 3.784 1.543 3 P 0 8 0;3=2,5=1
P 3.749 1.54228002 3 P 0 8 0;3=2,5=1
P 3.605 1.545 3 P 0 8 0;3=2,5=1
P 3.50085 1.543 3 P 0 8 0;3=2,5=1
P 3.53481998 1.54156998 3 P 0 8 0;3=2,5=1
P 3.57 1.542 3 P 0 8 0;3=2,5=1
P 5.4227 1.724 3 P 0 8 0;3=2,5=1
P 5.3977 1.724 3 P 0 8 0;3=2,5=1
P 5.58 1.615 6 P 0 8 0;1,3=3,5=0
P 5.3977 1.699 3 P 0 8 0;3=2,5=1
P 5.3977 1.749 3 P 0 8 0;3=2,5=1
P 5.4227 1.699 3 P 0 8 0;3=2,5=1
P 5.39 1.646 27 P 0 8 0;0,3=0,5=0
P 5.4 1.787 37 P 0 8 0;0,3=11,5=0
P 5.4352 1.7497 3 P 0 8 0;3=2,5=1
P 5.654 2.447 3 P 0 8 0;3=2,5=1
P 5.754 2.324 27 P 0 8 0;0,3=0,5=0
P 5.7 2.318 32 P 0 8 0;0,3=7,5=0
P 5.667 2.275 6 P 0 8 0;1,3=9,5=1
P 5.6 2.324 27 P 0 8 0;0,3=0,5=0
P 5.595 2.28 6 P 0 8 0;1,3=9,5=1
P 5.51 2.171 27 P 0 8 0;0,3=0,5=0
P 5.483 2.226 6 P 0 8 0;1,3=1,5=1
P 5.754 2.366 27 P 0 8 0;0,3=0,5=0
P 5.6695 2.2 3 P 0 8 0;3=2,5=1
P 5.771 2.279 6 P 0 8 0;1,3=9,5=1
P 5.789 2.366 3 P 0 8 0;3=2,5=1
P 5.7 2.372 32 P 0 8 0;0,3=7,5=0
P 5.6 2.4 3 P 0 8 0;3=2,5=1
P 5.645 2.33456998 24 P 0 8 0;0,3=22,5=0
P 5.6 4.01 6 P 0 8 0;3=3,5=0
P 5.55568996 3.88051004 6 P 0 8 0;1,3=4,5=1
P 5.465 2.366 27 P 0 8 0;0,3=0,5=0
P 5.765 2.197 6 P 0 8 0;1,3=1,5=1
P 5.71 2.179 3 P 0 8 0;3=2,5=1
P 5.41 2.164 6 P 0 8 0;1,3=1,5=1
P 5.458 2.165 3 P 0 8 0;3=2,5=1
P 5.465 2.405 3 P 0 8 0;3=2,5=1
P 5.6435 2.38443002 6 P 0 8 0;1,3=13,5=1
P 5.645 2.35543002 24 P 0 8 0;0,3=22,5=0
P 5.6 2.366 27 P 0 8 0;0,3=0,5=0
P 5.465 2.324 27 P 0 8 0;0,3=0,5=0
P 5.51 2.324 27 P 0 8 0;0,3=0,5=0
P 5.555 2.324 27 P 0 8 0;0,3=0,5=0
P 5.53121998 2.27978996 6 P 0 8 0;1,3=9,5=1
P 5.687 1.99 33 P 0 8 0;0,3=11,5=0
P 5.631 1.98 30 P 0 8 0;0,3=0,5=0
P 5.47211004 2.098 6 P 0 8 0;1,3=13,5=1
P 5.51 2.129 27 P 0 8 0;0,3=0,5=0
P 5.51 2.066 27 P 0 8 0;0,3=0,5=0
P 3.817 0.924 6 P 0 8 0;1,3=9,5=1
P 3.77 0.917 32 P 0 8 0;0,3=7,5=0
P 4.27 0.832 32 P 0 8 0;0,3=7,5=0
P 4.25 0.877 6 P 0 8 0;1,3=1,5=1
P 4.275 0.919 27 P 0 8 0;0,3=0,5=0
P 4.32 0.919 27 P 0 8 0;0,3=0,5=0
P 5.446 0.69 30 P 0 8 0;0,3=0,5=0
P 5.557 0.705 27 P 0 8 0;0,3=0,5=0
P 5.495 0.694 6 P 0 8 0;1,3=9,5=1
P 5.49 0.635 6 P 0 8 0;1,3=1,5=1
P 5.446 0.64 30 P 0 8 0;0,3=0,5=0
P 5.555 0.65 27 P 0 8 0;0,3=0,5=0
P 5.725 0.60301004 6 P 0 8 0;1,3=9,5=1
P 5.686 0.76 6 P 0 8 0;1,3=9,5=1
P 5.7287 0.6757 6 P 0 8 0;1,3=9,5=1
P 5.772 0.7 27 P 0 8 0;0,3=0,5=0
P 5.825 0.754 27 P 0 8 0;0,3=0,5=0
P 5.775 0.754 27 P 0 8 0;0,3=0,5=0
P 5.855 4.095 6 P 0 8 0;1,3=13,5=1
P 5.811 4.12 30 P 0 8 0;0,3=0,5=0
P 5.811 4.075 30 P 0 8 0;0,3=0,5=0
P 5.61731004 4.085 6 P 0 8 0;1,3=13,5=1
P 5.571 4.115 30 P 0 8 0;0,3=0,5=0
P 5.571 4.07 30 P 0 8 0;0,3=0,5=0
P 5.435 4.124 27 P 0 8 0;0,3=0,5=0
P 5.38558002 4.13778996 6 P 0 8 0;1,3=1,5=1
P 5.529 4.115 30 P 0 8 0;0,3=0,5=0
P 5.485 4.11 6 P 0 8 0;1,3=1,5=1
P 5.769 4.12 30 P 0 8 0;0,3=0,5=0
P 5.725 4.135 6 P 0 8 0;1,3=1,5=1
P 5.675 4.126 27 P 0 8 0;0,3=0,5=0
P 5.6218 4.13778996 6 P 0 8 0;1,3=1,5=1
P 5.323 4.257 6 P 0 8 0;1,3=9,5=1
P 5.323 4.20101004 27 P 0 8 0;0,3=0,5=0
P 3.786 3.37 30 P 0 8 0;0,3=0,5=0
P 3.786 3.415 30 P 0 8 0;0,3=0,5=0
P 3.83 3.335 6 P 0 8 0;1,3=4,5=1
P 3.415 3.285 6 P 0 8 0;1,3=4,5=1
P 3.464 3.235 30 P 0 8 0;0,3=0,5=0
P 3.464 3.28 30 P 0 8 0;0,3=0,5=0
P 3.786 3.28 30 P 0 8 0;0,3=0,5=0
P 3.786 3.325 30 P 0 8 0;0,3=0,5=0
P 3.83 3.285 6 P 0 8 0;1,3=4,5=1
P 3.415 3.385 6 P 0 8 0;1,3=4,5=1
P 3.464 3.415 30 P 0 8 0;0,3=0,5=0
P 3.464 3.37 30 P 0 8 0;0,3=0,5=0
P 4.83871004 1.98241004 6 P 0 8 0;1,3=1,5=1
P 4.884 1.975 30 P 0 8 0;0,3=0,5=0
P 4.80288002 2.03788002 6 P 0 8 0;1,3=1,5=1
P 4.97 3.41 6 P 0 8 0;1,3=1,5=1
P 4.985 3.504 27 P 0 8 0;0,3=0,5=0
P 5.031 3.455 30 P 0 8 0;0,3=0,5=0
P 4.81 3.41 3 P 0 8 0;3=2,5=1
P 4.935 3.504 27 P 0 8 0;0,3=0,5=0
P 4.42311004 2.09933002 6 P 0 8 0;1,3=5,5=1
P 3.552 4.197 30 P 0 8 0;0,3=0,5=0
P 3.539 4.13 30 P 0 8 0;0,3=0,5=0
P 3.48863002 4.105 6 P 0 8 0;1,3=1,5=1
P 2.987 3.235 2 P 0 8 0;3=10,5=1
P 0.718 1.599 30 P 0 8 0;0,3=0,5=0
P 0.7595 1.642 6 P 0 8 0;1,3=9,5=1
P 0.808 1.594 30 P 0 8 0;0,3=0,5=0
P 0.808 1.639 30 P 0 8 0;0,3=0,5=0
P 0.808 1.684 30 P 0 8 0;0,3=0,5=0
P 2.987 3.27 2 P 0 8 0;3=10,5=1
P 0.761 1.544 6 P 0 8 0;1,3=9,5=1
P 0.804 1.5 30 P 0 8 0;0,3=0,5=0
P 0.808 1.549 30 P 0 8 0;0,3=0,5=0
P 0.716 1.495 30 P 0 8 0;0,3=0,5=0
P 0.717 1.544 30 P 0 8 0;0,3=0,5=0
P 4.79246004 1.78463996 6 P 0 8 0;1,3=1,5=1
P 4.884 1.81 30 P 0 8 0;0,3=0,5=0
P 4.62 2.419 27 P 0 8 0;0,3=0,5=0
P 4.575 2.419 27 P 0 8 0;0,3=0,5=0
P 4.54121998 2.17806998 6 P 0 8 0;1,3=5,5=1
P 0.955 1.455 6 P 0 8 0;1,3=1,5=1
P 1.3505 0.658 30 P 0 8 0;0,3=0,5=0
P 1.512 0.75191004 3 P 0 8 0;3=2,5=1
P 0.85 1.594 30 P 0 8 0;0,3=0,5=0
P 1.8091 0.6339 6 P 0 8 0;1,3=9,5=1
P 1.459 0.752 2 P 0 8 0;3=10,5=1
P 1.3507 0.708 30 P 0 8 0;0,3=0,5=0
P 0.905 1.445 3 P 0 8 0;3=2,5=1
P 0.846 1.5 30 P 0 8 0;0,3=0,5=0
P 2.40508002 0.731 2 P 0 8 0;3=10,5=1
P 2.3431 0.6259 27 P 0 8 0;0,3=0,5=0
P 4.08846998 1.68595 5 P 0 8 0;0,3=18,5=0
P 2.40508002 0.699 2 P 0 8 0;3=10,5=1
P 4.04908996 1.68595 5 P 0 8 0;0,3=18,5=0
P 2.39311004 0.626 27 P 0 8 0;0,3=0,5=0
P 4.415 1.121 27 P 0 8 0;0,3=0,5=0
P 4.4085 1.16598996 2 P 0 8 0;3=10,5=1
P 4.48216998 1.44973002 5 P 0 8 0;0,3=18,5=0
P 4.37 1.121 27 P 0 8 0;0,3=0,5=0
P 4.3765 1.16598996 2 P 0 8 0;3=10,5=1
P 4.52155 1.44973002 5 P 0 8 0;0,3=18,5=0
P 4.0485 1.16098996 2 P 0 8 0;3=10,5=1
P 4.08846998 1.4891 5 P 0 8 0;0,3=18,5=0
P 4.0165 1.16098996 2 P 0 8 0;3=10,5=1
P 4.04908996 1.4891 5 P 0 8 0;0,3=18,5=0
P 4.82 2.125 6 P 0 8 0;1,3=3,5=0
P 3.54663996 1.04706998 2 P 0 8 0;3=10,5=1
P 3.51463996 1.04706998 2 P 0 8 0;3=10,5=1
P 3.44998996 1.085 2 P 0 8 0;3=10,5=1
P 3.41798996 1.085 2 P 0 8 0;3=10,5=1
P 3.445 1.815 3 P 0 8 0;3=2,5=1
P 2.49498996 2.04 6 P 0 8 0;1,3=13,5=1
P 2.46558996 2.193 23 P 0 8 0;0,3=21,5=0
P 2.54 2.264 27 P 0 8 0;0,3=0,5=0
P 2.54 2.216 27 P 0 8 0;0,3=0,5=0
P 4.785 3.46 6 P 0 8 0;1,3=1,5=1
P 3.93098002 1.72531998 5 P 0 8 0;0,3=18,5=0
P 3.8863 1.745 30 P 0 8 0;0,3=0,5=0
P 3.674 1.744 3 P 0 8 0;3=2,5=1
P 3.704 1.72 30 P 0 8 0;0,3=0,5=0
P 3.93098002 1.52846998 5 P 0 8 0;0,3=18,5=0
P 3.93098002 1.64658002 5 P 0 8 0;0,3=18,5=0
P 3.97035 1.44973002 5 P 0 8 0;0,3=18,5=0
P 3.93098002 1.4891 5 P 0 8 0;0,3=18,5=0
P 3.82 1.42 6 P 0 8 0;1,3=1,5=1
P 3.79 1.41 3 P 0 8 0;3=2,5=1
P 3.74 1.41 3 P 0 8 0;3=2,5=1
P 3.765 1.41 3 P 0 8 0;3=2,5=1
P 3.672 1.395 31 P 0 8 0;0,3=7,5=0
P 3.785 1.368 37 P 0 8 0;0,3=11,5=0
P 4.9097 1.385 6 P 0 8 0;1,3=9,5=1
P 4.884 1.63 30 P 0 8 0;0,3=0,5=0
P 4.884 1.675 30 P 0 8 0;0,3=0,5=0
P 4.84 1.66 6 P 0 8 0;1,3=1,5=1
P 4.81 1.725 6 P 0 8 0;1,3=1,5=1
P 3.375 1.194 2 P 0 8 0;3=10,5=1
P 4.53 1.181 27 P 0 8 0;0,3=0,5=0
P 4.5413 1.22166998 2 P 0 8 0;3=10,5=1
P 4.60026998 1.29223996 5 P 0 8 0;0,3=18,5=0
P 3.375 1.162 2 P 0 8 0;3=10,5=1
P 4.585 1.181 27 P 0 8 0;0,3=0,5=0
P 4.5733 1.22166998 2 P 0 8 0;3=10,5=1
P 4.63965 1.29223996 5 P 0 8 0;0,3=18,5=0
P 5.3 4.065 6 P 0 8 0;1,3=3,5=0
P 5.323 4.15901004 27 P 0 8 0;0,3=0,5=0
P 5.273 4.15901004 27 P 0 8 0;0,3=0,5=0
P 4.365 2.33 3 P 0 8 0;3=2,5=1
P 4.38373996 2.02058996 6 P 0 8 0;1,3=5,5=1
P 4.485 2.375 6 P 0 8 0;1,3=1,5=1
P 4.485 2.419 27 P 0 8 0;0,3=0,5=0
P 4.53 2.419 27 P 0 8 0;0,3=0,5=0
P 4.36748996 2.25 6 P 0 8 0;1,3=13,5=1
P 4.44 2.419 27 P 0 8 0;0,3=0,5=0
P 4.395 2.419 27 P 0 8 0;0,3=0,5=0
P 4.9097 1.335 6 P 0 8 0;1,3=9,5=1
P 4.365 2.375 6 P 0 8 0;1,3=1,5=1
P 4.35 2.419 27 P 0 8 0;0,3=0,5=0
P 3.465 1.74 3 P 0 8 0;3=2,5=1
P 3.44 1.03 6 P 0 8 0;1,3=1,5=1
P 2.44 2.193 23 P 0 8 0;0,3=21,5=0
P 6.285 1.895 3 P 0 8 0;3=2,5=1
P 6.255 1.96773996 27 P 0 8 0;0,3=0,5=0
P 6.3 1.96773996 27 P 0 8 0;0,3=0,5=0
P 6.258 2.15873996 2 P 0 8 0;3=10,5=1
P 6.3 2.00973996 27 P 0 8 0;0,3=0,5=0
P 6.275 2.05373996 3 P 0 8 0;3=2,5=1
P 6.335 2.05906004 6 P 0 8 0;1,3=9,5=1
P 1.77 3.98 6 P 0 8 0;1,3=1,5=1
P 1.8 4.024 27 P 0 8 0;0,3=0,5=0
P 1.75 3.945 3 P 0 8 0;3=2,5=1
P 1.766 3.91 30 P 0 8 0;0,3=0,5=0
P 1.5315 3.9459 6 P 0 8 0;1,3=9,5=1
P 1.517 4.113 6 P 0 8 0;1,3=1,5=1
P 1.467 3.851 30 P 0 8 0;0,3=0,5=0
P 1.511 3.863 6 P 0 8 0;1,3=9,5=1
P 1.477 4.142 30 P 0 8 0;0,3=0,5=0
P 1.5153 4.063 6 P 0 8 0;1,3=9,5=1
P 1.472 4.09 31 P 0 8 0;0,3=7,5=0
P 1.521 3.993 6 P 0 8 0;1,3=9,5=1
P 1.477 3.991 30 P 0 8 0;0,3=0,5=0
P 1.624 3.885 30 P 0 8 0;0,3=0,5=0
P 1.579 3.874 6 P 0 8 0;1,3=1,5=1
P 1.435 4.142 30 P 0 8 0;0,3=0,5=0
P 1.585 4.052 3 P 0 8 0;3=2,5=1
P 1.477 4.036 30 P 0 8 0;0,3=0,5=0
P 1.435 4.18 3 P 0 8 0;3=2,5=1
P 1.418 4.09 31 P 0 8 0;0,3=7,5=0
P 1.522 4.163 6 P 0 8 0;1,3=9,5=1
P 1.4 4.01 3 P 0 8 0;3=2,5=1
P 5.14 3.74 3 P 0 8 0;3=2,5=1
P 5.175 3.74 3 P 0 8 0;3=2,5=1
P 5.18 3.825 3 P 0 8 0;3=2,5=1
P 5.675 4.084 27 P 0 8 0;0,3=0,5=0
P 5.675 4.03 3 P 0 8 0;3=2,5=1
P 1.56 3.29 3 P 0 8 0;3=2,5=1
P 1.56 3.25 3 P 0 8 0;3=2,5=1
P 3.245 2.955 3 P 0 8 0;3=2,5=1
P 3.21 2.955 3 P 0 8 0;3=2,5=1
P 3.175 2.955 3 P 0 8 0;3=2,5=1
P 3.245 2.901 27 P 0 8 0;0,3=0,5=0
P 3.185 2.907 32 P 0 8 0;0,3=7,5=0
P 2.59 3.445 3 P 0 8 0;3=2,5=1
P 2.55 3.445 3 P 0 8 0;3=2,5=1
P 2.51 3.445 3 P 0 8 0;3=2,5=1
P 2.47 3.445 3 P 0 8 0;3=2,5=1
P 2.2 3.96 3 P 0 8 0;3=2,5=1
P 2.25 3.96 6 P 0 8 0;1,3=3,5=0
P 1.351 4.126 3 P 0 8 0;3=2,5=1
P 2.165 3.96 3 P 0 8 0;3=2,5=1
P 2.155 3.925 3 P 0 8 0;3=2,5=1
P 2.19 3.925 3 P 0 8 0;3=2,5=1
P 3.23 4.015 6 P 0 8 0;1,3=1,5=1
P 3.244 4.07 30 P 0 8 0;0,3=0,5=0
P 3.2 3.985 3 P 0 8 0;3=2,5=1
P 3.185 3.921 27 P 0 8 0;0,3=0,5=0
P 5.9065 2.4568 3 P 0 8 0;3=2,5=1
P 5.51 2.366 27 P 0 8 0;0,3=0,5=0
P 3.745 4.185 6 P 0 8 0;1,3=3,5=0
P 3.594 4.197 30 P 0 8 0;0,3=0,5=0
P 3.47 3.912 6 P 0 8 0;1,3=1,5=1
P 3.516 3.887 31 P 0 8 0;0,3=7,5=0
P 3.69 4.135 6 P 0 8 0;1,3=3,5=0
P 3.48278996 4.05678002 3 P 0 8 0;3=2,5=1
P 3.522 4.077 30 P 0 8 0;0,3=0,5=0
P 3.522 4.032 30 P 0 8 0;0,3=0,5=0
P 3.476 3.988 6 P 0 8 0;1,3=1,5=1
P 3.522 3.987 30 P 0 8 0;0,3=0,5=0
P 3.386 4.095 30 P 0 8 0;0,3=0,5=0
P 3.437 4.099 6 P 0 8 0;1,3=1,5=1
P 3.598 3.977 3 P 0 8 0;3=2,5=1
P 3.57 3.887 31 P 0 8 0;0,3=7,5=0
P 3.477 3.816 6 P 0 8 0;1,3=1,5=1
P 3.522 3.942 30 P 0 8 0;0,3=0,5=0
P 3.405 3.916 3 P 0 8 0;3=2,5=1
P 5.68326004 3.712 6 P 0 8 0;1,3=1,5=1
P 5.686 3.807 6 P 0 8 0;1,3=1,5=1
P 5.50643002 4.009 6 P 0 8 0;1,3=4,5=1
P 5.686 3.76 6 P 0 8 0;1,3=1,5=1
P 5.72 3.857 30 P 0 8 0;0,3=0,5=0
P 5.675 3.865 6 P 0 8 0;1,3=1,5=1
P 5.718 3.965 6 P 0 8 0;3=3,5=0
P 5.72 3.907 30 P 0 8 0;0,3=0,5=0
P 6.05315 3.67518996 18 P 0 8 0;1,3=23,5=0
P 6.05315 3.50983996 12 P 0 8 0;1,3=24,5=0
P 6.05315 3.34448996 12 P 0 8 0;1,3=24,5=0
P 0.865 3.645 3 P 0 8 0;3=2,5=1
P 0.905 3.645 3 P 0 8 0;3=2,5=1
P 0.945 3.645 3 P 0 8 0;3=2,5=1
P 0.945 3.69 3 P 0 8 0;3=2,5=1
P 0.945 3.73 3 P 0 8 0;3=2,5=1
P 0.945 3.765 3 P 0 8 0;3=2,5=1
P 0.865 3.845 3 P 0 8 0;3=2,5=1
P 0.905 3.845 3 P 0 8 0;3=2,5=1
P 0.94 3.845 3 P 0 8 0;3=2,5=1
P 0.945 3.805 6 P 0 8 0;1,3=1,5=1
P 0.828 3.846 3 P 0 8 0;3=2,5=1
P 0.828 3.646 3 P 0 8 0;3=2,5=1
P 5.66 3.47 6 P 0 8 0;1,3=3,5=0
P 5.68 3.567 6 P 0 8 0;1,3=4,5=1
P 5.406 3.863 6 P 0 8 0;1,3=1,5=1
P 3.46 4.16 3 P 0 8 0;3=2,5=1
P 3.495 4.15 3 P 0 8 0;3=2,5=1
P 3.5 4.195 3 P 0 8 0;3=2,5=1
P 3.53 4.165 3 P 0 8 0;3=2,5=1
P 5.769 4.075 30 P 0 8 0;0,3=0,5=0
P 5.769 4.031 3 P 0 8 0;3=2,5=1
P 5.644 3.967 6 P 0 8 0;1,3=1,5=1
P 5.803 3.907 3 P 0 8 0;3=2,5=1
P 1.45 3.78 3 P 0 8 0;3=2,5=1
P 1.485 3.76 6 P 0 8 0;1,3=9,5=1
P 1.485 3.8 3 P 0 8 0;3=2,5=1
P 5.406 2.346 6 P 0 8 0;1,3=3,5=0
P 5.375 2.32 3 P 0 8 0;3=2,5=1
P 5.34 2.315 3 P 0 8 0;3=2,5=1
P 5.316 3.69401004 21 P 0 8 0;0,3=25,5=0
P 5.43 3.6 6 P 0 8 0;1,3=1,5=1
P 5.433 3.651 3 P 0 8 0;3=2,5=1
P 5.43 3.7 3 P 0 8 0;3=2,5=1
P 5.39 3.6 3 P 0 8 0;3=2,5=1
P 5.393 3.651 3 P 0 8 0;3=2,5=1
P 5.39 3.7 3 P 0 8 0;3=2,5=1
P 1.582 3.776 30 P 0 8 0;0,3=0,5=0
P 1.6055 4.134 3 P 0 8 0;3=2,5=1
P 1.60581998 4.1 3 P 0 8 0;3=2,5=1
P 1.606 4.174 6 P 0 8 0;1,3=9,5=1
P 1.636 3.786 3 P 0 8 0;3=2,5=1
P 1.591 3.826 3 P 0 8 0;3=2,5=1
P 1.633 3.829 6 P 0 8 0;1,3=9,5=1
P 3.408 4.152 3 P 0 8 0;3=2,5=1
P 3.363 4.192 3 P 0 8 0;3=2,5=1
P 3.363 4.152 3 P 0 8 0;3=2,5=1
P 3.363 4.232 6 P 0 8 0;1,3=1,5=1
P 3.393 3.877 3 P 0 8 0;3=2,5=1
P 3.393 3.84 3 P 0 8 0;3=2,5=1
P 3.392 3.803 3 P 0 8 0;3=2,5=1
P 3.564 4.077 30 P 0 8 0;0,3=0,5=0
P 3.607 4.062 3 P 0 8 0;3=2,5=1
P 3.0535 2.217 38 P 0 8 0;0,3=16,5=0
P 2.665 2.065 6 P 0 8 0;1,3=13,5=1
P 2.41441004 2.287 23 P 0 8 0;0,3=21,5=0
P 2.54 2.306 27 P 0 8 0;0,3=0,5=0
P 2.6526 2.3065 25 P 0 8 0;0,3=19,5=0
P 2.59 2.306 27 P 0 8 0;0,3=0,5=0
P 3.185 3.879 27 P 0 8 0;0,3=0,5=0
P 3.185 3.823 37 P 0 8 0;0,3=11,5=0
P 3.3 4.113 6 P 0 8 0;1,3=13,5=1
P 3.344 4.095 30 P 0 8 0;0,3=0,5=0
P 3.286 4.07 30 P 0 8 0;0,3=0,5=0
P 3.564 3.942 30 P 0 8 0;0,3=0,5=0
P 3.564 3.987 30 P 0 8 0;0,3=0,5=0
P 1.807 4.13 33 P 0 8 0;0,3=11,5=0
P 1.8 4.066 27 P 0 8 0;0,3=0,5=0
P 1.352 4.084 6 P 0 8 0;1,3=1,5=1
P 1.678 3.927 6 P 0 8 0;1,3=13,5=1
P 1.666 3.885 30 P 0 8 0;0,3=0,5=0
P 1.724 3.91 30 P 0 8 0;0,3=0,5=0
P 1.435 4.036 30 P 0 8 0;0,3=0,5=0
P 1.435 3.991 30 P 0 8 0;0,3=0,5=0
P 1.95 0.5455 6 P 0 8 0;1,3=9,5=1
P 5.681 3.617 6 P 0 8 0;1,3=1,5=1
P 5.681 3.664 6 P 0 8 0;1,3=1,5=1
P 5.40318002 2.70436004 6 P 0 8 0;1,3=9,5=1
P 5.502 2.721 30 P 0 8 0;0,3=0,5=0
P 0.53 1.444 27 P 0 8 0;0,3=0,5=0
P 0.55921998 1.40543002 6 P 0 8 0;1,3=1,5=1
P 0.535 0.884 27 P 0 8 0;0,3=0,5=0
P 0.57 0.835 6 P 0 8 0;1,3=1,5=1
P 6.23 2.05375 6 P 0 8 0;1,3=13,5=1
P 6.255 2.00973996 27 P 0 8 0;0,3=0,5=0
P 6.21 2.00973996 27 P 0 8 0;0,3=0,5=0
P 3.584 1.827 6 P 0 8 0;1,3=9,5=1
P 1.54 3.776 30 P 0 8 0;0,3=0,5=0
P 1.535 3.905 2 P 0 8 0;3=10,5=1
P 1.539 3.822 6 P 0 8 0;1,3=13,5=1
P 1.477 3.946 30 P 0 8 0;0,3=0,5=0
P 1.477 3.901 30 P 0 8 0;0,3=0,5=0
P 1.98135 0.365 2 P 0 8 0;3=10,5=1
P 1.7317 0.7084 6 P 0 8 0;1,3=1,5=1
P 1.91535 0.412 2 P 0 8 0;3=10,5=1
P 1.8039 0.7072 6 P 0 8 0;1,3=9,5=1
P 3.2271 1.90298996 2 P 0 8 0;3=12,5=1
P 3.533 1.88648996 30 P 0 8 0;0,3=0,5=0
P 3.45301004 1.89898996 2 P 0 8 0;3=12,5=1
P 3.2591 1.90298996 2 P 0 8 0;3=12,5=1
P 3.45301004 1.93098996 2 P 0 8 0;3=12,5=1
P 3.533 1.93148996 30 P 0 8 0;0,3=0,5=0
P 1.26066998 2.64043002 11 P 0 8 0;1,3=26,5=0
P 0.908 2.831 27 P 0 8 0;0,3=0,5=0
P 5.7455 3.0095 34 P 0 8 0;0,3=14,5=0
P 5.7505 2.7245 34 P 0 8 0;0,3=14,5=0
P 5.035 3.945 6 P 0 8 0;1,3=1,5=1
P 5.085 3.896 27 P 0 8 0;0,3=0,5=0
P 5.035 3.896 27 P 0 8 0;0,3=0,5=0
P 5.075 3.945 3 P 0 8 0;3=2,5=1
P 2.97771998 1.88693996 3 P 0 8 0;3=2,5=1
P 3.00995 1.87611004 3 P 0 8 0;3=2,5=1
P 2.875 2.035 6 P 0 8 0;1,3=13,5=1
P 2.999 2.05 30 P 0 8 0;0,3=0,5=0
P 2.79 2.164 27 P 0 8 0;0,3=0,5=0
P 2.7274 2.1935 25 P 0 8 0;0,3=19,5=0
P 2.845 2.168 32 P 0 8 0;0,3=7,5=0
P 3.002 1.945 33 P 0 8 0;0,3=11,5=0
P 2.999 2.005 30 P 0 8 0;0,3=0,5=0
P 2.86066998 2.64043002 11 P 0 8 0;1,3=26,5=0
P 3.185 2.853 32 P 0 8 0;0,3=7,5=0
P 2.9715 2.352 38 P 0 8 0;0,3=16,5=0
P 2.91 2.341 27 P 0 8 0;0,3=0,5=0
P 2.7274 2.3065 25 P 0 8 0;0,3=19,5=0
P 2.85 2.343 37 P 0 8 0;0,3=11,5=0
P 2.96 2.847 37 P 0 8 0;0,3=11,5=0
P 3.035 2.847 37 P 0 8 0;0,3=11,5=0
P 3.11 2.847 37 P 0 8 0;0,3=11,5=0
P 2.855 2.844 27 P 0 8 0;0,3=0,5=0
P 2.9 2.844 27 P 0 8 0;0,3=0,5=0
P 2.79 2.338 27 P 0 8 0;0,3=0,5=0
P 2.155 0.614 27 P 0 8 0;0,3=0,5=0
P 2.2 0.614 27 P 0 8 0;0,3=0,5=0
P 2.26 0.623 32 P 0 8 0;0,3=7,5=0
P 2.105 0.305 2 P 0 8 0;3=10,5=1
P 2.1122 0.13781004 29 P 0 8 0;0,3=27,5=0
P 2.15156998 0.13781004 29 P 0 8 0;0,3=27,5=0
P 2.235 0.5825 3 P 0 8 0;3=2,5=1
P 3.405 0.635 3 P 0 8 0;3=2,5=1
P 5.295 0.605 6 P 0 8 0;1,3=1,5=1
P 5.91 4.04 6 P 0 8 0;1,3=1,5=1
P 5.91 4.089 27 P 0 8 0;0,3=0,5=0
P 2.135 0.54 3 P 0 8 0;3=2,5=1
P 5.215 0.6 6 P 0 8 0;1,3=1,5=1
P 6.025 4.04 6 P 0 8 0;1,3=1,5=1
P 6.025 4.089 27 P 0 8 0;0,3=0,5=0
P 3.36 0.6106 3 P 0 8 0;3=2,5=1
P 0.96 2.41 3 P 0 8 0;3=2,5=1
P 0.68 2.355 3 P 0 8 0;3=2,5=1
P 2.38 3.45 3 P 0 8 0;3=2,5=1
P 1.41 3.795 3 P 0 8 0;3=2,5=1
P 3.445 3.613 3 P 0 8 0;3=2,5=1
P 3.365 3.613 6 P 0 8 0;1,3=1,5=1
P 3.25 3.63 3 P 0 8 0;3=2,5=1
P 3.325 3.613 3 P 0 8 0;3=2,5=1
P 3.405 3.613 3 P 0 8 0;3=2,5=1
P 3.48418002 3.613 3 P 0 8 0;3=2,5=1
P 3.645 4.135 3 P 0 8 0;3=2,5=1
P 1.425 3.851 30 P 0 8 0;0,3=0,5=0
P 3.581 4.13 30 P 0 8 0;0,3=0,5=0
P 3.655 3.059 3 P 0 8 0;3=2,5=1
P 3.614 3.099 3 P 0 8 0;3=2,5=1
P 3.614 3.058 3 P 0 8 0;3=2,5=1
P 3.614 3.015 3 P 0 8 0;3=2,5=1
P 3.662 3.018 37 P 0 8 0;0,3=11,5=0
P 5.236 2.811 3 P 0 8 0;3=2,5=1
P 4.3305 2.914 3 P 0 8 0;3=28,5=1
P 4.3815 2.838 3 P 0 8 0;3=28,5=1
P 4.29 2.74 6 P 0 8 0;3=3,5=0
P 4.456 2.783 3 P 0 8 0;3=2,5=1
P 4.355 2.745 3 P 0 8 0;3=2,5=1
P 4.346 2.783 3 P 0 8 0;3=2,5=1
P 4.4 2.785 3 P 0 8 0;3=2,5=1
P 4 2.655 3 P 0 8 0;3=2,5=1
P 4.566 2.795 30 P 0 8 0;0,3=0,5=0
P 5.014 2.454 33 P 0 8 0;0,3=11,5=0
P 5.022 2.407 3 P 0 8 0;3=2,5=1
P 4.923 2.408 3 P 0 8 0;3=2,5=1
P 4.972 2.406 3 P 0 8 0;3=2,5=1
P 4.971 2.447 3 P 0 8 0;3=2,5=1
P 5.2871 2.275 3 P 0 8 0;3=2,5=1
P 5.389 2.275 30 P 0 8 0;0,3=0,5=0
P 5.62533002 1.02001004 3 P 0 8 0;3=2,5=1
P 5.65933002 1.02 3 P 0 8 0;3=2,5=1
P 3.804 0.816 2 P 0 8 0;3=10,5=1
P 3.77 0.863 32 P 0 8 0;0,3=7,5=0
P 3.77 0.811 27 P 0 8 0;0,3=0,5=0
P 4.269 0.73 30 P 0 8 0;0,3=0,5=0
P 4.27 0.778 32 P 0 8 0;0,3=7,5=0
P 4.23 0.7295 3 P 0 8 0;3=2,5=1
P 2.26 0.677 32 P 0 8 0;0,3=7,5=0
P 2.31 0.715 3 P 0 8 0;3=2,5=1
P 2.31 0.68 3 P 0 8 0;3=2,5=1
P 2.595 0.547 3 P 0 8 0;3=2,5=1
P 1.87598002 0.289 2 P 0 8 0;3=10,5=1
P 1.86 0.33 2 P 0 8 0;3=10,5=1
P 1.83661004 0.13781004 29 P 0 8 0;0,3=27,5=0
P 1.87598002 0.13781004 29 P 0 8 0;0,3=27,5=0
P 1.895 0.33 2 P 0 8 0;3=10,5=1
P 1.87598002 0.369 2 P 0 8 0;3=10,5=1
P 0.705 3.82 3 P 0 8 0;3=2,5=1
P 0.665 3.82 3 P 0 8 0;3=2,5=1
P 0.625 3.82 3 P 0 8 0;3=2,5=1
P 0.625 3.78 6 P 0 8 0;1,3=1,5=1
P 0.625 3.73 6 P 0 8 0;1,3=1,5=1
P 0.66 3.65 3 P 0 8 0;3=2,5=1
P 0.695 3.65 3 P 0 8 0;3=2,5=1
P 0.73 3.65 3 P 0 8 0;3=2,5=1
P 0.625 3.69 3 P 0 8 0;3=2,5=1
P 0.625 3.65 3 P 0 8 0;3=2,5=1
P 3.47 2.376 27 P 0 8 0;0,3=0,5=0
P 3.51 2.37 3 P 0 8 0;3=2,5=1
P 0.618 3.025 6 P 0 8 0;1,3=13,5=1
P 0.5505 3.0284 39 P 0 8 0;0,3=17,5=0
P 0.66 3.014 27 P 0 8 0;0,3=0,5=0
P 0.29 2.915 6 P 0 8 0;1,3=1,5=1
P 0.3695 2.9516 39 P 0 8 0;0,3=17,5=0
P 0.29 2.871 27 P 0 8 0;0,3=0,5=0
P 0.335 2.871 27 P 0 8 0;0,3=0,5=0
P 0.28 2.965 6 P 0 8 0;1,3=1,5=1
P 0.241 2.875 30 P 0 8 0;0,3=0,5=0
P 0.3695 2.9772 39 P 0 8 0;0,3=17,5=0
P 0.241 2.925 30 P 0 8 0;0,3=0,5=0
P 0.285 3.02 6 P 0 8 0;1,3=1,5=1
P 0.3695 3.0028 39 P 0 8 0;0,3=17,5=0
P 0.241 2.975 30 P 0 8 0;0,3=0,5=0
P 0.241 3.025 30 P 0 8 0;0,3=0,5=0
P 2.977 3.351 6 P 0 8 0;1,3=4,5=1
P 3.026 3.35 30 P 0 8 0;0,3=0,5=0
P 3.026 3.305 30 P 0 8 0;0,3=0,5=0
P 3.298 3.34 30 P 0 8 0;0,3=0,5=0
P 3.298 3.295 30 P 0 8 0;0,3=0,5=0
P 3.36525 3.255 6 P 0 8 0;1,3=4,5=1
P 3.36525 3.205 6 P 0 8 0;1,3=4,5=1
P 3.298 3.25 30 P 0 8 0;0,3=0,5=0
P 3.298 3.205 30 P 0 8 0;0,3=0,5=0
P 1.8062 0.7789 6 P 0 8 0;1,3=9,5=1
P 1.8646 0.6442 27 P 0 8 0;0,3=0,5=0
P 3.073 0.613 6 P 0 8 0;1,3=9,5=1
P 2.54526998 0.339 2 P 0 8 0;3=10,5=1
P 2.527 0.44 6 P 0 8 0;1,3=4,5=1
P 5.79 4.261 27 P 0 8 0;0,3=0,5=0
P 5.73991004 4.27558002 6 P 0 8 0;1,3=1,5=1
P 5.435 4.261 27 P 0 8 0;0,3=0,5=0
P 5.38558002 4.27558002 6 P 0 8 0;1,3=1,5=1
P 5.555 4.261 27 P 0 8 0;0,3=0,5=0
P 5.50368996 4.27558002 6 P 0 8 0;1,3=1,5=1
P 5.67 4.261 27 P 0 8 0;0,3=0,5=0
P 5.6218 4.27558002 6 P 0 8 0;1,3=1,5=1
P 5.875 1.9 6 P 0 8 0;1,3=1,5=1
P 3.865 3.65 3 P 0 8 0;3=2,5=1
P 5.91901998 1.95065 27 P 0 8 0;0,3=0,5=0
P 6.06901998 1.86 6 P 0 8 0;1,3=1,5=1
P 6.06901998 1.90865 27 P 0 8 0;0,3=0,5=0
P 3.81 3.65 3 P 0 8 0;3=2,5=1
P 5.96901998 1.95065 27 P 0 8 0;0,3=0,5=0
P 5.97 1.999 6 P 0 8 0;1,3=9,5=1
P 4.62 2.245 3 P 0 8 0;3=2,5=1
P 5.801 3.667 3 P 0 8 0;3=2,5=1
P 3.8 2.045 3 P 0 8 0;3=2,5=1
P 1.275 2.905 3 P 0 8 0;3=2,5=1
P 5.061 2.806 3 P 0 8 0;3=2,5=1
P 3.785 1.302 37 P 0 8 0;0,3=11,5=0
P 3.52 1.334 27 P 0 8 0;0,3=0,5=0
P 3.46 1.312 37 P 0 8 0;0,3=11,5=0
P 3.995 1.2 3 P 0 8 0;3=2,5=1
P 4.07 1.2 3 P 0 8 0;3=2,5=1
P 4.0805 1.16098996 2 P 0 8 0;3=10,5=1
P 4.092 1.005 2 P 0 8 0;3=10,5=1
P 4.135 0.885 3 P 0 8 0;3=2,5=1
P 4.13621998 0.75 2 P 0 8 0;3=10,5=1
P 4.13401998 0.54196998 2 P 0 8 0;3=10,5=1
P 4.09401998 0.54196998 2 P 0 8 0;3=10,5=1
P 4.05401998 0.54196998 2 P 0 8 0;3=10,5=1
P 4.01401998 0.54196998 2 P 0 8 0;3=10,5=1
P 2.985 1.845 3 P 0 8 0;3=2,5=1
P 2.845 1.907 2 P 0 8 0;3=10,5=1
P 2.845 1.811 2 P 0 8 0;3=10,5=1
P 2.822 1.79121004 3 P 0 8 0;3=2,5=1
P 2.71 1.845 3 P 0 8 0;3=2,5=1
P 2.2 0.69 3 P 0 8 0;3=2,5=1
P 2.2 0.656 27 P 0 8 0;0,3=0,5=0
P 2.15 0.69 3 P 0 8 0;3=2,5=1
P 2.155 0.656 27 P 0 8 0;0,3=0,5=0
P 1.9216 0.7784 3 P 0 8 0;3=2,5=1
P 2.0195 0.2905 2 P 0 8 0;3=10,5=1
P 1.91535 0.289 2 P 0 8 0;3=10,5=1
P 1.91535 0.13781004 29 P 0 8 0;0,3=27,5=0
P 1.78196004 0.50601004 2 P 0 8 0;3=10,5=1
P 1.80341004 0.47225 2 P 0 8 0;3=10,5=1
P 1.63543002 0.52158996 2 P 0 8 0;3=10,5=1
P 3.65101004 1.85158996 2 P 0 8 0;3=10,5=1
P 3.45301004 1.86698996 2 P 0 8 0;3=10,5=1
P 3.473 1.79 3 P 0 8 0;3=2,5=1
P 3.505 1.789 27 P 0 8 0;0,3=0,5=0
P 3.1951 1.90298996 2 P 0 8 0;3=10,5=1
P 3.2911 1.90298996 2 P 0 8 0;3=10,5=1
P 2.93896998 0.13781004 29 P 0 8 0;0,3=27,5=0
P 2.958 0.289 2 P 0 8 0;3=10,5=1
P 2.8996 0.13781004 29 P 0 8 0;0,3=27,5=0
P 2.88056998 0.289 2 P 0 8 0;3=10,5=1
P 2.95835 0.321 2 P 0 8 0;3=10,5=1
P 2.80051998 0.289 2 P 0 8 0;3=10,5=1
P 2.78148996 0.13781004 29 P 0 8 0;0,3=27,5=0
P 2.80086998 0.321 2 P 0 8 0;3=10,5=1
P 2.63506998 0.763 2 P 0 8 0;3=10,5=1
P 2.78655 0.763 2 P 0 8 0;3=10,5=1
P 2.73106998 0.763 2 P 0 8 0;3=10,5=1
P 2.7233 0.54871004 3 P 0 8 0;3=2,5=1
P 2.64338996 0.417 2 P 0 8 0;3=10,5=1
P 2.72308996 0.289 2 P 0 8 0;3=10,5=1
P 2.74211998 0.13781004 29 P 0 8 0;0,3=27,5=0
P 2.64303996 0.289 2 P 0 8 0;3=10,5=1
P 2.62401004 0.13781004 29 P 0 8 0;0,3=27,5=0
P 2.64338996 0.321 2 P 0 8 0;3=10,5=1
P 2.53421998 0.763 2 P 0 8 0;3=10,5=1
P 2.595 0.701 3 P 0 8 0;3=2,5=1
P 2.42716004 0.13781004 29 P 0 8 0;0,3=27,5=0
P 2.44618996 0.289 2 P 0 8 0;3=10,5=1
P 2.54526998 0.289 2 P 0 8 0;3=10,5=1
P 2.54526998 0.13781004 29 P 0 8 0;0,3=27,5=0
P 2.43821998 0.763 2 P 0 8 0;3=10,5=1
P 2.40508002 0.667 2 P 0 8 0;3=10,5=1
P 2.40508002 0.763 2 P 0 8 0;3=10,5=1
P 2.327 0.291 2 P 0 8 0;3=10,5=1
P 2.30905 0.13781004 29 P 0 8 0;0,3=27,5=0
P 3.56 1.305 3 P 0 8 0;3=2,5=1
P 3.535 1.305 3 P 0 8 0;3=2,5=1
P 3.51 1.305 3 P 0 8 0;3=2,5=1
P 3.54 1.28 3 P 0 8 0;3=2,5=1
P 3.57863996 1.04706998 2 P 0 8 0;3=10,5=1
P 3.593 0.92 2 P 0 8 0;3=10,5=1
P 3.65401998 0.54196998 2 P 0 8 0;3=10,5=1
P 3.61401998 0.54196998 2 P 0 8 0;3=10,5=1
P 3.57401998 0.54196998 2 P 0 8 0;3=10,5=1
P 3.53401998 0.54196998 2 P 0 8 0;3=10,5=1
P 3.49401998 0.54196998 2 P 0 8 0;3=10,5=1
P 3.375 1.226 2 P 0 8 0;3=10,5=1
P 3.375 1.13 2 P 0 8 0;3=10,5=1
P 3.48263996 1.04706998 2 P 0 8 0;3=10,5=1
P 3.48198996 1.085 2 P 0 8 0;3=10,5=1
P 3.38598996 1.085 2 P 0 8 0;3=10,5=1
P 3.33401998 0.54196998 2 P 0 8 0;3=10,5=1
P 3.45401998 0.54196998 2 P 0 8 0;3=10,5=1
P 3.41401998 0.54196998 2 P 0 8 0;3=10,5=1
P 3.37401998 0.54196998 2 P 0 8 0;3=10,5=1
P 3.17025 0.82975 2 P 0 8 0;3=10,5=1
P 3.17401998 0.54196998 2 P 0 8 0;3=10,5=1
P 3.21401998 0.54196998 2 P 0 8 0;3=10,5=1
P 3.25401998 0.54196998 2 P 0 8 0;3=10,5=1
P 3.29401998 0.54196998 2 P 0 8 0;3=10,5=1
P 3.10236998 0.89763002 2 P 0 8 0;3=10,5=1
P 3.035 0.694 3 P 0 8 0;3=2,5=1
P 2.98726004 0.49471004 2 P 0 8 0;3=10,5=1
P 2.98726004 0.43528996 2 P 0 8 0;3=10,5=1
P 3.07708002 0.289 2 P 0 8 0;3=10,5=1
P 3.05708002 0.13781004 29 P 0 8 0;0,3=27,5=0
P 2.88255 0.763 2 P 0 8 0;3=10,5=1
P 2.95835 0.417 2 P 0 8 0;3=10,5=1
P 2.80086998 0.417 2 P 0 8 0;3=10,5=1
P 3.9845 1.16098996 2 P 0 8 0;3=10,5=1
P 3.9 1.005 2 P 0 8 0;3=10,5=1
P 3.964 1.005 6 P 0 8 0;1,3=9,5=1
P 3.97401998 0.54196998 2 P 0 8 0;3=10,5=1
P 3.93401998 0.54196998 2 P 0 8 0;3=10,5=1
P 3.89401998 0.54196998 2 P 0 8 0;3=10,5=1
P 3.85401998 0.54196998 2 P 0 8 0;3=10,5=1
P 3.798 1.771 3 P 0 8 0;3=2,5=1
P 3.647 1.694 3 P 0 8 0;3=2,5=1
P 3.676 1.693 3 P 0 8 0;3=2,5=1
P 3.718 1.32 3 P 0 8 0;3=2,5=1
P 3.743 1.32 3 P 0 8 0;3=2,5=1
P 3.718 1.29 3 P 0 8 0;3=2,5=1
P 3.743 1.29 3 P 0 8 0;3=2,5=1
P 3.67 1.26 3 P 0 8 0;3=2,5=1
P 3.84 1.095 3 P 0 8 0;3=2,5=1
P 3.84 1.0298 3 P 0 8 0;3=2,5=1
P 3.798 1.06 33 P 0 8 0;0,3=11,5=0
P 3.76838002 1.0023 3 P 0 8 0;3=2,5=1
P 3.735 0.94 2 P 0 8 0;3=10,5=1
P 3.689 0.92 2 P 0 8 0;3=10,5=1
P 3.805 0.774 2 P 0 8 0;3=10,5=1
P 3.77 0.769 27 P 0 8 0;0,3=0,5=0
P 3.735 0.78 2 P 0 8 0;3=10,5=1
P 3.795 0.725 6 P 0 8 0;1,3=9,5=1
P 3.81401998 0.54196998 2 P 0 8 0;3=10,5=1
P 3.77401998 0.54196998 2 P 0 8 0;3=10,5=1
P 3.73401998 0.54196998 2 P 0 8 0;3=10,5=1
P 3.69401998 0.54196998 2 P 0 8 0;3=10,5=1
P 3.551 1.694 3 P 0 8 0;3=2,5=1
P 3.576 1.694 3 P 0 8 0;3=2,5=1
P 3.526 1.694 3 P 0 8 0;3=2,5=1
P 3.501 1.694 3 P 0 8 0;3=2,5=1
P 3.636 1.766 3 P 0 8 0;3=2,5=1
P 4.00973002 1.44971998 5 P 0 8 0;0,3=18,5=0
P 4.0491 1.41036004 5 P 0 8 0;0,3=18,5=0
P 4.00971998 1.80406004 5 P 0 8 0;0,3=18,5=0
P 4.12783996 1.64656998 5 P 0 8 0;0,3=18,5=0
P 4.12785 1.56783996 5 P 0 8 0;0,3=18,5=0
P 4.00973002 1.6072 5 P 0 8 0;0,3=18,5=0
P 4.0491 1.64658996 5 P 0 8 0;0,3=18,5=0
P 4.00973002 1.56785 5 P 0 8 0;0,3=18,5=0
P 4.12785 1.60721004 5 P 0 8 0;0,3=18,5=0
P 3.97036004 1.84343002 5 P 0 8 0;0,3=18,5=0
P 3.93098002 1.7647 5 P 0 8 0;0,3=18,5=0
P 3.8443 1.745 30 P 0 8 0;0,3=0,5=0
P 3.97036004 1.64658002 5 P 0 8 0;0,3=18,5=0
P 3.97036004 1.52846998 5 P 0 8 0;0,3=18,5=0
P 3.97035 1.48911004 5 P 0 8 0;0,3=18,5=0
P 3.8916 1.4891 5 P 0 8 0;0,3=18,5=0
P 3.87628996 1.29361004 30 P 0 8 0;0,3=0,5=0
P 2.86066998 1.04043002 11 P 0 8 0;1,3=26,5=0
P 4.6053 1.22166998 2 P 0 8 0;3=10,5=1
P 1.041 3.825 2 P 0 8 0;3=10,5=1
P 1.137 3.825 2 P 0 8 0;3=10,5=1
P 6.56038996 1.41205 2 P 0 8 0;3=10,5=1
P 6.56038996 1.37205 2 P 0 8 0;3=10,5=1
P 6.56038996 1.33205 2 P 0 8 0;3=10,5=1
P 6.56038996 1.29205 2 P 0 8 0;3=10,5=1
P 6.56038996 1.25205 2 P 0 8 0;3=10,5=1
P 6.56038996 1.21205 2 P 0 8 0;3=10,5=1
P 6.56038996 1.17205 2 P 0 8 0;3=10,5=1
P 6.56038996 1.13205 2 P 0 8 0;3=10,5=1
P 6.56038996 1.09205 2 P 0 8 0;3=10,5=1
P 5.9645 2.1035 3 P 0 8 0;3=28,5=1
P 6.0155 2.0845 3 P 0 8 0;3=28,5=1
P 0.22703996 0.43635 4 P 0 8 0;3=29,5=0
P 0.19878002 0.36811004 4 P 0 8 0;3=29,5=0
P 0.22703996 0.29986998 4 P 0 8 0;3=29,5=0
P 0.29528002 0.27161004 4 P 0 8 0;3=29,5=0
P 0.36351998 0.29986998 4 P 0 8 0;3=29,5=0
P 0.39178002 0.36811004 4 P 0 8 0;3=29,5=0
P 0.36351998 0.43635 4 P 0 8 0;3=29,5=0
P 0.29528002 0.46461004 4 P 0 8 0;3=29,5=0
P 6.33215 0.72178002 4 P 0 8 0;3=29,5=0
P 6.30388996 0.65353996 4 P 0 8 0;3=29,5=0
P 6.33215 0.5853 4 P 0 8 0;3=29,5=0
P 6.40038996 0.55703996 4 P 0 8 0;3=29,5=0
P 6.46863002 0.5853 4 P 0 8 0;3=29,5=0
P 6.49688996 0.65353996 4 P 0 8 0;3=29,5=0
P 6.46863002 0.72178002 4 P 0 8 0;3=29,5=0
P 6.40038996 0.75003996 4 P 0 8 0;3=29,5=0
P 6.33215 4.24658996 4 P 0 8 0;3=29,5=0
P 6.30388996 4.17835 4 P 0 8 0;3=29,5=0
P 6.33215 4.11011004 4 P 0 8 0;3=29,5=0
P 6.40038996 4.08185 4 P 0 8 0;3=29,5=0
P 6.46863002 4.11011004 4 P 0 8 0;3=29,5=0
P 6.49688996 4.17835 4 P 0 8 0;3=29,5=0
P 6.46863002 4.24658996 4 P 0 8 0;3=29,5=0
P 6.40038996 4.27485 4 P 0 8 0;3=29,5=0
P 5.92 1.36 6 P 0 8 0;3=1,5=1
P 6.22 1.36 3 P 0 8 0;3=2,5=1
P 5.99 0.925 3 P 0 8 0;3=2,5=1
P 4.24 3.983 27 P 0 8 0;0,3=0,5=0
P 1.265 3.606 27 P 0 8 0;0,3=0,5=0
P 5.803 3.857 3 P 0 8 0;3=2,5=1
P 5.465 3.441 33 P 0 8 0;0,3=11,5=0
P 5.465 3.288 33 P 0 8 0;0,3=11,5=0
P 5.465 3.364 33 P 0 8 0;0,3=11,5=0
P 5.461 3.206 33 P 0 8 0;0,3=11,5=0
P 1.355 3.905 3 P 0 8 0;3=2,5=1
P 1.21168996 3.96891998 3 P 0 8 0;3=2,5=1
P 0.42 2.368 3 P 0 8 0;3=2,5=1
P 1.885 2.981 27 P 0 8 0;0,3=0,5=0
P 5.325 2.725 3 P 0 8 0;3=2,5=1
P 1.6985 2.9895 3 P 0 8 0;3=28,5=1
P 1.6615 3.0405 3 P 0 8 0;3=28,5=1
P 5.6435 0.6535 3 P 0 8 0;3=28,5=1
P 5.1265 2.6815 3 P 0 8 0;3=28,5=1
P 5.0895 2.7325 3 P 0 8 0;3=28,5=1
P 4.1915 4.0395 3 P 0 8 0;3=28,5=1
P 4.0965 3.9445 3 P 0 8 0;3=28,5=1
P 4.1235 3.9715 3 P 0 8 0;3=28,5=1
P 4.1645 3.9715 3 P 0 8 0;3=28,5=1
P 4.1645 4.0125 3 P 0 8 0;3=28,5=1
P 4.1235 4.0125 3 P 0 8 0;3=28,5=1
P 4.0965 4.0395 3 P 0 8 0;3=28,5=1
P 4.1915 3.9445 3 P 0 8 0;3=28,5=1
P 4.5 4.07 3 P 0 8 0;3=2,5=1
P 4.31 4.16 3 P 0 8 0;3=2,5=1
P 1.41 2.985 3 P 0 8 0;3=2,5=1
P 1.479 3 30 P 0 8 0;0,3=0,5=0
P 1.45 2.965 3 P 0 8 0;3=2,5=1
P 1.51 3.242 3 P 0 8 0;3=2,5=1
P 1.89 3.26 3 P 0 8 0;3=2,5=1
P 1.895 3.19 3 P 0 8 0;3=2,5=1
P 1.9 3.055 3 P 0 8 0;3=2,5=1
P 1.9 3.015 3 P 0 8 0;3=2,5=1
P 1.65 2.94 3 P 0 8 0;3=2,5=1
P 1.685 2.94 3 P 0 8 0;3=2,5=1
P 4.7184 2.07965 5 P 0 8 0;0,3=18,5=0
P 4.71838996 2.1584 5 P 0 8 0;0,3=18,5=0
P 4.681 1.755 30 P 0 8 0;0,3=0,5=0
P 5.17 2.125 3 P 0 8 0;3=2,5=1
P 4.71838996 1.68595 5 P 0 8 0;0,3=18,5=0
P 4.67901998 1.84343002 5 P 0 8 0;0,3=18,5=0
P 4.56091004 1.8828 5 P 0 8 0;0,3=18,5=0
P 4.96 1.79258002 3 P 0 8 0;3=2,5=1
P 4.59 3.26 3 P 0 8 0;3=2,5=1
P 2.866 1.987 2 P 0 8 0;3=10,5=1
P 2.77 1.987 2 P 0 8 0;3=10,5=1
P 4.5093 1.22166998 2 P 0 8 0;3=10,5=1
P 0.04 2.85618996 2 P 0 8 0;3=10,5=1
P 0.04 2.81618996 2 P 0 8 0;3=10,5=1
P 0.04 3.13618996 2 P 0 8 0;3=10,5=1
P 0.04 3.09618996 2 P 0 8 0;3=10,5=1
P 0.04 3.05618996 2 P 0 8 0;3=10,5=1
P 0.04 3.01618996 2 P 0 8 0;3=10,5=1
P 3.49 3.03 3 P 0 8 0;3=2,5=1
P 3.555 3.065 3 P 0 8 0;3=2,5=1
P 3.695 2.675 3 P 0 8 0;3=2,5=1
P 3.725 2.32 3 P 0 8 0;3=2,5=1
P 0.945 1.05 3 P 0 8 0;3=2,5=1
P 4.635 0.865 3 P 0 8 0;3=2,5=1
P 4.694 0.915 30 P 0 8 0;0,3=0,5=0
P 0.866 1.413 3 P 0 8 0;3=2,5=1
P 2.885 3.17 3 P 0 8 0;3=2,5=1
P 0.83 4.17 3 P 0 8 0;3=2,5=1
P 0.455 1.26 3 P 0 8 0;3=2,5=1
P 0.175 0.91 3 P 0 8 0;3=2,5=1
P 0.17 2.045 3 P 0 8 0;3=2,5=1
P 0.455 1.61 3 P 0 8 0;3=2,5=1
P 1.32 3.755 3 P 0 8 0;3=2,5=1
P 1.25095 3.06095 3 P 0 8 0;3=2,5=1
P 0.95593002 3.33346998 3 P 0 8 0;3=2,5=1
P 0.575 2.89 6 P 0 8 0;1,3=1,5=1
P 0.5505 2.9516 39 P 0 8 0;0,3=17,5=0
P 0.16 3.025 3 P 0 8 0;3=2,5=1
P 0.199 3.025 30 P 0 8 0;0,3=0,5=0
P 0.16 3.075 3 P 0 8 0;3=2,5=1
P 0.199 3.075 30 P 0 8 0;0,3=0,5=0
P 0.7 3.384 27 P 0 8 0;0,3=0,5=0
P 0.72 3.35 3 P 0 8 0;3=2,5=1
P 0.635 3.596 3 P 0 8 0;3=2,5=1
P 0.671 3.575 2 P 0 8 0;3=10,5=1
P 0.767 3.575 2 P 0 8 0;3=10,5=1
P 1.4213 3.2563 3 P 0 8 0;3=2,5=1
P 4.472 3.475 3 P 0 8 0;3=2,5=1
P 5.97703002 1.87 3 P 0 8 0;3=2,5=1
P 0.606 1.612 3 P 0 8 0;3=2,5=1
P 5.33 0.87 3 P 0 8 0;3=2,5=1
P 6.26988996 2.37988996 3 P 0 8 0;3=2,5=1
P 4.46 3.745 3 P 0 8 0;3=2,5=1
P 3.83 3.415 3 P 0 8 0;3=2,5=1
P 3.506 3.325 30 P 0 8 0;0,3=0,5=0
P 3.55 3.325 2 P 0 8 0;3=10,5=1
P 6.335 3.015 3 P 0 8 0;3=2,5=1
P 1.667 3.388 3 P 0 8 0;3=2,5=1
P 0.995 3.564 27 P 0 8 0;0,3=0,5=0
P 4.48216998 1.80405 5 P 0 8 0;0,3=18,5=0
P 4.4428 1.80405 5 P 0 8 0;0,3=18,5=0
P 4.40343996 1.80406004 5 P 0 8 0;0,3=18,5=0
P 4.48216004 1.96153996 5 P 0 8 0;0,3=18,5=0
P 4.311 0.73 30 P 0 8 0;0,3=0,5=0
P 1.591 3.504 3 P 0 8 0;3=2,5=1
P 1.63 3.504 27 P 0 8 0;0,3=0,5=0
P 1.035 3.094 27 P 0 8 0;0,3=0,5=0
P 1.045 3.055 3 P 0 8 0;3=2,5=1
P 1.42 3.5 3 P 0 8 0;3=2,5=1
P 1.376 3.5 30 P 0 8 0;0,3=0,5=0
P 1.235 3.475 3 P 0 8 0;3=2,5=1
P 1.196 3.475 30 P 0 8 0;0,3=0,5=0
P 1.085 3.606 27 P 0 8 0;0,3=0,5=0
P 1.375 3.559 27 P 0 8 0;0,3=0,5=0
P 1.2 3.715 3 P 0 8 0;3=2,5=1
P 1.175 3.606 27 P 0 8 0;0,3=0,5=0
P 1.22 3.606 27 P 0 8 0;0,3=0,5=0
P 1.13 3.606 27 P 0 8 0;0,3=0,5=0
P 1.409 3.554 3 P 0 8 0;3=2,5=1
P 1.2 3.68 3 P 0 8 0;3=2,5=1
P 1.155 3.89 3 P 0 8 0;3=2,5=1
P 1.17 3.97 3 P 0 8 0;3=2,5=1
P 1.27 3.97061004 3 P 0 8 0;3=2,5=1
P 1.29 3.705 3 P 0 8 0;3=2,5=1
P 1.355 3.83 3 P 0 8 0;3=2,5=1
P 1.355 3.96 3 P 0 8 0;3=2,5=1
P 1.185 3.79 3 P 0 8 0;3=2,5=1
P 1.32 3.79 3 P 0 8 0;3=2,5=1
P 1.29 3.65 3 P 0 8 0;3=2,5=1
P 5.803 3.567 3 P 0 8 0;3=2,5=1
P 5.43 3.967 3 P 0 8 0;3=2,5=1
P 6.165 1.94873996 3 P 0 8 0;3=2,5=1
P 6.21 1.96773996 27 P 0 8 0;0,3=0,5=0
P 1.038 0.7624 3 P 0 8 0;3=2,5=1
P 4.037 2.593 3 P 0 8 0;3=2,5=1
P 3.978 2.593 3 P 0 8 0;3=2,5=1
P 4.209 2.552 27 P 0 8 0;0,3=0,5=0
P 4.15 2.552 27 P 0 8 0;0,3=0,5=0
P 4.093 2.552 27 P 0 8 0;0,3=0,5=0
P 4.037 2.552 27 P 0 8 0;0,3=0,5=0
P 3.978 2.552 27 P 0 8 0;0,3=0,5=0
P 3.919 2.552 27 P 0 8 0;0,3=0,5=0
P 3.801 2.552 27 P 0 8 0;0,3=0,5=0
P 3.86 2.552 27 P 0 8 0;0,3=0,5=0
P 4.81 0.707 3 P 0 8 0;3=2,5=1
P 6.47 1.135 3 P 0 8 0;3=2,5=1
P 4.595 3.22 3 P 0 8 0;3=2,5=1
P 4.17 3.471 27 P 0 8 0;0,3=0,5=0
P 4.175 3.52 3 P 0 8 0;3=2,5=1
P 3.98 3.471 27 P 0 8 0;0,3=0,5=0
P 3.98 3.52 3 P 0 8 0;3=2,5=1
P 3.973 3.207 3 P 0 8 0;3=2,5=1
P 3.973 3.239 30 P 0 8 0;0,3=0,5=0
P 4.075 3.05 3 P 0 8 0;3=2,5=1
P 3.839 3.726 3 P 0 8 0;3=2,5=1
P 3.839 3.758 30 P 0 8 0;0,3=0,5=0
P 4.1 3.58543002 3 P 0 8 0;3=2,5=1
P 5.637 3.524 6 P 0 8 0;1,3=1,5=1
P 5.316 3.51998996 21 P 0 8 0;0,3=25,5=0
P 5.276 3.189 3 P 0 8 0;3=2,5=1
P 5.329 3.189 3 P 0 8 0;3=2,5=1
P 5.386 3.189 3 P 0 8 0;3=2,5=1
P 5.271 3.456 3 P 0 8 0;3=2,5=1
P 5.271 3.406 3 P 0 8 0;3=2,5=1
P 5.324 3.456 3 P 0 8 0;3=2,5=1
P 5.381 3.456 3 P 0 8 0;3=2,5=1
P 5.324 3.406 3 P 0 8 0;3=2,5=1
P 5.381 3.406 3 P 0 8 0;3=2,5=1
P 5.802 3.617 3 P 0 8 0;3=2,5=1
P 5.763 3.712 3 P 0 8 0;3=2,5=1
P 5.803 3.757 3 P 0 8 0;3=2,5=1
P 5.803 3.807 3 P 0 8 0;3=2,5=1
P 5.602 3.865 3 P 0 8 0;3=2,5=1
P 5.645 3.79 3 P 0 8 0;3=2,5=1
P 5.48556998 3.877 6 P 0 8 0;1,3=1,5=1
P 5.237 3.777 3 P 0 8 0;3=2,5=1
P 5.282 3.777 3 P 0 8 0;3=2,5=1
P 5.237 3.841 3 P 0 8 0;3=2,5=1
P 5.322 3.777 3 P 0 8 0;3=2,5=1
P 5.385 4.07875 3 P 0 8 0;3=2,5=1
P 0.199 2.875 30 P 0 8 0;0,3=0,5=0
P 0.199 2.83 3 P 0 8 0;3=2,5=1
P 0.29 2.829 27 P 0 8 0;0,3=0,5=0
P 1.2 3.645 3 P 0 8 0;3=2,5=1
P 1.1 3.64 3 P 0 8 0;3=2,5=1
P 1.065 3.64 3 P 0 8 0;3=2,5=1
P 1.03 3.64 3 P 0 8 0;3=2,5=1
P 0.99 3.5 3 P 0 8 0;3=2,5=1
P 0.664 0.774 3 P 0 8 0;3=2,5=1
P 0.86 0.833 27 P 0 8 0;0,3=0,5=0
P 0.833 0.871 3 P 0 8 0;3=2,5=1
P 0.833 0.911 27 P 0 8 0;0,3=0,5=0
P 0.878 0.911 27 P 0 8 0;0,3=0,5=0
P 0.66 0.911 3 P 0 8 0;3=2,5=1
P 0.698 0.911 27 P 0 8 0;0,3=0,5=0
P 0.695 1 3 P 0 8 0;3=2,5=1
P 0.485 2.715 3 P 0 8 0;3=2,5=1
P 0.51771998 2.45073996 3 P 0 8 0;3=2,5=1
P 0.675 2.229 3 P 0 8 0;3=2,5=1
P 0.575 2.185 3 P 0 8 0;3=2,5=1
P 0.51771998 1.87986998 3 P 0 8 0;3=2,5=1
P 0.539 1.57 3 P 0 8 0;3=2,5=1
P 0.51771998 1.305 3 P 0 8 0;3=2,5=1
P 0.476 0.689 3 P 0 8 0;3=2,5=1
P 0.614 1.049 3 P 0 8 0;3=2,5=1
P 0.51771998 0.736 3 P 0 8 0;3=2,5=1
P 0.47 1 3 P 0 8 0;3=2,5=1
P 0.677 0.65 3 P 0 8 0;3=2,5=1
P 0.677 0.615 30 P 0 8 0;0,3=0,5=0
P 4.546 1.085 3 P 0 8 0;3=2,5=1
P 4.585 1.139 27 P 0 8 0;0,3=0,5=0
P 4.53 1.139 27 P 0 8 0;0,3=0,5=0
P 0.43705 3.51576004 19 P 0 8 0;3=30,5=0
P 0.43705 3.31655 19 P 0 8 0;3=30,5=0
P 0.24806998 3.47245 19 P 0 8 0;3=30,5=0
P 0.24806998 3.35985 19 P 0 8 0;3=30,5=0
P 0.24606004 3.4315 4 P 0 8 0;3=6,5=0
P 0.4587 3.4315 4 P 0 8 0;3=6,5=0
P 0.44098002 3.4008 4 P 0 8 0;3=6,5=0
P 0.22833996 3.4008 4 P 0 8 0;3=6,5=0
P 0.858 2.831 27 P 0 8 0;0,3=0,5=0
P 3.0535 2.143 38 P 0 8 0;0,3=16,5=0
P 5.75071998 1.655 3 P 0 8 0;3=2,5=1
P 1.76 4.16 3 P 0 8 0;3=2,5=1
P 2.26 3.785 3 P 0 8 0;3=2,5=1
P 2.215 3.785 3 P 0 8 0;3=2,5=1
P 3.843 3.687 3 P 0 8 0;3=2,5=1
P 0.61488996 3.32328996 3 P 0 8 0;3=2,5=1
P 5.335 1.245 3 P 0 8 0;3=2,5=1
P 5.345 1.3 3 P 0 8 0;3=2,5=1
P 5.345 1.365 3 P 0 8 0;3=2,5=1
P 3.645 2.13 3 P 0 8 0;3=2,5=1
P 3.651 2.17 30 P 0 8 0;0,3=0,5=0
P 3.67 2.13 3 P 0 8 0;3=2,5=1
P 3.11 1.935 3 P 0 8 0;3=2,5=1
P 4.294 1.075 3 P 0 8 0;3=2,5=1
P 4.5 1.082 3 P 0 8 0;3=2,5=1
P 5.385 1.895 3 P 0 8 0;3=2,5=1
P 5.425 1.895 3 P 0 8 0;3=2,5=1
P 5.4 1.853 37 P 0 8 0;0,3=11,5=0
P 5.39 1.604 27 P 0 8 0;0,3=0,5=0
P 5.76458996 1.61971004 3 P 0 8 0;3=2,5=1
P 5.34 1.605 3 P 0 8 0;3=2,5=1
P 5.44 1.59 3 P 0 8 0;3=2,5=1
P 0.12878002 0.21716998 2 P 0 8 0;3=10,5=1
P 0.16878002 0.21716998 2 P 0 8 0;3=10,5=1
P 0.20878002 0.21716998 2 P 0 8 0;3=10,5=1
P 0.24878002 0.21716998 2 P 0 8 0;3=10,5=1
P 0.08413002 4.33598002 2 P 0 8 0;3=10,5=1
P 0.04413002 4.33598002 2 P 0 8 0;3=10,5=1
P 0.04 4.29618996 2 P 0 8 0;3=10,5=1
P 0.04 4.25618996 2 P 0 8 0;3=10,5=1
P 0.04 4.21618996 2 P 0 8 0;3=10,5=1
P 0.04 4.17618996 2 P 0 8 0;3=10,5=1
P 0.04 4.13618996 2 P 0 8 0;3=10,5=1
P 0.04 4.09618996 2 P 0 8 0;3=10,5=1
P 0.04 4.05618996 2 P 0 8 0;3=10,5=1
P 0.04 4.01618996 2 P 0 8 0;3=10,5=1
P 0.04 3.97618996 2 P 0 8 0;3=10,5=1
P 0.04 3.93618996 2 P 0 8 0;3=10,5=1
P 0.04 3.89618996 2 P 0 8 0;3=10,5=1
P 0.04 3.85618996 2 P 0 8 0;3=10,5=1
P 0.04 3.81618996 2 P 0 8 0;3=10,5=1
P 0.04 3.77618996 2 P 0 8 0;3=10,5=1
P 0.04 3.73618996 2 P 0 8 0;3=10,5=1
P 0.04 3.69618996 2 P 0 8 0;3=10,5=1
P 0.04 3.65618996 2 P 0 8 0;3=10,5=1
P 0.04 3.61618996 2 P 0 8 0;3=10,5=1
P 0.04 3.57618996 2 P 0 8 0;3=10,5=1
P 0.04 3.53618996 2 P 0 8 0;3=10,5=1
P 0.04 3.49618996 2 P 0 8 0;3=10,5=1
P 0.04 3.45618996 2 P 0 8 0;3=10,5=1
P 0.04 3.41618996 2 P 0 8 0;3=10,5=1
P 0.04 3.37618996 2 P 0 8 0;3=10,5=1
P 0.04 2.97618996 2 P 0 8 0;3=10,5=1
P 0.04 2.93618996 2 P 0 8 0;3=10,5=1
P 0.04 2.89618996 2 P 0 8 0;3=10,5=1
P 0.04 0.49618996 2 P 0 8 0;3=10,5=1
P 0.04 0.45618996 2 P 0 8 0;3=10,5=1
P 0.04 0.41618996 2 P 0 8 0;3=10,5=1
P 0.04 0.37618996 2 P 0 8 0;3=10,5=1
P 0.04 0.33618996 2 P 0 8 0;3=10,5=1
P 0.04 0.29618996 2 P 0 8 0;3=10,5=1
P 0.04 0.25618996 2 P 0 8 0;3=10,5=1
P 0.04878002 0.21716998 2 P 0 8 0;3=10,5=1
P 0.08878002 0.21716998 2 P 0 8 0;3=10,5=1
P 2.76413002 4.33598002 2 P 0 8 0;3=10,5=1
P 2.72413002 4.33598002 2 P 0 8 0;3=10,5=1
P 2.68413002 4.33598002 2 P 0 8 0;3=10,5=1
P 2.64413002 4.33598002 2 P 0 8 0;3=10,5=1
P 2.60413002 4.33598002 2 P 0 8 0;3=10,5=1
P 0.55055 0.45073002 2 P 0 8 0;3=10,5=1
P 0.55558002 0.49041004 2 P 0 8 0;3=10,5=1
P 0.57858996 0.52313002 2 P 0 8 0;3=10,5=1
P 0.61463002 0.54048002 2 P 0 8 0;3=10,5=1
P 0.55055 0.29073002 2 P 0 8 0;3=10,5=1
P 0.55055 0.33073002 2 P 0 8 0;3=10,5=1
P 0.55055 0.37073002 2 P 0 8 0;3=10,5=1
P 0.55055 0.41073002 2 P 0 8 0;3=10,5=1
P 0.48878002 0.21716998 2 P 0 8 0;3=10,5=1
P 0.52878002 0.21716998 2 P 0 8 0;3=10,5=1
P 0.55055 0.25073002 2 P 0 8 0;3=10,5=1
P 0.44413002 4.33598002 2 P 0 8 0;3=10,5=1
P 0.40413002 4.33598002 2 P 0 8 0;3=10,5=1
P 0.36413002 4.33598002 2 P 0 8 0;3=10,5=1
P 0.32413002 4.33598002 2 P 0 8 0;3=10,5=1
P 0.28878002 0.21716998 2 P 0 8 0;3=10,5=1
P 0.32878002 0.21716998 2 P 0 8 0;3=10,5=1
P 0.36878002 0.21716998 2 P 0 8 0;3=10,5=1
P 0.40878002 0.21716998 2 P 0 8 0;3=10,5=1
P 0.44878002 0.21716998 2 P 0 8 0;3=10,5=1
P 0.28413002 4.33598002 2 P 0 8 0;3=10,5=1
P 0.24413002 4.33598002 2 P 0 8 0;3=10,5=1
P 0.20413002 4.33598002 2 P 0 8 0;3=10,5=1
P 0.16413002 4.33598002 2 P 0 8 0;3=10,5=1
P 0.12413002 4.33598002 2 P 0 8 0;3=10,5=1
P 0.889 0.67 3 P 0 8 0;3=2,5=1
P 0.6546 0.54196998 2 P 0 8 0;3=10,5=1
P 0.6946 0.54196998 2 P 0 8 0;3=10,5=1
P 0.7346 0.54196998 2 P 0 8 0;3=10,5=1
P 0.7746 0.54196998 2 P 0 8 0;3=10,5=1
P 0.8146 0.54196998 2 P 0 8 0;3=10,5=1
P 0.64413002 4.33598002 2 P 0 8 0;3=10,5=1
P 0.60413002 4.33598002 2 P 0 8 0;3=10,5=1
P 0.56413002 4.33598002 2 P 0 8 0;3=10,5=1
P 0.52413002 4.33598002 2 P 0 8 0;3=10,5=1
P 0.48413002 4.33598002 2 P 0 8 0;3=10,5=1
P 0.8575 2.0275 3 P 0 8 0;3=2,5=1
P 1.195 0.57693996 3 P 0 8 0;3=2,5=1
P 0.8546 0.54196998 2 P 0 8 0;3=10,5=1
P 0.8946 0.54196998 2 P 0 8 0;3=10,5=1
P 0.9346 0.54196998 2 P 0 8 0;3=10,5=1
P 0.9746 0.54196998 2 P 0 8 0;3=10,5=1
P 0.80413002 4.33598002 2 P 0 8 0;3=10,5=1
P 0.76413002 4.33598002 2 P 0 8 0;3=10,5=1
P 0.72413002 4.33598002 2 P 0 8 0;3=10,5=1
P 0.68413002 4.33598002 2 P 0 8 0;3=10,5=1
P 0.66 4.19 3 P 0 8 0;3=2,5=1
P 0.67 2.831 2 P 0 8 0;3=10,5=1
P 0.79248002 2.661 2 P 0 8 0;3=10,5=1
P 0.80148002 2.53648002 3 P 0 8 0;3=2,5=1
P 0.715 2.478 3 P 0 8 0;3=2,5=1
P 0.714 2.217 3 P 0 8 0;3=2,5=1
P 0.74593002 2.02206998 3 P 0 8 0;3=2,5=1
P 1.0146 0.54196998 2 P 0 8 0;3=10,5=1
P 1.0546 0.54196998 2 P 0 8 0;3=10,5=1
P 1.0946 0.54196998 2 P 0 8 0;3=10,5=1
P 1.1346 0.54196998 2 P 0 8 0;3=10,5=1
P 1.1746 0.54196998 2 P 0 8 0;3=10,5=1
P 1.00413002 4.33598002 2 P 0 8 0;3=10,5=1
P 0.96413002 4.33598002 2 P 0 8 0;3=10,5=1
P 0.92413002 4.33598002 2 P 0 8 0;3=10,5=1
P 0.88413002 4.33598002 2 P 0 8 0;3=10,5=1
P 0.84413002 4.33598002 2 P 0 8 0;3=10,5=1
P 1.025 4.2 3 P 0 8 0;3=2,5=1
P 0.94 4.2 3 P 0 8 0;3=2,5=1
P 0.858 2.87451998 6 P 0 8 0;3=4,5=1
P 0.988 2.724 3 P 0 8 0;3=2,5=1
P 0.987 2.683 6 P 0 8 0;1,3=1,5=1
P 0.856 2.637 2 P 0 8 0;3=10,5=1
P 0.93031998 2.46476998 3 P 0 8 0;3=2,5=1
P 0.872 2.583 3 P 0 8 0;3=2,5=1
P 0.868 2.3 2 P 0 8 0;3=10,5=1
P 1.401 3.956 3 P 0 8 0;3=2,5=1
P 1.435 3.946 30 P 0 8 0;0,3=0,5=0
P 1.40123002 3.91603996 3 P 0 8 0;3=2,5=1
P 1.48 3.7 3 P 0 8 0;3=2,5=1
P 1.38163002 0.21716998 2 P 0 8 0;3=10,5=1
P 1.42163002 0.21716998 2 P 0 8 0;3=10,5=1
P 1.46163002 0.21716998 2 P 0 8 0;3=10,5=1
P 1.50163002 0.21716998 2 P 0 8 0;3=10,5=1
P 1.54163002 0.21716998 2 P 0 8 0;3=10,5=1
P 1.36413002 4.33598002 2 P 0 8 0;3=10,5=1
P 1.32413002 4.33598002 2 P 0 8 0;3=10,5=1
P 1.28413002 4.33598002 2 P 0 8 0;3=10,5=1
P 1.24413002 4.33598002 2 P 0 8 0;3=10,5=1
P 1.20413002 4.33598002 2 P 0 8 0;3=10,5=1
P 1.515 3.7 3 P 0 8 0;3=2,5=1
P 1.385 0.75 2 P 0 8 0;3=10,5=1
P 1.44 0.625 2 P 0 8 0;3=10,5=1
P 1.5184 0.79935 2 P 0 8 0;3=10,5=1
P 1.2146 0.54196998 2 P 0 8 0;3=10,5=1
P 1.2546 0.54196998 2 P 0 8 0;3=10,5=1
P 1.2945 0.53916998 2 P 0 8 0;3=10,5=1
P 1.3292 0.51926004 2 P 0 8 0;3=10,5=1
P 1.34976998 0.48496004 2 P 0 8 0;3=10,5=1
P 1.35298996 0.44508996 2 P 0 8 0;3=10,5=1
P 1.35298996 0.40508996 2 P 0 8 0;3=10,5=1
P 1.35298996 0.36508996 2 P 0 8 0;3=10,5=1
P 1.35298996 0.32508996 2 P 0 8 0;3=10,5=1
P 1.35298996 0.28508996 2 P 0 8 0;3=10,5=1
P 1.35298996 0.24508996 2 P 0 8 0;3=10,5=1
P 1.16413002 4.33598002 2 P 0 8 0;3=10,5=1
P 1.12413002 4.33598002 2 P 0 8 0;3=10,5=1
P 1.08413002 4.33598002 2 P 0 8 0;3=10,5=1
P 1.04413002 4.33598002 2 P 0 8 0;3=10,5=1
P 1.96413002 4.33598002 2 P 0 8 0;3=10,5=1
P 1.92413002 4.33598002 2 P 0 8 0;3=10,5=1
P 1.915 4.13 3 P 0 8 0;3=2,5=1
P 1.873 4.13 33 P 0 8 0;0,3=11,5=0
P 1.88413002 4.33598002 2 P 0 8 0;3=10,5=1
P 1.84413002 4.33598002 2 P 0 8 0;3=10,5=1
P 1.80413002 4.33598002 2 P 0 8 0;3=10,5=1
P 1.76413002 4.33598002 2 P 0 8 0;3=10,5=1
P 1.746 4.061 3 P 0 8 0;3=2,5=1
P 1.746 4.106 6 P 0 8 0;1,3=1,5=1
P 1.751 3.871 3 P 0 8 0;3=2,5=1
P 1.746 4.016 3 P 0 8 0;3=2,5=1
P 1.751 3.826 6 P 0 8 0;1,3=1,5=1
P 1.786 3.746 3 P 0 8 0;3=2,5=1
P 1.786 3.786 3 P 0 8 0;3=2,5=1
P 2.0966 3.315 2 P 0 8 0;3=10,5=1
P 1.72413002 4.33598002 2 P 0 8 0;3=10,5=1
P 1.68413002 4.33598002 2 P 0 8 0;3=10,5=1
P 1.64413002 4.33598002 2 P 0 8 0;3=10,5=1
P 1.60413002 4.33598002 2 P 0 8 0;3=10,5=1
P 1.56413002 4.33598002 2 P 0 8 0;3=10,5=1
P 1.671 4.056 2 P 0 8 0;3=10,5=1
P 1.5086 0.674 6 P 0 8 0;1,3=1,5=1
P 1.59111998 0.45653996 2 P 0 8 0;3=10,5=1
P 1.60736004 0.49308996 2 P 0 8 0;3=10,5=1
P 1.58795 0.29666998 2 P 0 8 0;3=10,5=1
P 1.58795 0.33666998 2 P 0 8 0;3=10,5=1
P 1.58795 0.37666998 2 P 0 8 0;3=10,5=1
P 1.58795 0.41666998 2 P 0 8 0;3=10,5=1
P 1.58163002 0.21716998 2 P 0 8 0;3=10,5=1
P 1.58795 0.25666998 2 P 0 8 0;3=10,5=1
P 1.52413002 4.33598002 2 P 0 8 0;3=10,5=1
P 1.48413002 4.33598002 2 P 0 8 0;3=10,5=1
P 1.44413002 4.33598002 2 P 0 8 0;3=10,5=1
P 1.40413002 4.33598002 2 P 0 8 0;3=10,5=1
P 2.56413002 4.33598002 2 P 0 8 0;3=10,5=1
P 2.52413002 4.33598002 2 P 0 8 0;3=10,5=1
P 2.48413002 4.33598002 2 P 0 8 0;3=10,5=1
P 2.44413002 4.33598002 2 P 0 8 0;3=10,5=1
P 2.40413002 4.33598002 2 P 0 8 0;3=10,5=1
P 2.36413002 4.33598002 2 P 0 8 0;3=10,5=1
P 2.32413002 4.33598002 2 P 0 8 0;3=10,5=1
P 2.28413002 4.33598002 2 P 0 8 0;3=10,5=1
P 2.295 4.15 3 P 0 8 0;3=2,5=1
P 2.285 3.825 6 P 0 8 0;1,3=1,5=1
P 2.24413002 4.33598002 2 P 0 8 0;3=10,5=1
P 2.20413002 4.33598002 2 P 0 8 0;3=10,5=1
P 2.16413002 4.33598002 2 P 0 8 0;3=10,5=1
P 2.12413002 4.33598002 2 P 0 8 0;3=10,5=1
P 2.176 4.151 3 P 0 8 0;3=2,5=1
P 2.256 4.151 3 P 0 8 0;3=2,5=1
P 2.215 4.15 3 P 0 8 0;3=2,5=1
P 2.18 3.811 3 P 0 8 0;3=2,5=1
P 2.218 2.895 2 P 0 8 0;3=10,5=1
P 2.173 2.895 2 P 0 8 0;3=10,5=1
P 2.083 2.895 2 P 0 8 0;3=10,5=1
P 2.128 2.931 27 P 0 8 0;0,3=0,5=0
P 2.083 2.931 27 P 0 8 0;0,3=0,5=0
P 2.173 2.931 27 P 0 8 0;0,3=0,5=0
P 2.08413002 4.33598002 2 P 0 8 0;3=10,5=1
P 2.04413002 4.33598002 2 P 0 8 0;3=10,5=1
P 2.00413002 4.33598002 2 P 0 8 0;3=10,5=1
P 0.22703996 3.79855 4 P 0 8 0;3=29,5=0
P 0.19878002 3.73031004 4 P 0 8 0;3=29,5=0
P 0.22703996 3.66206998 4 P 0 8 0;3=29,5=0
P 0.29528002 3.63381004 4 P 0 8 0;3=29,5=0
P 0.36351998 3.66206998 4 P 0 8 0;3=29,5=0
P 0.39178002 3.73031004 4 P 0 8 0;3=29,5=0
P 0.36351998 3.79855 4 P 0 8 0;3=29,5=0
P 0.29528002 3.82681004 4 P 0 8 0;3=29,5=0
P 6.19961004 2.21273996 2 P 0 8 0;3=10,5=1
P 6.19961004 2.30873996 2 P 0 8 0;3=10,5=1
P 4.3445 1.16598996 2 P 0 8 0;3=10,5=1
P 4.4405 1.16598996 2 P 0 8 0;3=10,5=1
P 3.45301004 1.96298996 2 P 0 8 0;3=10,5=1
P 3.65101004 1.94758996 2 P 0 8 0;3=10,5=1
P 4.44 2.63 3 P 0 8 0;3=2,5=1
P 4.395 2.665 3 P 0 8 0;3=2,5=1
P 4.566 2.845 30 P 0 8 0;0,3=0,5=0
P 4.566 2.895 30 P 0 8 0;0,3=0,5=0
P 4.6 2.895 3 P 0 8 0;3=2,5=1
P 4.6 2.845 3 P 0 8 0;3=2,5=1
P 5.753 1.99 33 P 0 8 0;0,3=11,5=0
P 3.185 3.757 37 P 0 8 0;0,3=11,5=0
P 3.42 3.76 3 P 0 8 0;3=2,5=1
P 3.385 3.76 3 P 0 8 0;3=2,5=1
P 3.315 3.76 3 P 0 8 0;3=2,5=1
P 3.26 3.74 3 P 0 8 0;3=2,5=1
P 6.56038996 1.81205 2 P 0 8 0;3=10,5=1
P 6.56038996 1.77205 2 P 0 8 0;3=10,5=1
P 6.56038996 1.73205 2 P 0 8 0;3=10,5=1
P 6.56038996 1.69205 2 P 0 8 0;3=10,5=1
P 6.56038996 1.65205 2 P 0 8 0;3=10,5=1
P 6.56038996 1.61205 2 P 0 8 0;3=10,5=1
P 6.56038996 1.57205 2 P 0 8 0;3=10,5=1
P 6.56038996 1.53205 2 P 0 8 0;3=10,5=1
P 6.56038996 1.49205 2 P 0 8 0;3=10,5=1
P 6.56038996 1.45205 2 P 0 8 0;3=10,5=1
P 6.56038996 1.05205 2 P 0 8 0;3=10,5=1
P 6.56038996 1.01205 2 P 0 8 0;3=10,5=1
P 6.56038996 0.97205 2 P 0 8 0;3=10,5=1
P 6.56038996 0.93205 2 P 0 8 0;3=10,5=1
P 6.56038996 0.89205 2 P 0 8 0;3=10,5=1
P 6.56038996 0.85205 2 P 0 8 0;3=10,5=1
P 6.56038996 0.81205 2 P 0 8 0;3=10,5=1
P 6.56038996 0.77205 2 P 0 8 0;3=10,5=1
P 6.56038996 0.73205 2 P 0 8 0;3=10,5=1
P 6.56038996 0.69205 2 P 0 8 0;3=10,5=1
P 6.56038996 0.65205 2 P 0 8 0;3=10,5=1
P 6.56038996 0.61205 2 P 0 8 0;3=10,5=1
P 6.56038996 0.57205 2 P 0 8 0;3=10,5=1
P 6.53401998 0.54196998 2 P 0 8 0;3=10,5=1
P 6.49401998 0.54196998 2 P 0 8 0;3=10,5=1
P 6.29401998 0.54196998 2 P 0 8 0;3=10,5=1
P 6.25401998 0.54196998 2 P 0 8 0;3=10,5=1
P 6.21401998 0.54196998 2 P 0 8 0;3=10,5=1
P 6.17401998 0.54196998 2 P 0 8 0;3=10,5=1
P 6.13401998 0.54196998 2 P 0 8 0;3=10,5=1
P 6.09401998 0.54196998 2 P 0 8 0;3=10,5=1
P 6.05401998 0.54196998 2 P 0 8 0;3=10,5=1
P 6.01401998 0.54196998 2 P 0 8 0;3=10,5=1
P 5.97401998 0.54196998 2 P 0 8 0;3=10,5=1
P 5.93401998 0.54196998 2 P 0 8 0;3=10,5=1
P 5.89401998 0.54196998 2 P 0 8 0;3=10,5=1
P 5.85401998 0.54196998 2 P 0 8 0;3=10,5=1
P 5.81401998 0.54196998 2 P 0 8 0;3=10,5=1
P 5.77401998 0.54196998 2 P 0 8 0;3=10,5=1
P 5.73401998 0.54196998 2 P 0 8 0;3=10,5=1
P 5.69401998 0.54196998 2 P 0 8 0;3=10,5=1
P 5.65401998 0.54196998 2 P 0 8 0;3=10,5=1
P 5.61401998 0.54196998 2 P 0 8 0;3=10,5=1
P 5.57401998 0.54196998 2 P 0 8 0;3=10,5=1
P 5.53401998 0.54196998 2 P 0 8 0;3=10,5=1
P 5.49401998 0.54196998 2 P 0 8 0;3=10,5=1
P 5.45401998 0.54196998 2 P 0 8 0;3=10,5=1
P 5.41401998 0.54196998 2 P 0 8 0;3=10,5=1
P 5.37401998 0.54196998 2 P 0 8 0;3=10,5=1
P 5.33401998 0.54196998 2 P 0 8 0;3=10,5=1
P 5.29401998 0.54196998 2 P 0 8 0;3=10,5=1
P 5.25401998 0.54196998 2 P 0 8 0;3=10,5=1
P 5.21401998 0.54196998 2 P 0 8 0;3=10,5=1
P 5.17401998 0.54196998 2 P 0 8 0;3=10,5=1
P 5.13401998 0.54196998 2 P 0 8 0;3=10,5=1
P 5.09401998 0.54196998 2 P 0 8 0;3=10,5=1
P 5.05401998 0.54196998 2 P 0 8 0;3=10,5=1
P 5.01401998 0.54196998 2 P 0 8 0;3=10,5=1
P 4.97401998 0.54196998 2 P 0 8 0;3=10,5=1
P 4.93401998 0.54196998 2 P 0 8 0;3=10,5=1
P 4.89401998 0.54196998 2 P 0 8 0;3=10,5=1
P 4.85401998 0.54196998 2 P 0 8 0;3=10,5=1
P 4.81401998 0.54196998 2 P 0 8 0;3=10,5=1
P 4.77401998 0.54196998 2 P 0 8 0;3=10,5=1
P 4.73401998 0.54196998 2 P 0 8 0;3=10,5=1
P 4.69401998 0.54196998 2 P 0 8 0;3=10,5=1
P 4.65401998 0.54196998 2 P 0 8 0;3=10,5=1
P 4.61401998 0.54196998 2 P 0 8 0;3=10,5=1
P 4.57401998 0.54196998 2 P 0 8 0;3=10,5=1
P 4.53401998 0.54196998 2 P 0 8 0;3=10,5=1
P 4.49401998 0.54196998 2 P 0 8 0;3=10,5=1
P 4.45401998 0.54196998 2 P 0 8 0;3=10,5=1
P 4.41401998 0.54196998 2 P 0 8 0;3=10,5=1
P 4.37401998 0.54196998 2 P 0 8 0;3=10,5=1
P 4.33401998 0.54196998 2 P 0 8 0;3=10,5=1
P 4.29401998 0.54196998 2 P 0 8 0;3=10,5=1
P 4.25401998 0.54196998 2 P 0 8 0;3=10,5=1
P 4.21401998 0.54196998 2 P 0 8 0;3=10,5=1
P 4.17401998 0.54196998 2 P 0 8 0;3=10,5=1
P 2.80413002 4.33598002 2 P 0 8 0;3=10,5=1
P 2.84413002 4.33598002 2 P 0 8 0;3=10,5=1
P 2.88413002 4.33598002 2 P 0 8 0;3=10,5=1
P 2.92413002 4.33598002 2 P 0 8 0;3=10,5=1
P 2.96413002 4.33598002 2 P 0 8 0;3=10,5=1
P 3.00413002 4.33598002 2 P 0 8 0;3=10,5=1
P 3.04413002 4.33598002 2 P 0 8 0;3=10,5=1
P 3.08413002 4.33598002 2 P 0 8 0;3=10,5=1
P 3.12413002 4.33598002 2 P 0 8 0;3=10,5=1
P 3.16413002 4.33598002 2 P 0 8 0;3=10,5=1
P 3.20413002 4.33598002 2 P 0 8 0;3=10,5=1
P 3.24413002 4.33598002 2 P 0 8 0;3=10,5=1
P 3.28413002 4.33598002 2 P 0 8 0;3=10,5=1
P 3.32413002 4.33598002 2 P 0 8 0;3=10,5=1
P 3.36413002 4.33598002 2 P 0 8 0;3=10,5=1
P 3.40413002 4.33598002 2 P 0 8 0;3=10,5=1
P 3.44413002 4.33598002 2 P 0 8 0;3=10,5=1
P 3.48413002 4.33598002 2 P 0 8 0;3=10,5=1
P 3.52413002 4.33598002 2 P 0 8 0;3=10,5=1
P 3.56413002 4.33598002 2 P 0 8 0;3=10,5=1
P 3.60413002 4.33598002 2 P 0 8 0;3=10,5=1
P 3.64413002 4.33598002 2 P 0 8 0;3=10,5=1
P 3.68413002 4.33598002 2 P 0 8 0;3=10,5=1
P 3.72413002 4.33598002 2 P 0 8 0;3=10,5=1
P 3.76413002 4.33598002 2 P 0 8 0;3=10,5=1
P 3.80413002 4.33598002 2 P 0 8 0;3=10,5=1
P 3.84413002 4.33598002 2 P 0 8 0;3=10,5=1
P 3.88413002 4.33598002 2 P 0 8 0;3=10,5=1
P 3.92413002 4.33598002 2 P 0 8 0;3=10,5=1
P 3.96413002 4.33598002 2 P 0 8 0;3=10,5=1
P 4.00413002 4.33598002 2 P 0 8 0;3=10,5=1
P 4.04413002 4.33598002 2 P 0 8 0;3=10,5=1
P 4.08413002 4.33598002 2 P 0 8 0;3=10,5=1
P 4.12413002 4.33598002 2 P 0 8 0;3=10,5=1
P 4.16413002 4.33598002 2 P 0 8 0;3=10,5=1
P 4.20413002 4.33598002 2 P 0 8 0;3=10,5=1
P 4.24413002 4.33598002 2 P 0 8 0;3=10,5=1
P 4.28413002 4.33598002 2 P 0 8 0;3=10,5=1
P 4.32413002 4.33598002 2 P 0 8 0;3=10,5=1
P 4.36413002 4.33598002 2 P 0 8 0;3=10,5=1
P 4.40413002 4.33598002 2 P 0 8 0;3=10,5=1
P 4.44413002 4.33598002 2 P 0 8 0;3=10,5=1
P 4.48413002 4.33598002 2 P 0 8 0;3=10,5=1
P 4.52413002 4.33598002 2 P 0 8 0;3=10,5=1
P 4.56413002 4.33598002 2 P 0 8 0;3=10,5=1
P 4.60413002 4.33598002 2 P 0 8 0;3=10,5=1
P 4.64413002 4.33598002 2 P 0 8 0;3=10,5=1
P 4.68413002 4.33598002 2 P 0 8 0;3=10,5=1
P 4.72413002 4.33598002 2 P 0 8 0;3=10,5=1
P 4.76413002 4.33598002 2 P 0 8 0;3=10,5=1
P 4.80413002 4.33598002 2 P 0 8 0;3=10,5=1
P 4.84413002 4.33598002 2 P 0 8 0;3=10,5=1
P 4.88413002 4.33598002 2 P 0 8 0;3=10,5=1
P 4.92413002 4.33598002 2 P 0 8 0;3=10,5=1
P 4.96413002 4.33598002 2 P 0 8 0;3=10,5=1
P 5.00413002 4.33598002 2 P 0 8 0;3=10,5=1
P 5.04413002 4.33598002 2 P 0 8 0;3=10,5=1
P 5.08413002 4.33598002 2 P 0 8 0;3=10,5=1
P 5.12413002 4.33598002 2 P 0 8 0;3=10,5=1
P 5.16413002 4.33598002 2 P 0 8 0;3=10,5=1
P 5.20413002 4.33598002 2 P 0 8 0;3=10,5=1
P 5.24413002 4.33598002 2 P 0 8 0;3=10,5=1
P 5.28413002 4.33598002 2 P 0 8 0;3=10,5=1
P 5.32413002 4.33598002 2 P 0 8 0;3=10,5=1
P 5.36413002 4.33598002 2 P 0 8 0;3=10,5=1
P 5.40413002 4.33598002 2 P 0 8 0;3=10,5=1
P 5.44413002 4.33598002 2 P 0 8 0;3=10,5=1
P 5.48413002 4.33598002 2 P 0 8 0;3=10,5=1
P 5.52413002 4.33598002 2 P 0 8 0;3=10,5=1
P 5.56413002 4.33598002 2 P 0 8 0;3=10,5=1
P 5.60413002 4.33598002 2 P 0 8 0;3=10,5=1
P 5.64413002 4.33598002 2 P 0 8 0;3=10,5=1
P 5.68413002 4.33598002 2 P 0 8 0;3=10,5=1
P 5.72413002 4.33598002 2 P 0 8 0;3=10,5=1
P 5.76413002 4.33598002 2 P 0 8 0;3=10,5=1
P 5.80413002 4.33598002 2 P 0 8 0;3=10,5=1
P 5.84413002 4.33598002 2 P 0 8 0;3=10,5=1
P 5.88413002 4.33598002 2 P 0 8 0;3=10,5=1
P 5.92413002 4.33598002 2 P 0 8 0;3=10,5=1
P 5.96413002 4.33598002 2 P 0 8 0;3=10,5=1
P 6.00413002 4.33598002 2 P 0 8 0;3=10,5=1
P 6.04413002 4.33598002 2 P 0 8 0;3=10,5=1
P 6.08413002 4.33598002 2 P 0 8 0;3=10,5=1
P 6.12413002 4.33598002 2 P 0 8 0;3=10,5=1
P 6.16413002 4.33598002 2 P 0 8 0;3=10,5=1
P 6.20413002 4.33598002 2 P 0 8 0;3=10,5=1
P 6.24413002 4.33598002 2 P 0 8 0;3=10,5=1
P 6.28413002 4.33598002 2 P 0 8 0;3=10,5=1
P 6.32413002 4.33598002 2 P 0 8 0;3=10,5=1
P 6.36413002 4.33598002 2 P 0 8 0;3=10,5=1
P 6.40413002 4.33598002 2 P 0 8 0;3=10,5=1
P 6.44413002 4.33598002 2 P 0 8 0;3=10,5=1
P 6.48413002 4.33598002 2 P 0 8 0;3=10,5=1
P 6.52413002 4.33598002 2 P 0 8 0;3=10,5=1
P 6.56038996 4.31908996 2 P 0 8 0;3=10,5=1
P 6.56038996 4.27908996 2 P 0 8 0;3=10,5=1
P 6.56038996 4.23908996 2 P 0 8 0;3=10,5=1
P 6.56038996 4.19908996 2 P 0 8 0;3=10,5=1
P 6.56038996 4.15908996 2 P 0 8 0;3=10,5=1
P 6.56038996 4.11908996 2 P 0 8 0;3=10,5=1
P 6.56038996 4.07908996 2 P 0 8 0;3=10,5=1
P 6.56038996 4.03908996 2 P 0 8 0;3=10,5=1
P 6.56038996 3.99908996 2 P 0 8 0;3=10,5=1
P 6.56038996 3.95908996 2 P 0 8 0;3=10,5=1
P 6.56038996 3.91908996 2 P 0 8 0;3=10,5=1
P 6.56038996 3.87908996 2 P 0 8 0;3=10,5=1
P 6.56038996 3.83908996 2 P 0 8 0;3=10,5=1
P 6.56038996 3.79908996 2 P 0 8 0;3=10,5=1
P 6.56038996 3.75908996 2 P 0 8 0;3=10,5=1
P 6.56038996 3.71908996 2 P 0 8 0;3=10,5=1
P 6.56038996 3.67908996 2 P 0 8 0;3=10,5=1
P 6.56038996 3.63908996 2 P 0 8 0;3=10,5=1
P 6.56038996 3.59908996 2 P 0 8 0;3=10,5=1
P 6.56038996 3.55908996 2 P 0 8 0;3=10,5=1
P 6.56038996 3.51908996 2 P 0 8 0;3=10,5=1
P 6.56038996 3.47908996 2 P 0 8 0;3=10,5=1
P 6.56038996 3.43908996 2 P 0 8 0;3=10,5=1
P 6.56038996 3.39908996 2 P 0 8 0;3=10,5=1
P 6.56038996 3.35908996 2 P 0 8 0;3=10,5=1
P 6.56038996 3.31908996 2 P 0 8 0;3=10,5=1
P 6.56038996 3.27908996 2 P 0 8 0;3=10,5=1
P 6.56038996 3.23908996 2 P 0 8 0;3=10,5=1
P 6.56038996 3.19908996 2 P 0 8 0;3=10,5=1
P 6.56038996 3.15908996 2 P 0 8 0;3=10,5=1
P 6.56038996 3.11908996 2 P 0 8 0;3=10,5=1
P 6.56038996 2.35585 2 P 0 8 0;3=10,5=1
P 5.772 0.658 27 P 0 8 0;0,3=0,5=0
P 5.119 2.762 3 P 0 8 0;3=2,5=1
P 5.63341004 0.62101998 3 P 0 8 0;3=2,5=1
P 5.59941004 0.6212 3 P 0 8 0;3=2,5=1
P 2.419 2.388 3 P 0 8 0;3=2,5=1
P 2.419 2.355 30 P 0 8 0;0,3=0,5=0
P 2.79 2.206 27 P 0 8 0;0,3=0,5=0
P 2.79 2.296 27 P 0 8 0;0,3=0,5=0
P 2.805 2.243 3 P 0 8 0;3=2,5=1
P 2.7526 2.23 3 P 0 8 0;3=2,5=1
P 4.55511004 1.755 30 P 0 8 0;0,3=0,5=0
P 4.52153996 1.84343996 5 P 0 8 0;0,3=18,5=0
P 4.278 1.003 3 P 0 8 0;3=2,5=1
P 4.32 0.961 27 P 0 8 0;0,3=0,5=0
P 4.275 0.961 27 P 0 8 0;0,3=0,5=0
P 3.041 2.05 30 P 0 8 0;0,3=0,5=0
P 3.041 2.005 30 P 0 8 0;0,3=0,5=0
P 3.08966998 2.04 3 P 0 8 0;3=2,5=1
P 3.068 1.945 33 P 0 8 0;0,3=11,5=0
P 2.41441004 2.15 3 P 0 8 0;3=2,5=1
P 2.41441004 2.193 23 P 0 8 0;0,3=21,5=0
P 2.69 2.15 3 P 0 8 0;3=2,5=1
P 5.83 1.92 3 P 0 8 0;3=2,5=1
P 5.805 1.945 3 P 0 8 0;3=2,5=1
P 5.035 3.854 27 P 0 8 0;0,3=0,5=0
P 5.085 3.854 27 P 0 8 0;0,3=0,5=0
P 5.045 3.76 3 P 0 8 0;3=2,5=1
P 5.05 3.795 3 P 0 8 0;3=2,5=1
P 4.54 3.97 3 P 0 8 0;3=2,5=1
P 4.54 3.935 3 P 0 8 0;3=2,5=1
P 4.614 3.94 30 P 0 8 0;0,3=0,5=0
P 4.614 3.895 30 P 0 8 0;0,3=0,5=0
P 4.62 2.461 27 P 0 8 0;0,3=0,5=0
P 4.62 2.5 3 P 0 8 0;3=2,5=1
P 3.305 2.915 3 P 0 8 0;3=2,5=1
P 3.145 2.765 3 P 0 8 0;3=2,5=1
P 6.105 2.27 3 P 0 8 0;3=2,5=1
P 6.141 2.241 3 P 0 8 0;3=2,5=1
P 2.54 2.174 27 P 0 8 0;0,3=0,5=0
P 2.54 2.135 3 P 0 8 0;3=2,5=1
P 2.59 2.264 27 P 0 8 0;0,3=0,5=0
P 2.59 2.23 3 P 0 8 0;3=2,5=1
P 5.825 0.796 27 P 0 8 0;0,3=0,5=0
P 5.859 0.796 3 P 0 8 0;3=2,5=1
P 5.80643002 0.609 3 P 0 8 0;3=2,5=1
P 5.805 0.658 3 P 0 8 0;3=2,5=1
P 5.404 0.69 30 P 0 8 0;0,3=0,5=0
P 5.37 0.69 3 P 0 8 0;3=2,5=1
P 5.43956998 0.60543002 3 P 0 8 0;3=2,5=1
P 6.335 1.96873996 3 P 0 8 0;3=2,5=1
P 5.59 0.888 3 P 0 8 0;3=2,5=1
P 4.933 1.263 33 P 0 8 0;0,3=11,5=0
P 4.933 1.215 3 P 0 8 0;3=2,5=1
P 4.894 1.263 3 P 0 8 0;3=2,5=1
P 4.79866998 1.38866998 3 P 0 8 0;3=2,5=1
P 5.0395 1.43 3 P 0 8 0;3=2,5=1
P 4.485 2.461 27 P 0 8 0;0,3=0,5=0
P 4.44 2.5 3 P 0 8 0;3=2,5=1
P 4.965 1.925 3 P 0 8 0;3=2,5=1
P 4.96 2.055 3 P 0 8 0;3=2,5=1
P 5.346 1.52 3 P 0 8 0;3=2,5=1
P 5.346 1.483 3 P 0 8 0;3=2,5=1
P 4.926 1.675 30 P 0 8 0;0,3=0,5=0
P 4.96 1.675 3 P 0 8 0;3=2,5=1
P 4.024 2.215 30 P 0 8 0;0,3=0,5=0
P 3.99 2.25 3 P 0 8 0;3=2,5=1
P 3.9825 2.325 36 P 0 8 0;0,3=20,5=0
P 3.99 2.21406998 3 P 0 8 0;3=2,5=1
P 3.7206 2.13 3 P 0 8 0;3=2,5=1
P 3.6956 2.13 3 P 0 8 0;3=2,5=1
P 3.678 2.23 33 P 0 8 0;0,3=11,5=0
P 4.78 1.98 3 P 0 8 0;3=2,5=1
P 4.75776998 2.00091004 5 P 0 8 0;0,3=18,5=0
P 5.557 0.747 27 P 0 8 0;0,3=0,5=0
P 5.6065 0.7045 3 P 0 8 0;3=28,5=1
P 5.602 0.815 3 P 0 8 0;3=2,5=1
P 5.59 0.85 3 P 0 8 0;3=2,5=1
P 5.625 0.746 3 P 0 8 0;3=2,5=1
P 4.22 0.775 3 P 0 8 0;3=2,5=1
P 4.345 0.77 3 P 0 8 0;3=2,5=1
P 4.4843 0.8954 3 P 0 8 0;3=2,5=1
P 4.442 1.005 3 P 0 8 0;3=2,5=1
P 4.31 1.165 3 P 0 8 0;3=2,5=1
P 4.414 0.781 6 P 0 8 0;1,3=1,5=1
P 4.335 1.005 3 P 0 8 0;3=2,5=1
P 4.23 1.005 3 P 0 8 0;3=2,5=1
P 3.12 2.955 3 P 0 8 0;3=2,5=1
P 2.995 2.955 3 P 0 8 0;3=2,5=1
P 2.92 2.9472 3 P 0 8 0;3=2,5=1
P 2.88 2.93 3 P 0 8 0;3=2,5=1
P 2.96 2.913 37 P 0 8 0;0,3=11,5=0
P 3.035 2.913 37 P 0 8 0;0,3=11,5=0
P 3.11 2.913 37 P 0 8 0;0,3=11,5=0
P 2.855 2.886 27 P 0 8 0;0,3=0,5=0
P 2.9 2.886 27 P 0 8 0;0,3=0,5=0
P 3.01 3.12 3 P 0 8 0;3=2,5=1
P 3.662 2.952 37 P 0 8 0;0,3=11,5=0
P 5.121 2.447 3 P 0 8 0;3=2,5=1
P 5.121 2.407 3 P 0 8 0;3=2,5=1
P 5.298 2.23 3 P 0 8 0;3=2,5=1
P 5.332 2.2 6 P 0 8 0;1,3=1,5=1
P 5.369 2.015 3 P 0 8 0;3=2,5=1
P 5.435 2.05 3 P 0 8 0;3=2,5=1
P 5.409 2.015 3 P 0 8 0;3=2,5=1
P 5.071 2.407 3 P 0 8 0;3=2,5=1
P 4.815 1.82016004 3 P 0 8 0;3=2,5=1
P 4.78 1.82111004 27 P 0 8 0;0,3=0,5=0
P 4.44 2.26 3 P 0 8 0;3=2,5=1
P 4.40343002 2.19776998 5 P 0 8 0;0,3=18,5=0
P 4.45485 2.22 30 P 0 8 0;0,3=0,5=0
P 3.67 2.41243002 3 P 0 8 0;3=2,5=1
P 3.67 2.32 6 P 0 8 0;1,3=1,5=1
P 3.54975 2.479 3 P 0 8 0;3=2,5=1
P 3.605 2.43 3 P 0 8 0;3=2,5=1
P 3.55 2.425 3 P 0 8 0;3=2,5=1
P 3.415 2.335 3 P 0 8 0;3=2,5=1
P 3.505 2.295 3 P 0 8 0;3=2,5=1
P 3.40953002 2.37 3 P 0 8 0;3=2,5=1
P 3.116 2.524 3 P 0 8 0;3=2,5=1
P 3.12 2.344 3 P 0 8 0;3=2,5=1
P 3.12 2.17 6 P 0 8 0;1,3=1,5=1
P 3.512 1.966 3 P 0 8 0;3=2,5=1
P 4.24595 2.1584 5 P 0 8 0;0,3=18,5=0
P 4.67903002 1.80406004 5 P 0 8 0;0,3=18,5=0
P 4.67901998 2.1584 5 P 0 8 0;0,3=18,5=0
P 3.8916 2.15838996 5 P 0 8 0;0,3=18,5=0
P 3.93098002 2.07963996 5 P 0 8 0;0,3=18,5=0
P 3.97035 1.92216998 5 P 0 8 0;0,3=18,5=0
P 4.20658002 1.48908996 5 P 0 8 0;0,3=18,5=0
P 4.20658002 1.44973002 5 P 0 8 0;0,3=18,5=0
P 4.12783002 1.4891 5 P 0 8 0;0,3=18,5=0
P 4.24596004 1.56783996 5 P 0 8 0;0,3=18,5=0
P 4.16721004 1.56783002 5 P 0 8 0;0,3=18,5=0
P 4.309 1.48468996 5 P 0 8 0;0,3=18,5=0
P 4.12783002 1.52846998 5 P 0 8 0;0,3=18,5=0
P 4.16721998 2.04028002 5 P 0 8 0;0,3=18,5=0
P 4.31006004 1.93718002 5 P 0 8 0;0,3=18,5=0
P 4.3 2.029 27 P 0 8 0;0,3=0,5=0
P 4.16721004 2.00091998 5 P 0 8 0;0,3=18,5=0
P 4.0491 1.96155 5 P 0 8 0;0,3=18,5=0
P 4.08846004 1.96153996 5 P 0 8 0;0,3=18,5=0
P 4.20658002 1.88281004 5 P 0 8 0;0,3=18,5=0
P 4.199 1.75 30 P 0 8 0;0,3=0,5=0
P 4.306 1.795 27 P 0 8 0;0,3=0,5=0
P 4.323 1.741 30 P 0 8 0;0,3=0,5=0
P 4.098 1.75 30 P 0 8 0;0,3=0,5=0
P 4.20656998 1.80406004 5 P 0 8 0;0,3=18,5=0
P 4.20656998 1.68595 5 P 0 8 0;0,3=18,5=0
P 4.16721004 1.68596004 5 P 0 8 0;0,3=18,5=0
P 4.20658002 1.6072 5 P 0 8 0;0,3=18,5=0
P 4.305 1.591 27 P 0 8 0;0,3=0,5=0
P 4.305 1.649 27 P 0 8 0;0,3=0,5=0
P 4.24595 1.64658996 5 P 0 8 0;0,3=18,5=0
P 4.52153996 1.64656998 5 P 0 8 0;0,3=18,5=0
P 4.60026998 1.68595 5 P 0 8 0;0,3=18,5=0
P 4.63963996 1.56783996 5 P 0 8 0;0,3=18,5=0
P 4.60028002 1.56785 5 P 0 8 0;0,3=18,5=0
P 4.48218002 1.64658002 5 P 0 8 0;0,3=18,5=0
P 4.48218002 1.68595 5 P 0 8 0;0,3=18,5=0
P 4.46511004 1.755 30 P 0 8 0;0,3=0,5=0
P 4.63965 1.88281004 5 P 0 8 0;0,3=18,5=0
P 4.4428 1.60721998 5 P 0 8 0;0,3=18,5=0
P 4.40343002 1.64656998 5 P 0 8 0;0,3=18,5=0
P 4.36406004 1.64658996 5 P 0 8 0;0,3=18,5=0
P 4.48216998 1.56783002 5 P 0 8 0;0,3=18,5=0
P 4.52153996 1.41035 5 P 0 8 0;0,3=18,5=0
P 4.5609 1.41035 5 P 0 8 0;0,3=18,5=0
P 4.40343002 1.56783002 5 P 0 8 0;0,3=18,5=0
P 4.40343002 1.37098996 5 P 0 8 0;0,3=18,5=0
P 4.4428 1.41035 5 P 0 8 0;0,3=18,5=0
P 4.36406004 1.52846004 5 P 0 8 0;0,3=18,5=0
P 4.36406004 1.48911004 5 P 0 8 0;0,3=18,5=0
P 4.40341998 1.92216998 5 P 0 8 0;0,3=18,5=0
P 4.48216004 2.07965 5 P 0 8 0;0,3=18,5=0
P 4.395 3.37891998 2 P 0 8 0;3=10,5=1
P 4.44 4.165 2 P 0 8 0;3=10,5=1
P 2.86151004 3.295 2 P 0 8 0;3=10,5=1
P 3.21898996 3.43 3 P 0 8 0;3=2,5=1
P 3.256 3.43 30 P 0 8 0;0,3=0,5=0
P 4.134 2.936 33 P 0 8 0;0,3=11,5=0
P 4.134 2.855 33 P 0 8 0;0,3=11,5=0
P 3.548 2.898 2 P 0 8 0;3=10,5=1
P 3.621 2.91 3 P 0 8 0;3=2,5=1
P 3.658 2.861 3 P 0 8 0;3=2,5=1
P 3.658 2.911 3 P 0 8 0;3=2,5=1
P 3.623 2.861 3 P 0 8 0;3=2,5=1
P 3.615 2.961 3 P 0 8 0;3=2,5=1
P 3.253 3.917 3 P 0 8 0;3=2,5=1
P 3.253 3.962 3 P 0 8 0;3=2,5=1
P 3.248 4.107 3 P 0 8 0;3=2,5=1
P 3.213 4.167 3 P 0 8 0;3=2,5=1
P 3.248 4.152 3 P 0 8 0;3=2,5=1
P 3.213 4.236 6 P 0 8 0;1,3=1,5=1
P 3.253 3.872 3 P 0 8 0;3=2,5=1
P 4.465 2.895 2 P 0 8 0;3=10,5=1
P 4.093 2.863 3 P 0 8 0;3=2,5=1
P 4.091 2.813 3 P 0 8 0;3=2,5=1
P 4.092 2.917 3 P 0 8 0;3=2,5=1
P 3.78 2.735 3 P 0 8 0;3=2,5=1
P 3.435 2.589 3 P 0 8 0;3=2,5=1
P 3.5485 2.761 2 P 0 8 0;3=10,5=1
P 3.285 2.589 6 P 0 8 0;1,3=1,5=1
P 4.775 2.59 3 P 0 8 0;3=2,5=1
P 4.71 2.592 6 P 0 8 0;1,3=1,5=1
P 4.918 2.777 3 P 0 8 0;3=2,5=1
P 4.925 2.722 3 P 0 8 0;3=2,5=1
P 4.961 2.728 27 P 0 8 0;0,3=0,5=0
P 3.106 3.305 2 P 0 8 0;3=10,5=1
P 3.068 3.305 30 P 0 8 0;0,3=0,5=0
P 3.222 3.25 2 P 0 8 0;3=10,5=1
P 3.975 3.129 3 P 0 8 0;3=2,5=1
P 3.998 2.784 3 P 0 8 0;3=2,5=1
P 3.83 2.932 3 P 0 8 0;3=2,5=1
P 3.78 2.932 3 P 0 8 0;3=2,5=1
P 3.703 2.911 3 P 0 8 0;3=2,5=1
P 3.748 2.911 3 P 0 8 0;3=2,5=1
P 3.933 3.125 3 P 0 8 0;3=2,5=1
P 3.933 3.092 30 P 0 8 0;0,3=0,5=0
P 3.6 4.024 3 P 0 8 0;3=2,5=1
P 3.564 4.032 30 P 0 8 0;0,3=0,5=0
P 3.631 4.228 3 P 0 8 0;3=2,5=1
P 3.60311004 4.0988 3 P 0 8 0;3=2,5=1
P 3.631 4.183 3 P 0 8 0;3=2,5=1
P 3.38 3.15 3 P 0 8 0;3=2,5=1
P 4.43 3.965 2 P 0 8 0;3=10,5=1
P 4.396 3.965 30 P 0 8 0;0,3=0,5=0
P 4.43 4.015 2 P 0 8 0;3=10,5=1
P 4.714 3.633 3 P 0 8 0;3=2,5=1
P 4.71 3.47 3 P 0 8 0;3=2,5=1
P 4.94093996 4.12008002 17 P 0 8 0;3=31,5=0
P 4.94093996 3.09646004 17 P 0 8 0;3=31,5=0
P 3.8865 2.9265 3 P 0 8 0;3=28,5=1
P 2.55906004 4.12008002 17 P 0 8 0;3=31,5=0
P 2.55906004 3.09646004 17 P 0 8 0;3=31,5=0
P 5.815 2.67 3 P 0 8 0;3=2,5=1
P 5.7425 2.6375 35 P 0 8 0;0,3=32,5=0
P 5.517 2.563 3 P 0 8 0;3=2,5=1
P 5.49 2.675 3 P 0 8 0;3=2,5=1
P 5.3035 2.5748 3 P 0 8 0;3=2,5=1
P 5.278 2.611 27 P 0 8 0;0,3=0,5=0
P 5.122 2.587 3 P 0 8 0;3=2,5=1
P 5.123 2.544 3 P 0 8 0;3=2,5=1
P 5.121 2.495 3 P 0 8 0;3=2,5=1
P 5.121 2.625 3 P 0 8 0;3=2,5=1
P 5.41346004 3.03506998 3 P 0 8 0;3=2,5=1
P 5.814 2.9225 3 P 0 8 0;3=2,5=1
P 5.7375 2.9225 35 P 0 8 0;0,3=32,5=0
P 5.25176004 4.11925 3 P 0 8 0;3=2,5=1
P 5.88778996 3.34448996 12 P 0 8 0;3=24,5=0
P 5.88778996 3.50983996 12 P 0 8 0;3=24,5=0
P 5.88778996 3.67518996 12 P 0 8 0;3=24,5=0
P 5.08 2.454 33 P 0 8 0;0,3=11,5=0
P 5.538 2.402 3 P 0 8 0;3=2,5=1
P 5.555 2.366 27 P 0 8 0;0,3=0,5=0
P 5.666 2.129 2 P 0 8 0;3=10,5=1
P 5.647 2.044 3 P 0 8 0;3=2,5=1
P 5.687 2.043 3 P 0 8 0;3=2,5=1
P 5.732 2.043 3 P 0 8 0;3=2,5=1
P 5.865 2.3 3 P 0 8 0;3=2,5=1
P 6.36 2.16141998 3 P 0 8 0;3=2,5=1
P 6.51581998 2.24803996 20 P 0 8 0;3=33,5=0
P 6.51581998 1.97243996 20 P 0 8 0;3=34,5=0
P 6.40951998 2.20866998 8 P 0 8 0;3=35,5=0
P 6.40951998 2.01181004 8 P 0 8 0;3=35,5=0
P 0.06038996 1.38346004 10 P 0 8 0;3=36,5=0
P 0.26038996 1.38346004 10 P 0 8 0;3=36,5=0
P 0.06038996 1.18346004 10 P 0 8 0;3=36,5=0
P 0.26038996 1.18346004 10 P 0 8 0;3=36,5=0
P 0.06038996 0.8126 10 P 0 8 0;3=36,5=0
P 0.26038996 0.8126 10 P 0 8 0;3=36,5=0
P 0.06038996 0.6126 10 P 0 8 0;3=36,5=0
P 0.26038996 0.6126 10 P 0 8 0;3=36,5=0
P 0.06038996 2.5252 10 P 0 8 0;3=36,5=0
P 0.26038996 2.5252 10 P 0 8 0;3=36,5=0
P 0.06038996 2.3252 10 P 0 8 0;3=36,5=0
P 0.26038996 2.3252 10 P 0 8 0;3=36,5=0
P 0.06038996 1.95433002 10 P 0 8 0;3=36,5=0
P 0.26038996 1.95433002 10 P 0 8 0;3=36,5=0
P 0.06038996 1.75433002 10 P 0 8 0;3=36,5=0
P 0.26038996 1.75433002 10 P 0 8 0;3=36,5=0
P 1.26066998 1.84043002 11 P 0 8 0;3=26,5=0
P 5.4525 2.6795 27 P 0 8 0;0,3=0,5=0
P 3.256 3.295 30 P 0 8 0;0,3=0,5=0
P 3.256 3.25 30 P 0 8 0;0,3=0,5=0
P 4.63966004 1.96153996 5 P 0 8 0;0,3=18,5=0
P 4.63966004 1.92216998 5 P 0 8 0;0,3=18,5=0
P 3.93098002 2.00091004 5 P 0 8 0;0,3=18,5=0
P 3.93096998 2.04028002 5 P 0 8 0;0,3=18,5=0
P 4.44 2.461 27 P 0 8 0;0,3=0,5=0
P 4.76666004 1.38866998 5 P 0 8 0;0,3=18,5=0
P 2.69 2.1935 25 P 0 8 0;0,3=19,5=0
P 3.245 2.859 27 P 0 8 0;0,3=0,5=0
P 6.421 1.08 30 P 0 8 0;0,3=0,5=0
P 6.421 0.965 30 P 0 8 0;0,3=0,5=0
P 6.421 1.02 30 P 0 8 0;0,3=0,5=0
P 0.889 0.71 30 P 0 8 0;0,3=0,5=0
P 1.038 0.718 30 P 0 8 0;0,3=0,5=0
P 1.7485 3.388 40 P 0 8 0;0,3=8,5=0
P 5.96901998 1.90865 27 P 0 8 0;0,3=0,5=0
P 5.762 3.907 30 P 0 8 0;0,3=0,5=0
P 5.762 3.857 30 P 0 8 0;0,3=0,5=0
P 5.91901998 2.003 6 P 0 8 0;1,3=9,5=1
P 6.06901998 2.004 6 P 0 8 0;1,3=9,5=1
P 3.49 0.825 6 P 0 8 0;1,3=9,5=1
P 2.65966998 0.93443002 11 P 0 8 0;3=26,5=0
P 6.036 2.79 30 P 0 8 0;0,3=0,5=0
P 6.095 2.545 6 P 0 8 0;1,3=1,5=1
P 5.07 1.885 3 P 0 8 0;3=2,5=1
P 5.33 0.995 2 P 0 8 0;3=10,5=1
P 3.54 0.825 3 P 0 8 0;3=2,5=1
P 6.04 2.545 6 P 0 8 0;1,3=1,5=1
P 6.036 2.615 30 P 0 8 0;0,3=0,5=0
P 5.07 1.925 3 P 0 8 0;3=2,5=1
P 4.926 2.025 30 P 0 8 0;0,3=0,5=0
P 5.33 0.95 2 P 0 8 0;3=10,5=1
P 2.53966998 0.93443002 11 P 0 8 0;3=26,5=0
P 2.7965 1.945 30 P 0 8 0;0,3=0,5=0
P 2.802 1.987 2 P 0 8 0;3=10,5=1
P 2.8385 1.945 30 P 0 8 0;0,3=0,5=0
P 2.834 1.987 2 P 0 8 0;3=10,5=1
P 2.795 1.88 27 P 0 8 0;0,3=0,5=0
P 2.845 1.875 2 P 0 8 0;3=10,5=1
P 2.795 1.838 27 P 0 8 0;0,3=0,5=0
P 2.845 1.843 2 P 0 8 0;3=10,5=1
P 2.77866998 0.93443002 11 P 0 8 0;3=26,5=0
P 4.97 1.54 6 P 0 8 0;1,3=3,5=0
P 4.926 1.855 30 P 0 8 0;0,3=0,5=0
P 4.9806 1.855 6 P 0 8 0;1,3=1,5=1
P 1.26066998 1.04043002 11 P 0 8 0;3=26,5=0
P 0.724 2.646 6 P 0 8 0;1,3=1,5=1
P 0.758 2.743 6 P 0 8 0;1,3=4,5=1
P 3.235 2.63 6 P 0 8 0;3=3,5=0
P 3.275 2.32 6 P 0 8 0;1,3=4,5=1
P 3.24 2.275 6 P 0 8 0;1,3=1,5=1
P 3.305 2.65 6 P 0 8 0;1,3=3,5=0
P 3.375 2.65 6 P 0 8 0;3=3,5=0
P 3.326 2.466 6 P 0 8 0;1,3=4,5=1
P 3.335 2.511 27 P 0 8 0;0,3=0,5=0
P 2.1481 0.7881 6 P 0 8 0;1,3=9,5=1
P 5.08 1.105 3 P 0 8 0;3=2,5=1
P 5.454 2.87 30 P 0 8 0;0,3=0,5=0
P 2.08295 0.525 6 P 0 8 0;1,3=13,5=1
P 2.07283002 0.13781004 29 P 0 8 0;0,3=27,5=0
P 5.225 1.145 3 P 0 8 0;3=2,5=1
P 5.546 2.815 30 P 0 8 0;0,3=0,5=0
P 5.132 0.66 3 P 0 8 0;3=2,5=1
P 2.0816 0.7399 3 P 0 8 0;3=2,5=1
P 2.03346004 0.13781004 29 P 0 8 0;0,3=27,5=0
P 2.0137 0.43 6 P 0 8 0;1,3=13,5=1
P 1.98 0.495 6 P 0 8 0;1,3=13,5=1
P 1.99408996 0.13781004 29 P 0 8 0;0,3=27,5=0
P 2.03 0.75 6 P 0 8 0;1,3=9,5=1
P 5.08 1.155 3 P 0 8 0;3=2,5=1
P 5.546 3.065 30 P 0 8 0;0,3=0,5=0
P 5.08 1.055 3 P 0 8 0;3=2,5=1
P 5.546 2.595 30 P 0 8 0;0,3=0,5=0
P 2.0788 0.7874 6 P 0 8 0;1,3=9,5=1
P 1.924 0.45786004 6 P 0 8 0;1,3=13,5=1
P 1.95471998 0.13781004 29 P 0 8 0;0,3=27,5=0
P 2.19093996 0.13781004 29 P 0 8 0;0,3=27,5=0
P 2.29581998 0.48918002 6 P 0 8 0;1,3=3,5=0
P 2.633 0.522 2 P 0 8 0;3=10,5=1
P 3.455 0.87 3 P 0 8 0;3=2,5=1
P 0.9225 0.9775 3 P 0 8 0;3=2,5=1
P 4.82 0.835 6 P 0 8 0;1,3=1,5=1
P 0.676 1.599 30 P 0 8 0;0,3=0,5=0
P 0.8825 1.7725 3 P 0 8 0;3=2,5=1
P 3.405 0.87 3 P 0 8 0;3=2,5=1
P 0.965 0.98 3 P 0 8 0;3=2,5=1
P 0.91 1.815 6 P 0 8 0;1,3=1,5=1
P 0.675 1.544 30 P 0 8 0;0,3=0,5=0
P 4.78 0.78 3 P 0 8 0;3=2,5=1
P 4.4428 1.84343002 5 P 0 8 0;0,3=18,5=0
P 3.575 1.88648996 30 P 0 8 0;0,3=0,5=0
P 3.65101004 1.88358996 2 P 0 8 0;3=12,5=1
P 4.48216998 1.84343002 5 P 0 8 0;0,3=18,5=0
P 3.575 1.93148996 30 P 0 8 0;0,3=0,5=0
P 3.65101004 1.91558996 2 P 0 8 0;3=12,5=1
P 3.065 1.695 6 P 0 8 0;1,3=3,5=0
P 2.98283996 1.75183996 3 P 0 8 0;3=2,5=1
P 2.225 3.245 3 P 0 8 0;3=2,5=1
P 4.595 2.62 3 P 0 8 0;3=2,5=1
P 4.025 3.08 3 P 0 8 0;3=2,5=1
P 0.62 3.07 3 P 0 8 0;3=2,5=1
P 0.66 3.056 27 P 0 8 0;0,3=0,5=0
P 5.865 1.125 6 P 0 8 0;1,3=1,5=1
P 5.865 1.07 6 P 0 8 0;1,3=1,5=1
P 2.265 3.34 3 P 0 8 0;3=2,5=1
P 4.57 2.585 3 P 0 8 0;3=2,5=1
P 4.02 3.03 3 P 0 8 0;3=2,5=1
P 0.645 2.9675 3 P 0 8 0;3=2,5=1
P 0.5505 3.0028 39 P 0 8 0;0,3=17,5=0
P 5.48828996 4.16328996 6 P 0 8 0;1,3=1,5=1
P 5.55315 4.175 6 P 0 8 0;1,3=1,5=1
P 5.67126004 4.175 6 P 0 8 0;1,3=1,5=1
P 5.78936998 4.175 6 P 0 8 0;1,3=1,5=1
P 4.205 2.295 6 P 0 8 0;1,3=3,5=0
P 4.65933002 1.6269 6 P 0 8 0;3=3,5=0
P 4.254 2.296 6 P 0 8 0;1,3=3,5=0
P 4.23 2.354 6 P 0 8 0;1,3=3,5=0
P 4.915 1.485 6 P 0 8 0;1,3=3,5=0
P 3.94 2.235 6 P 0 8 0;1,3=3,5=0
P 4.85 1.54 6 P 0 8 0;1,3=3,5=0
P 4.149 2.298 6 P 0 8 0;1,3=3,5=0
P 4.161 2.354 6 P 0 8 0;1,3=3,5=0
P 3.75 2.1 6 P 0 8 0;1,3=3,5=0
P 4.975 1.485 6 P 0 8 0;1,3=3,5=0
P 3.8 2.1 6 P 0 8 0;1,3=3,5=0
P 4.73806998 1.54816004 6 P 0 8 0;1,3=3,5=0
P 3.9 2.325 6 P 0 8 0;1,3=3,5=0
P 4.73806998 1.50878996 6 P 0 8 0;3=3,5=0
P 3.83 2.325 6 P 0 8 0;1,3=3,5=0
P 0.846 2.489 6 P 0 8 0;1,3=4,5=1
P 0.805 2.444 27 P 0 8 0;0,3=0,5=0
P 3.28 3.065 3 P 0 8 0;3=2,5=1
P 0.85 2.444 27 P 0 8 0;0,3=0,5=0
P 0.796 2.489 6 P 0 8 0;1,3=4,5=1
P 3.325 3.065 3 P 0 8 0;3=2,5=1
P 0.76 2.444 27 P 0 8 0;0,3=0,5=0
P 0.715 2.444 27 P 0 8 0;0,3=0,5=0
P 4.985 3.546 27 P 0 8 0;0,3=0,5=0
P 5.03 3.546 6 P 0 8 0;1,3=4,5=1
P 4.935 3.546 27 P 0 8 0;0,3=0,5=0
P 4.935 3.59 6 P 0 8 0;1,3=4,5=1
P 4.67 3.555 6 P 0 8 0;1,3=3,5=0
P 4.736 3.551 30 P 0 8 0;0,3=0,5=0
P 4.885 3.546 27 P 0 8 0;0,3=0,5=0
P 4.885 3.59 6 P 0 8 0;1,3=9,5=1
P 4.70461998 3.69461998 6 P 0 8 0;1,3=4,5=1
P 5.395 2.92 6 P 0 8 0;1,3=1,5=1
P 5.496 2.87 30 P 0 8 0;0,3=0,5=0
P 5.502 2.9225 30 P 0 8 0;0,3=0,5=0
P 5.452 2.9225 27 P 0 8 0;0,3=0,5=0
P 5.504 2.815 30 P 0 8 0;0,3=0,5=0
P 4.926 1.81 30 P 0 8 0;0,3=0,5=0
P 5.015 1.925 3 P 0 8 0;3=2,5=1
P 5.452 2.771 27 P 0 8 0;0,3=0,5=0
P 5.504 2.77 30 P 0 8 0;0,3=0,5=0
P 5.39976998 2.75123996 6 P 0 8 0;1,3=9,5=1
P 5.504 3.065 30 P 0 8 0;0,3=0,5=0
P 5.504 3.02 30 P 0 8 0;0,3=0,5=0
P 5.452 3.019 27 P 0 8 0;0,3=0,5=0
P 5.375 2.96606998 6 P 0 8 0;1,3=9,5=1
P 5.504 2.595 30 P 0 8 0;0,3=0,5=0
P 5.4525 2.6375 27 P 0 8 0;0,3=0,5=0
P 5.504 2.64 30 P 0 8 0;0,3=0,5=0
P 5.4525 2.563 6 P 0 8 0;1,3=9,5=1
P 3.545 0.6092 3 P 0 8 0;3=2,5=1
P 1.395 0.625 6 P 0 8 0;1,3=9,5=1
P 5.085 0.645 3 P 0 8 0;3=2,5=1
P 3.495 0.61 3 P 0 8 0;3=2,5=1
P 5.04 0.645 3 P 0 8 0;3=2,5=1
P 1.485 0.625 6 P 0 8 0;1,3=9,5=1
P 2.34841998 0.13781004 29 P 0 8 0;0,3=27,5=0
P 2.3431 0.5839 27 P 0 8 0;0,3=0,5=0
P 2.38778996 0.13781004 29 P 0 8 0;0,3=27,5=0
P 2.39311004 0.584 27 P 0 8 0;0,3=0,5=0
P 2.97303002 0.584 27 P 0 8 0;0,3=0,5=0
P 2.97833996 0.13781004 29 P 0 8 0;0,3=27,5=0
P 3.02303002 0.584 27 P 0 8 0;0,3=0,5=0
P 3.01771004 0.13781004 29 P 0 8 0;0,3=27,5=0
P 2.80055 0.584 27 P 0 8 0;0,3=0,5=0
P 2.82086004 0.13781004 29 P 0 8 0;0,3=27,5=0
P 2.85055 0.584 27 P 0 8 0;0,3=0,5=0
P 2.86023002 0.13781004 29 P 0 8 0;0,3=27,5=0
P 2.65806998 0.584 27 P 0 8 0;0,3=0,5=0
P 2.66338002 0.13781004 29 P 0 8 0;0,3=27,5=0
P 2.70806998 0.584 27 P 0 8 0;0,3=0,5=0
P 2.70275 0.13781004 29 P 0 8 0;0,3=27,5=0
P 2.46121998 0.584 27 P 0 8 0;0,3=0,5=0
P 2.46653002 0.13781004 29 P 0 8 0;0,3=27,5=0
P 2.51121998 0.584 27 P 0 8 0;0,3=0,5=0
P 2.5059 0.13781004 29 P 0 8 0;0,3=27,5=0
P 2.95835 0.385 2 P 0 8 0;3=12,5=1
P 2.95835 0.353 2 P 0 8 0;3=12,5=1
P 2.80086998 0.385 2 P 0 8 0;3=12,5=1
P 2.80086998 0.353 2 P 0 8 0;3=12,5=1
P 2.64338996 0.385 2 P 0 8 0;3=12,5=1
P 2.64338996 0.353 2 P 0 8 0;3=12,5=1
P 2.95835 0.481 2 P 0 8 0;3=12,5=1
P 2.95835 0.449 2 P 0 8 0;3=12,5=1
P 3.125 0.875 2 P 0 8 0;3=12,5=1
P 2.97303002 0.626 27 P 0 8 0;0,3=0,5=0
P 3.14763002 0.85236998 2 P 0 8 0;3=12,5=1
P 3.02303002 0.626 27 P 0 8 0;0,3=0,5=0
P 2.81855 0.763 2 P 0 8 0;3=12,5=1
P 2.80055 0.626 27 P 0 8 0;0,3=0,5=0
P 2.85055 0.763 2 P 0 8 0;3=12,5=1
P 2.85055 0.626 27 P 0 8 0;0,3=0,5=0
P 2.66706998 0.763 2 P 0 8 0;3=12,5=1
P 2.65806998 0.626 27 P 0 8 0;0,3=0,5=0
P 2.69906998 0.763 2 P 0 8 0;3=12,5=1
P 2.70806998 0.626 27 P 0 8 0;0,3=0,5=0
P 2.47021998 0.763 2 P 0 8 0;3=12,5=1
P 2.46121998 0.626 27 P 0 8 0;0,3=0,5=0
P 2.50221998 0.763 2 P 0 8 0;3=12,5=1
P 2.51121998 0.626 27 P 0 8 0;0,3=0,5=0
P 1.889 0.5496 3 P 0 8 0;3=2,5=1
P 2.435 0.4865 6 P 0 8 0;1,3=4,5=1
P 1.8646 0.6022 27 P 0 8 0;0,3=0,5=0
P 1.79723996 0.15731004 28 P 0 8 0;0,3=37,5=0
P 3.56 3.023 6 P 0 8 0;1,3=1,5=1
P 3.461 2.255 30 P 0 8 0;0,3=0,5=0
P 3.461 2.21 30 P 0 8 0;0,3=0,5=0
P 3.57 2.955 6 P 0 8 0;1,3=1,5=1
P 3.329 2.21 30 P 0 8 0;0,3=0,5=0
P 3.329 2.255 30 P 0 8 0;0,3=0,5=0
P 4.975 2.14 3 P 0 8 0;3=2,5=1
P 5.03005 0.99493996 6 P 0 8 0;1,3=1,5=1
P 3.09645 0.13781004 29 P 0 8 0;0,3=27,5=0
P 2.58463996 0.13781004 29 P 0 8 0;0,3=27,5=0
P 5.638 3.907 6 P 0 8 0;1,3=1,5=1
P 1.8317 0.5639 6 P 0 8 0;1,3=9,5=1
P 5.372 3.963 6 P 0 8 0;1,3=13,5=1
A 6.58071004 2.84646004 6.60038996 2.86613996 6.58071004 2.86613996 7 P 0 N
L 6.60038996 2.86613996 6.60038996 4.33661004 7 P 0 
A 6.60038996 4.33661004 6.56101998 4.37598002 6.56101998 4.33661004 7 P 0 N
L 6.56101998 4.37598002 0.03936998 4.37598002 7 P 0 
A 0.03936998 4.37598002 0 4.33661004 0.03936998 4.33661004 7 P 0 N
L 0 4.33661004 0 0.21653996 7 P 0 
A 0 0.21653996 0.03936998 0.17716998 0.03936998 0.21653996 7 P 0 N
L 0.03936998 0.17716998 0.55118002 0.17716998 7 P 0 
A 0.55118002 0.17716998 0.59055 0.21653996 0.55118002 0.21653996 7 P 0 N
L 0.59055 0.21653996 0.59055 0.4626 7 P 0 
A 0.59055 0.4626 0.62991998 0.50196998 0.62991998 0.4626 7 P 0 Y
L 0.62991998 0.50196998 1.27361998 0.50196998 7 P 0 
A 1.27361998 0.50196998 1.31298996 0.4626 1.27361998 0.4626 7 P 0 Y
L 1.31298996 0.4626 1.31298996 0.21653996 7 P 0 
A 1.31298996 0.21653996 1.35236004 0.17716998 1.35235994 0.21653996 7 P 0 N
L 1.35236004 0.17716998 1.58858002 0.17716998 7 P 0 
A 1.58858002 0.17716998 1.62795 0.21653996 1.58858002 0.21653996 7 P 0 N
L 1.62795 0.21653996 1.62795 0.43011998 7 P 0 
A 1.62795 0.43011998 1.77165 0.43011998 1.6998 0.43011998 7 P 0 Y
L 1.77165 0.43011998 1.77165 0.01968996 7 P 0 
L 1.77165 0.01968996 1.79133996 0 7 P 8191 
L 1.79133996 0 2.19291004 0 7 P 0 
L 2.19291004 0 2.2126 0.01968996 7 P 8191 
L 2.2126 0.01968996 2.2126 0.29331004 7 P 0 
A 2.2126 0.29331004 2.2874 0.29331004 2.25 0.29331004 7 P 0 Y
L 2.2874 0.29331004 2.2874 0.01968996 7 P 0 
L 2.2874 0.01968996 2.30708996 0 7 P 8191 
L 2.30708996 0 3.10236004 0 7 P 0 
L 3.10236004 0 3.12205 0.01968996 7 P 8191 
L 3.12205 0.01968996 3.12205 0.4626 7 P 0 
A 3.12205 0.4626 3.16141998 0.50196998 3.16141998 0.4626 7 P 0 Y
L 3.16141998 0.50196998 6.56101998 0.50196998 7 P 0 
A 6.56101998 0.50196998 6.60038996 0.54133996 6.56101998 0.54133996 7 P 0 N
L 6.60038996 0.54133996 6.60038996 2.375 7 P 0 
A 6.60038996 2.375 6.58071004 2.39468996 6.58070502 2.37500502 7 P 0 N
L 6.58071004 2.39468996 6.57211004 2.39468996 7 P 8191 
A 6.57211004 2.39468996 6.55243002 2.41436998 6.57211004 2.41436998 7 P 0 Y
L 6.55243002 2.41436998 6.55243002 2.82676998 7 P 0 
A 6.55243002 2.82676998 6.57211004 2.84646004 6.57211496 2.826775 7 P 0 Y
L 6.57211004 2.84646004 6.58071004 2.84646004 7 P 8191 
S P 0
OB 0.5 4.33661003937 I
OS 0.5 3.5315
OS 0.039369980315 3.5315
OS 0.030119980315 3.5315
OS 0.030119980315 3.9179
OS 0.030119980315 4.337469980315
OS 0.03853996063 4.34588996063
OS 0.5 4.34588996063
OS 0.5 4.33661003937
OE
SE
S P 0
OB 6.20551003937 3.9252 I
OS 6.20551003937 4.33661003937
OS 6.20551003937 4.344919980315
OS 6.564030019685 4.344919980315
OS 6.5698 4.33915
OS 6.5698 3.9252
OS 6.20551003937 3.9252
OE
SE
S P 0
OB 6.205 0.54133996063 I
OS 6.20551003937 0.54133996063
OS 6.20551003937 0.901569980315
OS 6.570169980315 0.901569980315
OS 6.570169980315 0.54005
OS 6.562419980315 0.5323
OS 6.205 0.5323
OS 6.205 0.54133996063
OE
SE
S P 0
OB 0.560430019685 0.5353 I
OS 0.560430019685 0.2166
OS 0.55126003937 0.207430019685
OS 0.071380019685 0.207430019685
OS 0.038269980315 0.207430019685
OS 0.030330019685 0.215369980315
OS 0.030330019685 0.5353
OS 0.560430019685 0.5353
OE
SE
P 1.105 4.145 14 P 0 8 0;0,3=38,5=0
P 5.78 1.165 14 P 0 8 0;0,3=38,5=0
P 0.95 0.845 14 P 0 8 0;0,3=38,5=0
P 2.68566998 1.12143002 13 P 0 8 0;3=39,5=0
P 2.68566998 2.55943002 13 P 0 8 0;3=39,5=0
P 1.46066998 2.68043002 13 P 0 8 0;3=39,5=0
P 1.43566998 1.06043002 13 P 0 8 0;3=39,5=0
P 6.40038996 0.65353996 16 P 0 8 0;3=40,5=0
P 0.29528002 3.73031004 16 P 0 8 0;3=40,5=0
P 0.29528002 0.36811004 16 P 0 8 0;3=40,5=0
P 6.40038996 4.17835 16 P 0 8 0;3=40,5=0
P 6.34055 3.34448996 15 P 0 8 0;3=41,5=0
P 6.34055 3.67518996 15 P 0 8 0;3=41,5=0
L 3.16 -0.655 3.16 -1.58 1 P 0 
L 1.36 -0.655 1.36 -1.58 1 P 0 
L 1.36 -1.58 5.06 -1.58 1 P 0 
L 5.06 -1.58 5.06 -0.655 1 P 0 
L 5.06 -0.655 1.36 -0.655 1 P 0 
A 1.559 -1.33655 1.559 -1.33655 1.55268002 -1.33655 7 P 0 N
A 1.54775 -1.205 1.54775 -1.205 1.53883002 -1.205 7 P 0 N
A 1.54763996 -0.99775 1.54763996 -0.99775 1.53871998 -0.99775 7 P 0 N
A 1.54063996 -1.10118002 1.54063996 -1.10118002 1.52603996 -1.10118002 7 P 0 N
A 1.49695 -1.10118002 1.49695 -1.10118002 1.48656998 -1.10118002 7 P 0 N
A 1.45963996 -1.10118002 1.45963996 -1.10118002 1.4533 -1.10118002 7 P 0 N
A 1.52135 -0.98681004 1.52135 -0.98681004 1.51503002 -0.98681004 7 P 0 N
A 1.79433002 -1.43586998 1.79433002 -1.43586998 1.78798996 -1.43586998 7 P 0 N
A 1.79841004 -1.40261004 1.79841004 -1.40261004 1.78798996 -1.40261004 7 P 0 N
A 1.80255 -1.36311004 1.80255 -1.36311004 1.78798996 -1.36311004 7 P 0 N
A 1.80668996 -1.31528002 1.80668996 -1.31528002 1.78798996 -1.31528002 7 P 0 N
A 1.68013002 -1.37456004 1.68013002 -1.37456004 1.67378996 -1.37456004 7 P 0 N
A 1.69321998 -1.35033002 1.69321998 -1.35033002 1.6843 -1.35033002 7 P 0 N
A 1.7108 -1.31738996 1.7108 -1.31738996 1.69798002 -1.31738996 7 P 0 N
A 1.89666998 -1.31511004 1.89666998 -1.31511004 1.88383996 -1.31511004 7 P 0 N
A 1.88198996 -1.16876004 1.88198996 -1.16876004 1.85558996 -1.16876004 7 P 0 N
A 1.87928002 -1.27801998 1.87928002 -1.27801998 1.86343996 -1.27801998 7 P 0 N
A 1.86176998 -1.23075 1.86176998 -1.23075 1.84206004 -1.23075 7 P 0 N
A 1.80978996 -1.25916998 1.80978996 -1.25916998 1.78798996 -1.25916998 7 P 0 N
A 1.74681004 -1.16876004 1.74681004 -1.16876004 1.72041004 -1.16876004 7 P 0 N
A 1.67813002 -1.15513002 1.67813002 -1.15513002 1.65841998 -1.15513002 7 P 0 N
A 1.73018002 -1.27816004 1.73018002 -1.27816004 1.71433996 -1.27816004 7 P 0 N
A 1.75373002 -1.23081004 1.75373002 -1.23081004 1.73405 -1.23081004 7 P 0 N
A 1.65531004 -1.25255 1.65531004 -1.25255 1.63661998 -1.25255 7 P 0 N
A 1.69808996 -1.21291998 1.69808996 -1.21291998 1.67628996 -1.21291998 7 P 0 N
A 1.81438996 -1.1968 1.81438996 -1.1968 1.78798996 -1.1968 7 P 0 N
A 1.6269 -1.1749 1.6269 -1.1749 1.61106004 -1.1749 7 P 0 N
A 1.58461004 -1.19126004 1.58461004 -1.19126004 1.57178002 -1.19126004 7 P 0 N
A 1.5853 -1.31428002 1.5853 -1.31428002 1.57488996 -1.31428002 7 P 0 N
A 1.61735 -1.28638996 1.61735 -1.28638996 1.60276998 -1.28638996 7 P 0 N
A 1.88198996 -1.03361004 1.88198996 -1.03361004 1.85558996 -1.03361004 7 P 0 N
A 1.71881004 -1.10118002 1.71881004 -1.10118002 1.69238996 -1.10118002 7 P 0 N
A 1.65183002 -1.10118002 1.65183002 -1.10118002 1.63003002 -1.10118002 7 P 0 N
A 1.67801998 -1.04738996 1.67801998 -1.04738996 1.65831004 -1.04738996 7 P 0 N
A 1.74681004 -1.03361004 1.74681004 -1.03361004 1.72041004 -1.03361004 7 P 0 N
A 1.69811998 -0.98951004 1.69811998 -0.98951004 1.67631998 -0.98951004 7 P 0 N
A 1.81438996 -1.00556004 1.81438996 -1.00556004 1.78798996 -1.00556004 7 P 0 N
A 1.59258002 -1.10118002 1.59258002 -1.10118002 1.5739 -1.10118002 7 P 0 N
A 1.58451004 -1.01148996 1.58451004 -1.01148996 1.57168002 -1.01148996 7 P 0 N
A 1.62681004 -1.02773996 1.62681004 -1.02773996 1.61096998 -1.02773996 7 P 0 N
A 1.92148002 -1.21285 1.92148002 -1.21285 1.89968002 -1.21285 7 P 0 N
A 1.92148002 -0.98951004 1.92148002 -0.98951004 1.89968002 -0.98951004 7 P 0 N
A 1.80978996 -0.9432 1.80978996 -0.9432 1.78798996 -0.9432 7 P 0 N
A 1.80668996 -0.88708002 1.80668996 -0.88708002 1.78798996 -0.88708002 7 P 0 N
A 1.80255 -0.83923996 1.80255 -0.83923996 1.78798996 -0.83923996 7 P 0 N
A 1.8919 -0.88538002 1.8919 -0.88538002 1.87906998 -0.88538002 7 P 0 N
A 1.87838996 -0.92456998 1.87838996 -0.92456998 1.86255 -0.92456998 7 P 0 N
A 1.65531004 -0.94981004 1.65531004 -0.94981004 1.63661998 -0.94981004 7 P 0 N
A 1.73123002 -0.92378002 1.73123002 -0.92378002 1.71538996 -0.92378002 7 P 0 N
A 1.71216998 -0.88443996 1.71216998 -0.88443996 1.69935 -0.88443996 7 P 0 N
A 1.86225 -0.97178002 1.86225 -0.97178002 1.84253996 -0.97178002 7 P 0 N
A 1.75451998 -0.97123996 1.75451998 -0.97123996 1.73483996 -0.97123996 7 P 0 N
A 1.61741998 -0.91601004 1.61741998 -0.91601004 1.60283996 -0.91601004 7 P 0 N
A 1.5853 -0.88808996 1.5853 -0.88808996 1.57488996 -0.88808996 7 P 0 N
A 1.79841004 -0.79975 1.79841004 -0.79975 1.78798996 -0.79975 7 P 0 N
A 1.79433002 -0.76648002 1.79433002 -0.76648002 1.78798996 -0.76648002 7 P 0 N
A 1.92135 -1.36781004 1.92135 -1.36781004 1.91503996 -1.36781004 7 P 0 N
A 1.91096004 -1.34658002 1.91096004 -1.34658002 1.90203996 -1.34658002 7 P 0 N
A 2.19078996 -1.1806 2.26591004 -1.16473002 2.21741014 -1.12088169 7 P 0 N
A 2.15903002 -1.1402 2.19078996 -1.18061004 2.22093406 -1.12423278 7 P 0 N
A 2.05721004 -1.16178996 2.08853002 -1.16658996 2.08281614 -1.09929134 7 P 0 N
A 2.00546998 -1.13951998 2.03345 -1.17196004 2.07793927 -1.10530069 7 P 0 N
A 2.03346004 -1.17195 2.0847 -1.18461004 2.07891181 -1.09801299 7 P 0 N
A 2.0847 -1.18461998 2.14261004 -1.15663002 2.07348435 -1.08751378 7 P 0 N
A 2.08853996 -1.16658002 2.13313002 -1.14451998 2.06368967 -1.06025512 7 P 0 N
A 1.95808002 -1.25255 1.95808002 -1.25255 1.93938996 -1.25255 7 P 0 N
A 1.98775 -1.28635 1.98775 -1.28635 1.97316998 -1.28635 7 P 0 N
A 2.27411998 -1.11835 2.15906004 -1.11835 2.21658996 -1.11611998 7 P 0 N
L 2.25188002 -1.11418002 2.1807 -1.11418002 7 P 0 
L 2.1807 -1.11418002 2.1807 -1.11398996 7 P 8191 
A 2.25188996 -1.11398996 2.18071004 -1.11398996 2.2163 -1.1124 7 P 0 N
A 2.08028996 -1.03428996 2.02048996 -1.08258996 2.0798126 -1.09486801 7 P 0 N
A 2.13151998 -1.05146004 2.0803 -1.0343 2.0802999 -1.11932195 7 P 0 N
A 2.1315 -1.05146998 2.14175 -1.03951004 2.1356003 -1.04461171 7 P 0 N
A 2.14175 -1.03951004 2.08283002 -1.01613002 2.07772461 -1.11492805 7 P 0 N
A 2.08283996 -1.01611998 2.00698002 -1.05835 2.08064724 -1.10143169 7 P 0 N
L 2.27413002 -1.12868996 2.18073996 -1.12868996 7 P 0 
A 2.18075 -1.12868996 2.19083002 -1.15751998 2.22417795 -1.12968307 7 P 0 N
A 2.19083002 -1.15753002 2.25311004 -1.15211004 2.21927195 -1.12381791 7 P 0 N
L 2.15903996 -1.1402 2.15903996 -1.11835 7 P 8191 
A 2.02048996 -1.0826 2.05721998 -1.16181004 2.09087933 -1.0980811 7 P 0 N
A 2.00698996 -1.05836004 2.00546998 -1.13953002 2.09672953 -1.10063967 7 P 0 N
A 2.14258996 -1.15661004 2.13313996 -1.14453002 2.13544892 -1.15246004 7 P 0 N
A 1.95808002 -0.94981004 1.95808002 -0.94981004 1.93938996 -0.94981004 7 P 0 N
A 1.90183996 -0.8525 1.90183996 -0.8525 1.89291004 -0.8525 7 P 0 N
A 1.91108002 -0.82726998 1.91108002 -0.82726998 1.90473996 -0.82726998 7 P 0 N
L 2.32081004 -1.02041004 2.32081004 -1.17625 7 P 0 
A 2.49568002 -1.15528996 2.47898002 -1.16443002 2.4882003 -1.1614502 7 P 0 N
A 2.47896998 -1.16443996 2.50283002 -1.18086004 2.51649242 -1.13546152 7 P 0 N
A 2.50281998 -1.18086998 2.54318002 -1.1834 2.52887392 -1.08843022 7 P 0 N
A 2.52306998 -1.16761004 2.52848996 -1.16771998 2.52673258 -1.12070098 7 P 0 N
A 2.49566004 -1.15528996 2.52306998 -1.1676 2.5255122 -1.12549094 7 P 0 N
A 2.37851998 -1.15753002 2.4408 -1.15211004 2.40696191 -1.12381791 7 P 0 N
A 2.45358002 -1.16471998 2.44078996 -1.1521 2.44541191 -1.16020689 7 P 0 N
A 2.37848002 -1.1806 2.4536 -1.16473002 2.4051001 -1.12088169 7 P 0 N
A 2.34673002 -1.1402 2.37848996 -1.18061004 2.40863406 -1.12423278 7 P 0 N
A 2.2659 -1.16471998 2.25311004 -1.1521 2.25773199 -1.16020689 7 P 0 N
A 2.3006 -1.17626004 2.3208 -1.17626004 2.3107 -1.17386841 7 P 0 N
L 2.30058996 -1.17625 2.30058996 -1.02033996 7 P 0 
A 2.50836998 -1.10106004 2.54306004 -1.11513002 2.56106673 -1.02093386 7 P 0 N
A 2.51081004 -1.07948002 2.50836998 -1.10103996 2.51886093 -1.09130915 7 P 0 N
A 2.53611004 -1.07688996 2.5108 -1.07948996 2.52742205 -1.11680827 7 P 0 N
A 2.56883996 -1.07368002 2.50178002 -1.06358996 2.5273123 -1.12178858 7 P 0 N
A 2.50178996 -1.06358996 2.48536998 -1.08248996 2.52926211 -1.10403986 7 P 0 N
L 2.48536998 -1.0825 2.48536998 -1.09748002 7 P 8191 
A 2.48536998 -1.09748002 2.49956004 -1.12031004 2.51189104 -1.09682067 7 P 0 N
A 2.46181004 -1.11835 2.34675 -1.11835 2.40428002 -1.11611998 7 P 0 N
L 2.43956998 -1.11418002 2.36841004 -1.11418002 7 P 0 
L 2.36841004 -1.11418002 2.36841004 -1.11398996 7 P 8191 
A 2.43958002 -1.11398996 2.3684 -1.11398996 2.40398996 -1.1124 7 P 0 N
L 2.43956998 -1.11398996 2.43956998 -1.11418002 7 P 8191 
A 2.49955 -1.1203 2.52723002 -1.12985 2.58163209 -0.92727982 7 P 0 N
A 2.55001998 -1.14328002 2.52723002 -1.12986004 2.51462185 -1.17733228 7 P 0 N
L 2.46181004 -1.12868996 2.36843996 -1.12868996 7 P 0 
A 2.36843996 -1.12868996 2.37851998 -1.15751998 2.41186801 -1.12968307 7 P 0 N
L 2.34675 -1.1402 2.34675 -1.11835 7 P 8191 
L 2.46181004 -1.11835 2.46181004 -1.12868996 7 P 8191 
L 2.25188002 -1.11398996 2.25188002 -1.11418002 7 P 8191 
A 2.3208 -1.02041004 2.3006 -1.02033996 2.31069163 -1.02276978 7 P 0 N
L 2.27413002 -1.11835 2.27413002 -1.12868996 7 P 8191 
A 2.52848996 -1.16771004 2.54891998 -1.15895 2.52774557 -1.13777087 7 P 0 N
A 2.55608002 -1.08618002 2.53611998 -1.07688996 2.5249185 -1.12704419 7 P 0 N
L 2.71926004 -1.06796998 2.71926004 -1.17483996 7 P 0 
A 2.78888996 -1.16296998 2.81508002 -1.16676998 2.8083499 -1.12100167 7 P 0 N
A 2.8151 -1.16675 2.83966004 -1.15211998 2.80521398 -1.12222392 7 P 0 N
A 2.85201004 -1.16508002 2.83966004 -1.15211004 2.84505768 -1.15933514 7 P 0 N
L 2.85201004 -1.16508002 2.84523996 -1.17161004 7 P 8191 
A 2.81425 -1.1835 2.84525 -1.17161004 2.81425 -1.13714291 7 P 0 N
L 2.81425 -1.1835 2.79571004 -1.1835 7 P 8191 
A 2.75886998 -1.16443002 2.79571998 -1.18351998 2.80278976 -1.12476142 7 P 0 N
A 2.74528996 -1.13568002 2.75888002 -1.16443002 2.80246565 -1.12624016 7 P 0 N
A 2.54316998 -1.1834 2.56906004 -1.1647 2.5305814 -1.13869892 7 P 0 N
A 2.56906004 -1.1647 2.57053996 -1.13728002 2.53763041 -1.14925374 7 P 0 N
A 2.65463996 -1.18351998 2.66863996 -1.17373996 2.65440246 -1.16826969 7 P 0 N
L 2.65463002 -1.1835 2.64165 -1.1835 7 P 8191 
A 2.60955 -1.16043002 2.64163996 -1.18351004 2.63911063 -1.15317815 7 P 0 N
A 2.62978002 -1.15461998 2.66001998 -1.16328996 2.6502374 -1.14033868 7 P 0 N
A 2.66863996 -1.17375 2.66001998 -1.16328996 2.66100344 -1.17126132 7 P 0 N
A 2.6962 -1.17483996 2.71926004 -1.17483996 2.70773002 -1.17286427 7 P 0 N
L 2.69618996 -1.17483996 2.69618996 -1.06796998 7 P 0 
A 2.83833002 -1.09275 2.82661998 -1.08201998 2.74555758 -1.18224094 7 P 0 N
A 2.82661998 -1.08198996 2.80036998 -1.07538996 2.80348839 -1.11848878 7 P 0 N
A 2.80036004 -1.07541998 2.76848996 -1.09933002 2.80700217 -1.1174685 7 P 0 N
A 2.76848996 -1.09931998 2.76446004 -1.12066004 2.82315728 -1.120694 7 P 0 N
A 2.74998002 -1.09273996 2.74528996 -1.11838996 2.8498563 -1.12425591 7 P 0 N
A 2.7954 -1.05776998 2.74998996 -1.09273996 2.80799961 -1.12109961 7 P 0 N
L 2.79541004 -1.05776998 2.80918996 -1.05776998 7 P 8191 
A 2.85401998 -1.08106004 2.80918996 -1.05776998 2.80626024 -1.1181998 7 P 0 N
A 2.83833002 -1.09273996 2.85403002 -1.08106004 2.84418386 -1.08421683 7 P 0 N
L 2.76445 -1.12066004 2.76445 -1.12943002 7 P 8191 
A 2.76446004 -1.12943002 2.76836998 -1.14305 2.80607844 -1.12485364 7 P 0 N
A 2.76836998 -1.14305 2.78891004 -1.16296998 2.80906152 -1.12164144 7 P 0 N
L 2.74528996 -1.13566004 2.74528996 -1.11838996 7 P 8191 
A 2.55606004 -1.0862 2.56885 -1.07366998 2.56205354 -1.0795252 7 P 0 N
L 2.60953996 -1.07953996 2.59981998 -1.07953996 7 P 8191 
A 2.5993 -1.05931998 2.59981004 -1.07955 2.6022813 -1.06936624 7 P 0 N
L 2.5993 -1.05931998 2.60953996 -1.05931998 7 P 8191 
L 2.60953996 -1.05931998 2.60953996 -1.03491998 7 P 8191 
A 2.62971998 -1.03418002 2.60953996 -1.03491004 2.61966791 -1.03559478 7 P 0 N
L 2.62971004 -1.03418996 2.62978002 -1.05931998 7 P 8191 
L 2.62978002 -1.05931998 2.66008002 -1.05931998 7 P 8191 
A 2.66003996 -1.07955 2.66008002 -1.05931998 2.65827421 -1.0694314 7 P 0 N
L 2.66003002 -1.07953996 2.62978002 -1.07953996 7 P 8191 
A 2.71926004 -1.06796998 2.6962 -1.06796998 2.70773002 -1.0720561 7 P 0 N
A 2.71968996 -1.02341998 2.71968996 -1.02341998 2.70775 -1.02341998 7 P 0 N
A 2.57053996 -1.13728996 2.54306998 -1.11513002 2.53584449 -1.15219301 7 P 0 N
A 2.54891998 -1.15895 2.55001004 -1.14328002 2.54127923 -1.15054557 7 P 0 N
L 2.60953996 -1.16041004 2.60953996 -1.07953996 7 P 0 
L 2.62978002 -1.07953996 2.62978002 -1.15463002 7 P 0 
L 2.98495 -1.09393996 2.98495 -1.17625 7 P 0 
A 2.96473996 -1.17626998 2.98493996 -1.17626998 2.97483996 -1.17442303 7 P 0 N
L 2.96473002 -1.17625 2.96473002 -1.17226004 7 P 8191 
A 2.94165 -1.1835 2.96471004 -1.17226004 2.93076516 -1.1318935 7 P 0 N
L 2.94165 -1.1835 2.90701004 -1.1835 7 P 8191 
A 2.90671004 -1.10841998 2.90703002 -1.18351004 2.9153065 -1.14592904 7 P 0 N
A 2.91853002 -1.12288996 2.91853002 -1.16618996 2.92048209 -1.14453996 7 P 0 N
L 2.91853002 -1.1662 2.94456004 -1.1662 7 P 8191 
A 2.94456998 -1.16618996 2.94456998 -1.12288996 2.94406004 -1.14453996 7 P 0 N
A 2.96473002 -1.09686004 2.94741998 -1.07955 2.94874833 -1.09553169 7 P 0 N
L 2.9474 -1.07953996 2.90986998 -1.07953996 7 P 8191 
A 2.90986998 -1.07953996 2.89821004 -1.0852 2.92433445 -1.12417766 7 P 0 N
A 2.89111998 -1.07086004 2.8982 -1.0852 2.8969689 -1.07688996 7 P 0 N
A 2.91561998 -1.05931998 2.89111998 -1.07085 2.92146033 -1.103525 7 P 0 N
L 2.91563002 -1.05931998 2.95031004 -1.05931998 7 P 8191 
A 2.98496004 -1.09393996 2.95031004 -1.05933002 2.9453438 -1.09895197 7 P 0 N
A 2.92878996 -1.10535 2.9067 -1.10841998 2.93158484 -1.20646998 7 P 0 N
A 2.96471998 -1.10841004 2.92878002 -1.10536004 2.93215738 -1.27883829 7 P 0 N
L 2.96473002 -1.10841004 2.96473002 -1.09686004 7 P 8191 
L 2.94456004 -1.12288002 2.91853002 -1.12288002 7 P 8191 
L 3.04731004 -1.06001004 3.04191998 -1.07631998 7 P 8191 
L 3.04191998 -1.07631998 3.03648002 -1.06001004 7 P 8191 
L 3.03648002 -1.06001004 3.03243002 -1.06001004 7 P 8191 
L 3.03243002 -1.06001004 3.02698002 -1.08543996 7 P 8191 
L 3.02698002 -1.08543996 3.03226004 -1.08543996 7 P 8191 
L 3.03226004 -1.08543996 3.03501004 -1.06886998 7 P 8191 
L 3.03501004 -1.06886998 3.04086004 -1.08543996 7 P 8191 
L 3.04086004 -1.08543996 3.04308996 -1.08543996 7 P 8191 
L 3.04308996 -1.08543996 3.04888996 -1.06871004 7 P 8191 
L 3.04888996 -1.06871004 3.05171004 -1.08543996 7 P 8191 
L 3.05171004 -1.08543996 3.05713002 -1.08543996 7 P 8191 
L 3.05713002 -1.08543996 3.05163996 -1.06001004 7 P 8191 
L 3.05163996 -1.06001004 3.04731004 -1.06001004 7 P 8191 
L 3.01066998 -1.06508002 3.00223002 -1.06508002 7 P 8191 
L 3.00223002 -1.06508002 3.00223002 -1.06001004 7 P 8191 
L 3.00223002 -1.06001004 3.02461004 -1.06001004 7 P 8191 
L 3.02461004 -1.06001004 3.02461004 -1.06508002 7 P 8191 
L 3.02461004 -1.06508002 3.01615 -1.06508002 7 P 8191 
L 3.01615 -1.06508002 3.01615 -1.08533996 7 P 8191 
L 3.01615 -1.08533996 3.01066998 -1.08533996 7 P 8191 
L 3.01066998 -1.08533996 3.01066998 -1.06508002 7 P 8191 
L 3.84627992 -1.32267215 3.85374665 -1.32892087 0 P 0 ;2,4=42,6=0.000000
L 3.85374665 -1.32892087 3.86214656 -1.33266998 0 P 0 ;2,4=42,6=0.000000
L 3.86214656 -1.33266998 3.86961339 -1.33266998 0 P 0 ;2,4=42,6=0.000000
L 3.86961339 -1.33266998 3.87708012 -1.32892087 0 P 0 ;2,4=42,6=0.000000
L 3.87708012 -1.32892087 3.88268061 -1.32267215 0 P 0 ;2,4=42,6=0.000000
L 3.88268061 -1.32267215 3.88548002 -1.31391949 0 P 0 ;2,4=42,6=0.000000
L 3.88548002 -1.31391949 3.88361378 -1.30517136 0 P 0 ;2,4=42,6=0.000000
L 3.88361378 -1.30517136 3.87894646 -1.29767067 0 P 0 ;2,4=42,6=0.000000
L 3.87894646 -1.29767067 3.87054646 -1.29266939 0 P 0 ;2,4=42,6=0.000000
L 3.87054646 -1.29266939 3.85934715 -1.29016998 0 P 0 ;2,4=42,6=0.000000
L 3.85934715 -1.29016998 3.85281348 -1.28517106 0 P 0 ;2,4=42,6=0.000000
L 3.85281348 -1.28517106 3.8500124 -1.27642057 0 P 0 ;2,4=42,6=0.000000
L 3.8500124 -1.27642057 3.85188041 -1.26767018 0 P 0 ;2,4=42,6=0.000000
L 3.85188041 -1.26767018 3.85654606 -1.26142156 0 P 0 ;2,4=42,6=0.000000
L 3.85654606 -1.26142156 3.86307972 -1.25766998 0 P 0 ;2,4=42,6=0.000000
L 3.86307972 -1.25766998 3.86961339 -1.25766998 0 P 0 ;2,4=42,6=0.000000
L 3.86961339 -1.25766998 3.87614705 -1.26016949 0 P 0 ;2,4=42,6=0.000000
L 3.87614705 -1.26016949 3.88174754 -1.26642047 0 P 0 ;2,4=42,6=0.000000
L 3.94087913 -1.33266998 3.9334123 -1.33142028 0 P 0 ;2,4=42,6=0.000000
L 3.9334123 -1.33142028 3.92688041 -1.32642136 0 P 0 ;2,4=42,6=0.000000
L 3.92688041 -1.32642136 3.92127992 -1.31892067 0 P 0 ;2,4=42,6=0.000000
L 3.92127992 -1.31892067 3.91754567 -1.31017028 0 P 0 ;2,4=42,6=0.000000
L 3.91754567 -1.31017028 3.91567933 -1.30017008 0 P 0 ;2,4=42,6=0.000000
L 3.91567933 -1.30017008 3.91567933 -1.29016998 0 P 0 ;2,4=42,6=0.000000
L 3.91567933 -1.29016998 3.91754567 -1.28016978 0 P 0 ;2,4=42,6=0.000000
L 3.91754567 -1.28016978 3.92127992 -1.27141939 0 P 0 ;2,4=42,6=0.000000
L 3.92127992 -1.27141939 3.92688041 -1.26392096 0 P 0 ;2,4=42,6=0.000000
L 3.92688041 -1.26392096 3.9334123 -1.25891978 0 P 0 ;2,4=42,6=0.000000
L 3.9334123 -1.25891978 3.94087913 -1.25766998 0 P 0 ;2,4=42,6=0.000000
L 3.94087913 -1.25766998 3.94834587 -1.25891978 0 P 0 ;2,4=42,6=0.000000
L 3.94834587 -1.25891978 3.95487953 -1.26392096 0 P 0 ;2,4=42,6=0.000000
L 3.95487953 -1.26392096 3.96048002 -1.27141939 0 P 0 ;2,4=42,6=0.000000
L 3.96048002 -1.27141939 3.96421427 -1.28016978 0 P 0 ;2,4=42,6=0.000000
L 3.96421427 -1.28016978 3.96608061 -1.29016998 0 P 0 ;2,4=42,6=0.000000
L 3.96608061 -1.29016998 3.96608061 -1.30017008 0 P 0 ;2,4=42,6=0.000000
L 3.96608061 -1.30017008 3.96421427 -1.31017028 0 P 0 ;2,4=42,6=0.000000
L 3.96421427 -1.31017028 3.96048002 -1.31892067 0 P 0 ;2,4=42,6=0.000000
L 3.96048002 -1.31892067 3.95487953 -1.32642136 0 P 0 ;2,4=42,6=0.000000
L 3.95487953 -1.32642136 3.94834587 -1.33142028 0 P 0 ;2,4=42,6=0.000000
L 3.94834587 -1.33142028 3.94087913 -1.33266998 0 P 0 ;2,4=42,6=0.000000
L 3.99721299 -1.25766998 3.99721299 -1.33266998 0 P 0 ;2,4=42,6=0.000000
L 3.99721299 -1.33266998 4.03454695 -1.33266998 0 P 0 ;2,4=42,6=0.000000
L 4.07034675 -1.33266998 4.07034675 -1.25766998 0 P 0 ;2,4=42,6=0.000000
L 4.07034675 -1.25766998 4.08901289 -1.25766998 0 P 0 ;2,4=42,6=0.000000
L 4.08901289 -1.25766998 4.09647963 -1.26142156 0 P 0 ;2,4=42,6=0.000000
L 4.09647963 -1.26142156 4.10208012 -1.26642047 0 P 0 ;2,4=42,6=0.000000
L 4.10208012 -1.26642047 4.10674754 -1.2739188 0 P 0 ;2,4=42,6=0.000000
L 4.10674754 -1.2739188 4.11048002 -1.28267156 0 P 0 ;2,4=42,6=0.000000
L 4.11048002 -1.28267156 4.11141319 -1.29517116 0 P 0 ;2,4=42,6=0.000000
L 4.11141319 -1.29517116 4.11048002 -1.30767077 0 P 0 ;2,4=42,6=0.000000
L 4.11048002 -1.30767077 4.10674754 -1.31642126 0 P 0 ;2,4=42,6=0.000000
L 4.10674754 -1.31642126 4.10208012 -1.32392185 0 P 0 ;2,4=42,6=0.000000
L 4.10208012 -1.32392185 4.09647963 -1.32892087 0 P 0 ;2,4=42,6=0.000000
L 4.09647963 -1.32892087 4.08901289 -1.33266998 0 P 0 ;2,4=42,6=0.000000
L 4.08901289 -1.33266998 4.07034675 -1.33266998 0 P 0 ;2,4=42,6=0.000000
L 4.18454695 -1.33266998 4.14721299 -1.33266998 0 P 0 ;2,4=42,6=0.000000
L 4.14721299 -1.33266998 4.14721299 -1.25766998 0 P 0 ;2,4=42,6=0.000000
L 4.14721299 -1.25766998 4.18454695 -1.25766998 0 P 0 ;2,4=42,6=0.000000
L 4.16961339 -1.29391919 4.14721299 -1.29391919 0 P 0 ;2,4=42,6=0.000000
L 4.22221299 -1.33266998 4.22221299 -1.25766998 0 P 0 ;2,4=42,6=0.000000
L 4.22221299 -1.25766998 4.24554646 -1.25766998 0 P 0 ;2,4=42,6=0.000000
L 4.24554646 -1.25766998 4.25301329 -1.26142156 0 P 0 ;2,4=42,6=0.000000
L 4.25301329 -1.26142156 4.25768061 -1.26642047 0 P 0 ;2,4=42,6=0.000000
L 4.25768061 -1.26642047 4.25954695 -1.27642057 0 P 0 ;2,4=42,6=0.000000
L 4.25954695 -1.27642057 4.25768061 -1.28642077 0 P 0 ;2,4=42,6=0.000000
L 4.25768061 -1.28642077 4.25208012 -1.29266939 0 P 0 ;2,4=42,6=0.000000
L 4.25208012 -1.29266939 4.24554646 -1.29642087 0 P 0 ;2,4=42,6=0.000000
L 4.24554646 -1.29642087 4.22221299 -1.29642087 0 P 0 ;2,4=42,6=0.000000
L 4.24554646 -1.29642087 4.25954695 -1.33266998 0 P 0 ;2,4=42,6=0.000000
L 4.2916125 -1.33266998 4.2916125 -1.25766998 0 P 0 ;2,4=42,6=0.000000
L 4.2916125 -1.25766998 4.31587913 -1.32017037 0 P 0 ;2,4=42,6=0.000000
L 4.31587913 -1.32017037 4.34014744 -1.25766998 0 P 0 ;2,4=42,6=0.000000
L 4.34014744 -1.25766998 4.34014744 -1.33266998 0 P 0 ;2,4=42,6=0.000000
L 4.36754567 -1.33266998 4.39087913 -1.25766998 0 P 0 ;2,4=42,6=0.000000
L 4.39087913 -1.25766998 4.41421427 -1.33266998 0 P 0 ;2,4=42,6=0.000000
L 4.4058127 -1.30642106 4.37594557 -1.30642106 0 P 0 ;2,4=42,6=0.000000
L 4.44627992 -1.32267215 4.45374665 -1.32892087 0 P 0 ;2,4=42,6=0.000000
L 4.45374665 -1.32892087 4.46214656 -1.33266998 0 P 0 ;2,4=42,6=0.000000
L 4.46214656 -1.33266998 4.46961339 -1.33266998 0 P 0 ;2,4=42,6=0.000000
L 4.46961339 -1.33266998 4.47708012 -1.32892087 0 P 0 ;2,4=42,6=0.000000
L 4.47708012 -1.32892087 4.48268061 -1.32267215 0 P 0 ;2,4=42,6=0.000000
L 4.48268061 -1.32267215 4.48548002 -1.31391949 0 P 0 ;2,4=42,6=0.000000
L 4.48548002 -1.31391949 4.48361378 -1.30517136 0 P 0 ;2,4=42,6=0.000000
L 4.48361378 -1.30517136 4.47894646 -1.29767067 0 P 0 ;2,4=42,6=0.000000
L 4.47894646 -1.29767067 4.47054646 -1.29266939 0 P 0 ;2,4=42,6=0.000000
L 4.47054646 -1.29266939 4.45934715 -1.29016998 0 P 0 ;2,4=42,6=0.000000
L 4.45934715 -1.29016998 4.45281348 -1.28517106 0 P 0 ;2,4=42,6=0.000000
L 4.45281348 -1.28517106 4.4500124 -1.27642057 0 P 0 ;2,4=42,6=0.000000
L 4.4500124 -1.27642057 4.45188041 -1.26767018 0 P 0 ;2,4=42,6=0.000000
L 4.45188041 -1.26767018 4.45654606 -1.26142156 0 P 0 ;2,4=42,6=0.000000
L 4.45654606 -1.26142156 4.46307972 -1.25766998 0 P 0 ;2,4=42,6=0.000000
L 4.46307972 -1.25766998 4.46961339 -1.25766998 0 P 0 ;2,4=42,6=0.000000
L 4.46961339 -1.25766998 4.47614705 -1.26016949 0 P 0 ;2,4=42,6=0.000000
L 4.47614705 -1.26016949 4.48174754 -1.26642047 0 P 0 ;2,4=42,6=0.000000
L 4.52034675 -1.33266998 4.52034675 -1.25766998 0 P 0 ;2,4=42,6=0.000000
L 4.5558127 -1.25766998 4.52034675 -1.30392156 0 P 0 ;2,4=42,6=0.000000
L 4.56141319 -1.33266998 4.53621348 -1.28267156 0 P 0 ;2,4=42,6=0.000000
L 4.69834587 -1.29266939 4.70208012 -1.28892018 0 P 0 ;2,4=42,6=0.000000
L 4.70208012 -1.28892018 4.70487953 -1.28267156 0 P 0 ;2,4=42,6=0.000000
L 4.70487953 -1.28267156 4.70674754 -1.2739188 0 P 0 ;2,4=42,6=0.000000
L 4.70674754 -1.2739188 4.70487953 -1.26642047 0 P 0 ;2,4=42,6=0.000000
L 4.70487953 -1.26642047 4.70114705 -1.26142156 0 P 0 ;2,4=42,6=0.000000
L 4.70114705 -1.26142156 4.69461339 -1.25766998 0 P 0 ;2,4=42,6=0.000000
L 4.69461339 -1.25766998 4.66941358 -1.25766998 0 P 0 ;2,4=42,6=0.000000
L 4.66941358 -1.25766998 4.66941358 -1.33266998 0 P 0 ;2,4=42,6=0.000000
L 4.66941358 -1.33266998 4.70021388 -1.33266998 0 P 0 ;2,4=42,6=0.000000
L 4.70021388 -1.33266998 4.70674754 -1.32767106 0 P 0 ;2,4=42,6=0.000000
L 4.70674754 -1.32767106 4.71048002 -1.32017037 0 P 0 ;2,4=42,6=0.000000
L 4.71048002 -1.32017037 4.71234636 -1.31141998 0 P 0 ;2,4=42,6=0.000000
L 4.71234636 -1.31141998 4.71048002 -1.30267185 0 P 0 ;2,4=42,6=0.000000
L 4.71048002 -1.30267185 4.70487953 -1.29517116 0 P 0 ;2,4=42,6=0.000000
L 4.70487953 -1.29517116 4.69834587 -1.29266939 0 P 0 ;2,4=42,6=0.000000
L 4.69834587 -1.29266939 4.66941358 -1.29266939 0 P 0 ;2,4=42,6=0.000000
L 4.76587913 -1.33266998 4.7584123 -1.33142028 0 P 0 ;2,4=42,6=0.000000
L 4.7584123 -1.33142028 4.75188041 -1.32642136 0 P 0 ;2,4=42,6=0.000000
L 4.75188041 -1.32642136 4.74627992 -1.31892067 0 P 0 ;2,4=42,6=0.000000
L 4.74627992 -1.31892067 4.74254567 -1.31017028 0 P 0 ;2,4=42,6=0.000000
L 4.74254567 -1.31017028 4.74067933 -1.30017008 0 P 0 ;2,4=42,6=0.000000
L 4.74067933 -1.30017008 4.74067933 -1.29016998 0 P 0 ;2,4=42,6=0.000000
L 4.74067933 -1.29016998 4.74254567 -1.28016978 0 P 0 ;2,4=42,6=0.000000
L 4.74254567 -1.28016978 4.74627992 -1.27141939 0 P 0 ;2,4=42,6=0.000000
L 4.74627992 -1.27141939 4.75188041 -1.26392096 0 P 0 ;2,4=42,6=0.000000
L 4.75188041 -1.26392096 4.7584123 -1.25891978 0 P 0 ;2,4=42,6=0.000000
L 4.7584123 -1.25891978 4.76587913 -1.25766998 0 P 0 ;2,4=42,6=0.000000
L 4.76587913 -1.25766998 4.77334587 -1.25891978 0 P 0 ;2,4=42,6=0.000000
L 4.77334587 -1.25891978 4.77987953 -1.26392096 0 P 0 ;2,4=42,6=0.000000
L 4.77987953 -1.26392096 4.78548002 -1.27141939 0 P 0 ;2,4=42,6=0.000000
L 4.78548002 -1.27141939 4.78921427 -1.28016978 0 P 0 ;2,4=42,6=0.000000
L 4.78921427 -1.28016978 4.79108061 -1.29016998 0 P 0 ;2,4=42,6=0.000000
L 4.79108061 -1.29016998 4.79108061 -1.30017008 0 P 0 ;2,4=42,6=0.000000
L 4.79108061 -1.30017008 4.78921427 -1.31017028 0 P 0 ;2,4=42,6=0.000000
L 4.78921427 -1.31017028 4.78548002 -1.31892067 0 P 0 ;2,4=42,6=0.000000
L 4.78548002 -1.31892067 4.77987953 -1.32642136 0 P 0 ;2,4=42,6=0.000000
L 4.77987953 -1.32642136 4.77334587 -1.33142028 0 P 0 ;2,4=42,6=0.000000
L 4.77334587 -1.33142028 4.76587913 -1.33266998 0 P 0 ;2,4=42,6=0.000000
L 4.84087913 -1.25766998 4.84087913 -1.33266998 0 P 0 ;2,4=42,6=0.000000
L 4.81941358 -1.25766998 4.86234636 -1.25766998 0 P 0 ;2,4=42,6=0.000000
L 3.36933297 -0.955 3.36933297 -0.88 0 P 0 ;2,4=43,6=0.000000
L 3.36933297 -0.88 3.39173337 -0.88 0 P 0 ;2,4=43,6=0.000000
L 3.39173337 -0.88 3.3992001 -0.88375157 0 P 0 ;2,4=43,6=0.000000
L 3.3992001 -0.88375157 3.40480059 -0.8924997 0 P 0 ;2,4=43,6=0.000000
L 3.40480059 -0.8924997 3.40666693 -0.9024998 0 P 0 ;2,4=43,6=0.000000
L 3.40666693 -0.9024998 3.40480059 -0.9125 0 P 0 ;2,4=43,6=0.000000
L 3.40480059 -0.9125 3.40013327 -0.92000069 0 P 0 ;2,4=43,6=0.000000
L 3.40013327 -0.92000069 3.39173337 -0.92375217 0 P 0 ;2,4=43,6=0.000000
L 3.39173337 -0.92375217 3.36933297 -0.92375217 0 P 0 ;2,4=43,6=0.000000
L 3.44619931 -0.95749941 3.47980059 -0.88 0 P 0 ;2,4=43,6=0.000000
L 3.51653356 -0.955 3.51653356 -0.88 0 P 0 ;2,4=43,6=0.000000
L 3.51653356 -0.88 3.55946634 -0.955 0 P 0 ;2,4=43,6=0.000000
L 3.55946634 -0.955 3.55946634 -0.88 0 P 0 ;2,4=43,6=0.000000
L 3.68799911 -0.95749941 3.68613287 -0.9562497 0 P 0 ;2,4=43,6=0.000000
L 3.68613287 -0.9562497 3.68613287 -0.9537503 0 P 0 ;2,4=43,6=0.000000
L 3.68613287 -0.9537503 3.68799911 -0.95250059 0 P 0 ;2,4=43,6=0.000000
L 3.68799911 -0.95250059 3.68986703 -0.9537503 0 P 0 ;2,4=43,6=0.000000
L 3.68986703 -0.9537503 3.68986703 -0.9562497 0 P 0 ;2,4=43,6=0.000000
L 3.68986703 -0.9562497 3.68799911 -0.95749941 0 P 0 ;2,4=43,6=0.000000
L 3.68799911 -0.92375217 3.68613287 -0.9225001 0 P 0 ;2,4=43,6=0.000000
L 3.68613287 -0.9225001 3.68613287 -0.92000069 0 P 0 ;2,4=43,6=0.000000
L 3.68613287 -0.92000069 3.68799911 -0.91875089 0 P 0 ;2,4=43,6=0.000000
L 3.68799911 -0.91875089 3.68986703 -0.92000069 0 P 0 ;2,4=43,6=0.000000
L 3.68986703 -0.92000069 3.68986703 -0.9225001 0 P 0 ;2,4=43,6=0.000000
L 3.68986703 -0.9225001 3.68799911 -0.92375217 0 P 0 ;2,4=43,6=0.000000
L 3.81933297 -0.955 3.81933297 -0.88 0 P 0 ;2,4=43,6=0.000000
L 3.81933297 -0.88 3.84266644 -0.88 0 P 0 ;2,4=43,6=0.000000
L 3.84266644 -0.88 3.85013327 -0.88375157 0 P 0 ;2,4=43,6=0.000000
L 3.85013327 -0.88375157 3.85480059 -0.88875049 0 P 0 ;2,4=43,6=0.000000
L 3.85480059 -0.88875049 3.85666693 -0.89875059 0 P 0 ;2,4=43,6=0.000000
L 3.85666693 -0.89875059 3.85480059 -0.90875079 0 P 0 ;2,4=43,6=0.000000
L 3.85480059 -0.90875079 3.8492001 -0.91499941 0 P 0 ;2,4=43,6=0.000000
L 3.8492001 -0.91499941 3.84266644 -0.91875089 0 P 0 ;2,4=43,6=0.000000
L 3.84266644 -0.91875089 3.81933297 -0.91875089 0 P 0 ;2,4=43,6=0.000000
L 3.84266644 -0.91875089 3.85666693 -0.955 0 P 0 ;2,4=43,6=0.000000
L 3.9242001 -0.955 3.9242001 -0.88 0 P 0 ;2,4=43,6=0.000000
L 3.9242001 -0.88 3.88966565 -0.93375 0 P 0 ;2,4=43,6=0.000000
L 3.88966565 -0.93375 3.93633425 -0.93375 0 P 0 ;2,4=43,6=0.000000
L 3.98799911 -0.88 3.98053228 -0.88249951 0 P 0 ;2,4=43,6=0.000000
L 3.98053228 -0.88249951 3.97493346 -0.88875049 0 P 0 ;2,4=43,6=0.000000
L 3.97493346 -0.88875049 3.97119931 -0.89624882 0 P 0 ;2,4=43,6=0.000000
L 3.97119931 -0.89624882 3.9683999 -0.90625128 0 P 0 ;2,4=43,6=0.000000
L 3.9683999 -0.90625128 3.96746673 -0.91750118 0 P 0 ;2,4=43,6=0.000000
L 3.96746673 -0.91750118 3.9683999 -0.92875108 0 P 0 ;2,4=43,6=0.000000
L 3.9683999 -0.92875108 3.97119931 -0.93875128 0 P 0 ;2,4=43,6=0.000000
L 3.97119931 -0.93875128 3.97493346 -0.94625187 0 P 0 ;2,4=43,6=0.000000
L 3.97493346 -0.94625187 3.98053228 -0.95250059 0 P 0 ;2,4=43,6=0.000000
L 3.98053228 -0.95250059 3.98799911 -0.955 0 P 0 ;2,4=43,6=0.000000
L 3.98799911 -0.955 3.99546585 -0.95250059 0 P 0 ;2,4=43,6=0.000000
L 3.99546585 -0.95250059 4.00106644 -0.94625187 0 P 0 ;2,4=43,6=0.000000
L 4.00106644 -0.94625187 4.00480059 -0.93875128 0 P 0 ;2,4=43,6=0.000000
L 4.00480059 -0.93875128 4.0076 -0.92875108 0 P 0 ;2,4=43,6=0.000000
L 4.0076 -0.92875108 4.00853317 -0.91750118 0 P 0 ;2,4=43,6=0.000000
L 4.00853317 -0.91750118 4.0076 -0.90625128 0 P 0 ;2,4=43,6=0.000000
L 4.0076 -0.90625128 4.00480059 -0.89624882 0 P 0 ;2,4=43,6=0.000000
L 4.00480059 -0.89624882 4.00106644 -0.88875049 0 P 0 ;2,4=43,6=0.000000
L 4.00106644 -0.88875049 3.99546585 -0.88249951 0 P 0 ;2,4=43,6=0.000000
L 3.99546585 -0.88249951 3.98799911 -0.88 0 P 0 ;2,4=43,6=0.000000
L 4.06299911 -0.88 4.05553228 -0.88249951 0 P 0 ;2,4=43,6=0.000000
L 4.05553228 -0.88249951 4.04993346 -0.88875049 0 P 0 ;2,4=43,6=0.000000
L 4.04993346 -0.88875049 4.04619931 -0.89624882 0 P 0 ;2,4=43,6=0.000000
L 4.04619931 -0.89624882 4.0433999 -0.90625128 0 P 0 ;2,4=43,6=0.000000
L 4.0433999 -0.90625128 4.04246673 -0.91750118 0 P 0 ;2,4=43,6=0.000000
L 4.04246673 -0.91750118 4.0433999 -0.92875108 0 P 0 ;2,4=43,6=0.000000
L 4.0433999 -0.92875108 4.04619931 -0.93875128 0 P 0 ;2,4=43,6=0.000000
L 4.04619931 -0.93875128 4.04993346 -0.94625187 0 P 0 ;2,4=43,6=0.000000
L 4.04993346 -0.94625187 4.05553228 -0.95250059 0 P 0 ;2,4=43,6=0.000000
L 4.05553228 -0.95250059 4.06299911 -0.955 0 P 0 ;2,4=43,6=0.000000
L 4.06299911 -0.955 4.07046585 -0.95250059 0 P 0 ;2,4=43,6=0.000000
L 4.07046585 -0.95250059 4.07606644 -0.94625187 0 P 0 ;2,4=43,6=0.000000
L 4.07606644 -0.94625187 4.07980059 -0.93875128 0 P 0 ;2,4=43,6=0.000000
L 4.07980059 -0.93875128 4.0826 -0.92875108 0 P 0 ;2,4=43,6=0.000000
L 4.0826 -0.92875108 4.08353317 -0.91750118 0 P 0 ;2,4=43,6=0.000000
L 4.08353317 -0.91750118 4.0826 -0.90625128 0 P 0 ;2,4=43,6=0.000000
L 4.0826 -0.90625128 4.07980059 -0.89624882 0 P 0 ;2,4=43,6=0.000000
L 4.07980059 -0.89624882 4.07606644 -0.88875049 0 P 0 ;2,4=43,6=0.000000
L 4.07606644 -0.88875049 4.07046585 -0.88249951 0 P 0 ;2,4=43,6=0.000000
L 4.07046585 -0.88249951 4.06299911 -0.88 0 P 0 ;2,4=43,6=0.000000
L 4.12026614 -0.92375217 4.1267998 -0.91499941 0 P 0 ;2,4=43,6=0.000000
L 4.1267998 -0.91499941 4.1324003 -0.91000049 0 P 0 ;2,4=43,6=0.000000
L 4.1324003 -0.91000049 4.13986703 -0.90750108 0 P 0 ;2,4=43,6=0.000000
L 4.13986703 -0.90750108 4.14640069 -0.91000049 0 P 0 ;2,4=43,6=0.000000
L 4.14640069 -0.91000049 4.15106644 -0.91499941 0 P 0 ;2,4=43,6=0.000000
L 4.15106644 -0.91499941 4.15480059 -0.9225001 0 P 0 ;2,4=43,6=0.000000
L 4.15480059 -0.9225001 4.15573376 -0.93125059 0 P 0 ;2,4=43,6=0.000000
L 4.15573376 -0.93125059 4.15480059 -0.93875128 0 P 0 ;2,4=43,6=0.000000
L 4.15480059 -0.93875128 4.15106644 -0.94625187 0 P 0 ;2,4=43,6=0.000000
L 4.15106644 -0.94625187 4.14546585 -0.95250059 0 P 0 ;2,4=43,6=0.000000
L 4.14546585 -0.95250059 4.13893396 -0.955 0 P 0 ;2,4=43,6=0.000000
L 4.13893396 -0.955 4.13146713 -0.95250059 0 P 0 ;2,4=43,6=0.000000
L 4.13146713 -0.95250059 4.12493346 -0.94500217 0 P 0 ;2,4=43,6=0.000000
L 4.12493346 -0.94500217 4.12119931 -0.93375 0 P 0 ;2,4=43,6=0.000000
L 4.12119931 -0.93375 4.12026614 -0.92125039 0 P 0 ;2,4=43,6=0.000000
L 4.12026614 -0.92125039 4.12213238 -0.90500157 0 P 0 ;2,4=43,6=0.000000
L 4.12213238 -0.90500157 4.12493346 -0.89624882 0 P 0 ;2,4=43,6=0.000000
L 4.12493346 -0.89624882 4.12959921 -0.88750069 0 P 0 ;2,4=43,6=0.000000
L 4.12959921 -0.88750069 4.13613287 -0.8812498 0 P 0 ;2,4=43,6=0.000000
L 4.13613287 -0.8812498 4.14266644 -0.88 0 P 0 ;2,4=43,6=0.000000
L 4.14266644 -0.88 4.1492001 -0.88249951 0 P 0 ;2,4=43,6=0.000000
L 4.1492001 -0.88249951 4.15386752 -0.88875049 0 P 0 ;2,4=43,6=0.000000
L 4.20086663 -0.93000079 4.22513327 -0.93000079 0 P 0 ;2,4=43,6=0.000000
L 4.29546585 -0.91499941 4.2992001 -0.9112502 0 P 0 ;2,4=43,6=0.000000
L 4.2992001 -0.9112502 4.30199951 -0.90500157 0 P 0 ;2,4=43,6=0.000000
L 4.30199951 -0.90500157 4.30386752 -0.89624882 0 P 0 ;2,4=43,6=0.000000
L 4.30386752 -0.89624882 4.30199951 -0.88875049 0 P 0 ;2,4=43,6=0.000000
L 4.30199951 -0.88875049 4.29826703 -0.88375157 0 P 0 ;2,4=43,6=0.000000
L 4.29826703 -0.88375157 4.29173337 -0.88 0 P 0 ;2,4=43,6=0.000000
L 4.29173337 -0.88 4.26653356 -0.88 0 P 0 ;2,4=43,6=0.000000
L 4.26653356 -0.88 4.26653356 -0.955 0 P 0 ;2,4=43,6=0.000000
L 4.26653356 -0.955 4.29733386 -0.955 0 P 0 ;2,4=43,6=0.000000
L 4.29733386 -0.955 4.30386752 -0.95000108 0 P 0 ;2,4=43,6=0.000000
L 4.30386752 -0.95000108 4.3076 -0.94250039 0 P 0 ;2,4=43,6=0.000000
L 4.3076 -0.94250039 4.30946634 -0.93375 0 P 0 ;2,4=43,6=0.000000
L 4.30946634 -0.93375 4.3076 -0.92500187 0 P 0 ;2,4=43,6=0.000000
L 4.3076 -0.92500187 4.30199951 -0.91750118 0 P 0 ;2,4=43,6=0.000000
L 4.30199951 -0.91750118 4.29546585 -0.91499941 0 P 0 ;2,4=43,6=0.000000
L 4.29546585 -0.91499941 4.26653356 -0.91499941 0 P 0 ;2,4=43,6=0.000000
L 4.36299911 -0.88 4.35553228 -0.88249951 0 P 0 ;2,4=43,6=0.000000
L 4.35553228 -0.88249951 4.34993346 -0.88875049 0 P 0 ;2,4=43,6=0.000000
L 4.34993346 -0.88875049 4.34619931 -0.89624882 0 P 0 ;2,4=43,6=0.000000
L 4.34619931 -0.89624882 4.3433999 -0.90625128 0 P 0 ;2,4=43,6=0.000000
L 4.3433999 -0.90625128 4.34246673 -0.91750118 0 P 0 ;2,4=43,6=0.000000
L 4.34246673 -0.91750118 4.3433999 -0.92875108 0 P 0 ;2,4=43,6=0.000000
L 4.3433999 -0.92875108 4.34619931 -0.93875128 0 P 0 ;2,4=43,6=0.000000
L 4.34619931 -0.93875128 4.34993346 -0.94625187 0 P 0 ;2,4=43,6=0.000000
L 4.34993346 -0.94625187 4.35553228 -0.95250059 0 P 0 ;2,4=43,6=0.000000
L 4.35553228 -0.95250059 4.36299911 -0.955 0 P 0 ;2,4=43,6=0.000000
L 4.36299911 -0.955 4.37046585 -0.95250059 0 P 0 ;2,4=43,6=0.000000
L 4.37046585 -0.95250059 4.37606644 -0.94625187 0 P 0 ;2,4=43,6=0.000000
L 4.37606644 -0.94625187 4.37980059 -0.93875128 0 P 0 ;2,4=43,6=0.000000
L 4.37980059 -0.93875128 4.3826 -0.92875108 0 P 0 ;2,4=43,6=0.000000
L 4.3826 -0.92875108 4.38353317 -0.91750118 0 P 0 ;2,4=43,6=0.000000
L 4.38353317 -0.91750118 4.3826 -0.90625128 0 P 0 ;2,4=43,6=0.000000
L 4.3826 -0.90625128 4.37980059 -0.89624882 0 P 0 ;2,4=43,6=0.000000
L 4.37980059 -0.89624882 4.37606644 -0.88875049 0 P 0 ;2,4=43,6=0.000000
L 4.37606644 -0.88875049 4.37046585 -0.88249951 0 P 0 ;2,4=43,6=0.000000
L 4.37046585 -0.88249951 4.36299911 -0.88 0 P 0 ;2,4=43,6=0.000000
L 4.43799911 -0.88 4.43053228 -0.88249951 0 P 0 ;2,4=43,6=0.000000
L 4.43053228 -0.88249951 4.42493346 -0.88875049 0 P 0 ;2,4=43,6=0.000000
L 4.42493346 -0.88875049 4.42119931 -0.89624882 0 P 0 ;2,4=43,6=0.000000
L 4.42119931 -0.89624882 4.4183999 -0.90625128 0 P 0 ;2,4=43,6=0.000000
L 4.4183999 -0.90625128 4.41746673 -0.91750118 0 P 0 ;2,4=43,6=0.000000
L 4.41746673 -0.91750118 4.4183999 -0.92875108 0 P 0 ;2,4=43,6=0.000000
L 4.4183999 -0.92875108 4.42119931 -0.93875128 0 P 0 ;2,4=43,6=0.000000
L 4.42119931 -0.93875128 4.42493346 -0.94625187 0 P 0 ;2,4=43,6=0.000000
L 4.42493346 -0.94625187 4.43053228 -0.95250059 0 P 0 ;2,4=43,6=0.000000
L 4.43053228 -0.95250059 4.43799911 -0.955 0 P 0 ;2,4=43,6=0.000000
L 4.43799911 -0.955 4.44546585 -0.95250059 0 P 0 ;2,4=43,6=0.000000
L 4.44546585 -0.95250059 4.45106644 -0.94625187 0 P 0 ;2,4=43,6=0.000000
L 4.45106644 -0.94625187 4.45480059 -0.93875128 0 P 0 ;2,4=43,6=0.000000
L 4.45480059 -0.93875128 4.4576 -0.92875108 0 P 0 ;2,4=43,6=0.000000
L 4.4576 -0.92875108 4.45853317 -0.91750118 0 P 0 ;2,4=43,6=0.000000
L 4.45853317 -0.91750118 4.4576 -0.90625128 0 P 0 ;2,4=43,6=0.000000
L 4.4576 -0.90625128 4.45480059 -0.89624882 0 P 0 ;2,4=43,6=0.000000
L 4.45480059 -0.89624882 4.45106644 -0.88875049 0 P 0 ;2,4=43,6=0.000000
L 4.45106644 -0.88875049 4.44546585 -0.88249951 0 P 0 ;2,4=43,6=0.000000
L 4.44546585 -0.88249951 4.43799911 -0.88 0 P 0 ;2,4=43,6=0.000000
L 4.51299911 -0.88 4.50553228 -0.88249951 0 P 0 ;2,4=43,6=0.000000
L 4.50553228 -0.88249951 4.49993346 -0.88875049 0 P 0 ;2,4=43,6=0.000000
L 4.49993346 -0.88875049 4.49619931 -0.89624882 0 P 0 ;2,4=43,6=0.000000
L 4.49619931 -0.89624882 4.4933999 -0.90625128 0 P 0 ;2,4=43,6=0.000000
L 4.4933999 -0.90625128 4.49246673 -0.91750118 0 P 0 ;2,4=43,6=0.000000
L 4.49246673 -0.91750118 4.4933999 -0.92875108 0 P 0 ;2,4=43,6=0.000000
L 4.4933999 -0.92875108 4.49619931 -0.93875128 0 P 0 ;2,4=43,6=0.000000
L 4.49619931 -0.93875128 4.49993346 -0.94625187 0 P 0 ;2,4=43,6=0.000000
L 4.49993346 -0.94625187 4.50553228 -0.95250059 0 P 0 ;2,4=43,6=0.000000
L 4.50553228 -0.95250059 4.51299911 -0.955 0 P 0 ;2,4=43,6=0.000000
L 4.51299911 -0.955 4.52046585 -0.95250059 0 P 0 ;2,4=43,6=0.000000
L 4.52046585 -0.95250059 4.52606644 -0.94625187 0 P 0 ;2,4=43,6=0.000000
L 4.52606644 -0.94625187 4.52980059 -0.93875128 0 P 0 ;2,4=43,6=0.000000
L 4.52980059 -0.93875128 4.5326 -0.92875108 0 P 0 ;2,4=43,6=0.000000
L 4.5326 -0.92875108 4.53353317 -0.91750118 0 P 0 ;2,4=43,6=0.000000
L 4.53353317 -0.91750118 4.5326 -0.90625128 0 P 0 ;2,4=43,6=0.000000
L 4.5326 -0.90625128 4.52980059 -0.89624882 0 P 0 ;2,4=43,6=0.000000
L 4.52980059 -0.89624882 4.52606644 -0.88875049 0 P 0 ;2,4=43,6=0.000000
L 4.52606644 -0.88875049 4.52046585 -0.88249951 0 P 0 ;2,4=43,6=0.000000
L 4.52046585 -0.88249951 4.51299911 -0.88 0 P 0 ;2,4=43,6=0.000000
L 4.58799911 -0.955 4.58799911 -0.88 0 P 0 ;2,4=43,6=0.000000
L 4.58799911 -0.88 4.5767998 -0.89499911 0 P 0 ;2,4=43,6=0.000000
L 4.5767998 -0.955 4.59919843 -0.955 0 P 0 ;2,4=43,6=0.000000
L 4.65086663 -0.93000079 4.67513327 -0.93000079 0 P 0 ;2,4=43,6=0.000000
L 4.73799911 -0.88 4.73053228 -0.88249951 0 P 0 ;2,4=43,6=0.000000
L 4.73053228 -0.88249951 4.72493346 -0.88875049 0 P 0 ;2,4=43,6=0.000000
L 4.72493346 -0.88875049 4.72119931 -0.89624882 0 P 0 ;2,4=43,6=0.000000
L 4.72119931 -0.89624882 4.7183999 -0.90625128 0 P 0 ;2,4=43,6=0.000000
L 4.7183999 -0.90625128 4.71746673 -0.91750118 0 P 0 ;2,4=43,6=0.000000
L 4.71746673 -0.91750118 4.7183999 -0.92875108 0 P 0 ;2,4=43,6=0.000000
L 4.7183999 -0.92875108 4.72119931 -0.93875128 0 P 0 ;2,4=43,6=0.000000
L 4.72119931 -0.93875128 4.72493346 -0.94625187 0 P 0 ;2,4=43,6=0.000000
L 4.72493346 -0.94625187 4.73053228 -0.95250059 0 P 0 ;2,4=43,6=0.000000
L 4.73053228 -0.95250059 4.73799911 -0.955 0 P 0 ;2,4=43,6=0.000000
L 4.73799911 -0.955 4.74546585 -0.95250059 0 P 0 ;2,4=43,6=0.000000
L 4.74546585 -0.95250059 4.75106644 -0.94625187 0 P 0 ;2,4=43,6=0.000000
L 4.75106644 -0.94625187 4.75480059 -0.93875128 0 P 0 ;2,4=43,6=0.000000
L 4.75480059 -0.93875128 4.7576 -0.92875108 0 P 0 ;2,4=43,6=0.000000
L 4.7576 -0.92875108 4.75853317 -0.91750118 0 P 0 ;2,4=43,6=0.000000
L 4.75853317 -0.91750118 4.7576 -0.90625128 0 P 0 ;2,4=43,6=0.000000
L 4.7576 -0.90625128 4.75480059 -0.89624882 0 P 0 ;2,4=43,6=0.000000
L 4.75480059 -0.89624882 4.75106644 -0.88875049 0 P 0 ;2,4=43,6=0.000000
L 4.75106644 -0.88875049 4.74546585 -0.88249951 0 P 0 ;2,4=43,6=0.000000
L 4.74546585 -0.88249951 4.73799911 -0.88 0 P 0 ;2,4=43,6=0.000000
L 4.79526614 -0.8924997 4.80086663 -0.88500128 0 P 0 ;2,4=43,6=0.000000
L 4.80086663 -0.88500128 4.8074003 -0.8812498 0 P 0 ;2,4=43,6=0.000000
L 4.8074003 -0.8812498 4.81486703 -0.88 0 P 0 ;2,4=43,6=0.000000
L 4.81486703 -0.88 4.8242001 -0.88249951 0 P 0 ;2,4=43,6=0.000000
L 4.8242001 -0.88249951 4.83073376 -0.88875049 0 P 0 ;2,4=43,6=0.000000
L 4.83073376 -0.88875049 4.8326 -0.89624882 0 P 0 ;2,4=43,6=0.000000
L 4.8326 -0.89624882 4.83166693 -0.90375187 0 P 0 ;2,4=43,6=0.000000
L 4.83166693 -0.90375187 4.82793268 -0.91000049 0 P 0 ;2,4=43,6=0.000000
L 4.82793268 -0.91000049 4.80926654 -0.9225001 0 P 0 ;2,4=43,6=0.000000
L 4.80926654 -0.9225001 4.80086663 -0.93125059 0 P 0 ;2,4=43,6=0.000000
L 4.80086663 -0.93125059 4.79526614 -0.94375246 0 P 0 ;2,4=43,6=0.000000
L 4.79526614 -0.94375246 4.7933999 -0.955 0 P 0 ;2,4=43,6=0.000000
L 4.7933999 -0.955 4.8326 -0.955 0 P 0 ;2,4=43,6=0.000000
L 3.36746673 -1.205 3.36746673 -1.13 0 P 0 ;2,4=44,6=0.000000
L 3.36746673 -1.13 3.38613287 -1.13 0 P 0 ;2,4=44,6=0.000000
L 3.38613287 -1.13 3.39359961 -1.13375157 0 P 0 ;2,4=44,6=0.000000
L 3.39359961 -1.13375157 3.3992001 -1.13875049 0 P 0 ;2,4=44,6=0.000000
L 3.3992001 -1.13875049 3.40386752 -1.14624882 0 P 0 ;2,4=44,6=0.000000
L 3.40386752 -1.14624882 3.4076 -1.15500157 0 P 0 ;2,4=44,6=0.000000
L 3.4076 -1.15500157 3.40853317 -1.16750118 0 P 0 ;2,4=44,6=0.000000
L 3.40853317 -1.16750118 3.4076 -1.18000079 0 P 0 ;2,4=44,6=0.000000
L 3.4076 -1.18000079 3.40386752 -1.18875128 0 P 0 ;2,4=44,6=0.000000
L 3.40386752 -1.18875128 3.3992001 -1.19625187 0 P 0 ;2,4=44,6=0.000000
L 3.3992001 -1.19625187 3.39359961 -1.20125089 0 P 0 ;2,4=44,6=0.000000
L 3.39359961 -1.20125089 3.38613287 -1.205 0 P 0 ;2,4=44,6=0.000000
L 3.38613287 -1.205 3.36746673 -1.205 0 P 0 ;2,4=44,6=0.000000
L 3.47980059 -1.205 3.47980059 -1.15500157 0 P 0 ;2,4=44,6=0.000000
L 3.47980059 -1.1637497 3.47606644 -1.15875079 0 P 0 ;2,4=44,6=0.000000
L 3.47606644 -1.15875079 3.47046585 -1.15625128 0 P 0 ;2,4=44,6=0.000000
L 3.47046585 -1.15625128 3.46393396 -1.15500157 0 P 0 ;2,4=44,6=0.000000
L 3.46393396 -1.15500157 3.4574003 -1.15750108 0 P 0 ;2,4=44,6=0.000000
L 3.4574003 -1.15750108 3.4517998 -1.1625 0 P 0 ;2,4=44,6=0.000000
L 3.4517998 -1.1625 3.44806555 -1.17000069 0 P 0 ;2,4=44,6=0.000000
L 3.44806555 -1.17000069 3.44619931 -1.18000079 0 P 0 ;2,4=44,6=0.000000
L 3.44619931 -1.18000079 3.44806555 -1.19000098 0 P 0 ;2,4=44,6=0.000000
L 3.44806555 -1.19000098 3.4517998 -1.19750167 0 P 0 ;2,4=44,6=0.000000
L 3.4517998 -1.19750167 3.4574003 -1.20250059 0 P 0 ;2,4=44,6=0.000000
L 3.4574003 -1.20250059 3.46393396 -1.205 0 P 0 ;2,4=44,6=0.000000
L 3.46393396 -1.205 3.47046585 -1.2037503 0 P 0 ;2,4=44,6=0.000000
L 3.47046585 -1.2037503 3.47606644 -1.20000108 0 P 0 ;2,4=44,6=0.000000
L 3.47606644 -1.20000108 3.47980059 -1.19500217 0 P 0 ;2,4=44,6=0.000000
L 3.53799911 -1.13 3.53799911 -1.205 0 P 0 ;2,4=44,6=0.000000
L 3.52493346 -1.15500157 3.55106644 -1.15500157 0 P 0 ;2,4=44,6=0.000000
L 3.59900039 -1.17125039 3.62886752 -1.17125039 0 P 0 ;2,4=44,6=0.000000
L 3.62886752 -1.17125039 3.62606644 -1.1625 0 P 0 ;2,4=44,6=0.000000
L 3.62606644 -1.1625 3.62140069 -1.15750108 0 P 0 ;2,4=44,6=0.000000
L 3.62140069 -1.15750108 3.61486703 -1.15500157 0 P 0 ;2,4=44,6=0.000000
L 3.61486703 -1.15500157 3.60833346 -1.15625128 0 P 0 ;2,4=44,6=0.000000
L 3.60833346 -1.15625128 3.60273287 -1.16000049 0 P 0 ;2,4=44,6=0.000000
L 3.60273287 -1.16000049 3.59900039 -1.16875089 0 P 0 ;2,4=44,6=0.000000
L 3.59900039 -1.16875089 3.59713238 -1.17625157 0 P 0 ;2,4=44,6=0.000000
L 3.59713238 -1.17625157 3.59713238 -1.18375 0 P 0 ;2,4=44,6=0.000000
L 3.59713238 -1.18375 3.59900039 -1.19125069 0 P 0 ;2,4=44,6=0.000000
L 3.59900039 -1.19125069 3.60366604 -1.19875138 0 P 0 ;2,4=44,6=0.000000
L 3.60366604 -1.19875138 3.60926654 -1.2037503 0 P 0 ;2,4=44,6=0.000000
L 3.60926654 -1.2037503 3.6158002 -1.205 0 P 0 ;2,4=44,6=0.000000
L 3.6158002 -1.205 3.62233386 -1.20250059 0 P 0 ;2,4=44,6=0.000000
L 3.62233386 -1.20250059 3.62886752 -1.19500217 0 P 0 ;2,4=44,6=0.000000
L 3.68799911 -1.20749941 3.68613287 -1.2062497 0 P 0 ;2,4=44,6=0.000000
L 3.68613287 -1.2062497 3.68613287 -1.2037503 0 P 0 ;2,4=44,6=0.000000
L 3.68613287 -1.2037503 3.68799911 -1.20250059 0 P 0 ;2,4=44,6=0.000000
L 3.68799911 -1.20250059 3.68986703 -1.2037503 0 P 0 ;2,4=44,6=0.000000
L 3.68986703 -1.2037503 3.68986703 -1.2062497 0 P 0 ;2,4=44,6=0.000000
L 3.68986703 -1.2062497 3.68799911 -1.20749941 0 P 0 ;2,4=44,6=0.000000
L 3.68799911 -1.17375217 3.68613287 -1.1725001 0 P 0 ;2,4=44,6=0.000000
L 3.68613287 -1.1725001 3.68613287 -1.17000069 0 P 0 ;2,4=44,6=0.000000
L 3.68613287 -1.17000069 3.68799911 -1.16875089 0 P 0 ;2,4=44,6=0.000000
L 3.68799911 -1.16875089 3.68986703 -1.17000069 0 P 0 ;2,4=44,6=0.000000
L 3.68986703 -1.17000069 3.68986703 -1.1725001 0 P 0 ;2,4=44,6=0.000000
L 3.68986703 -1.1725001 3.68799911 -1.17375217 0 P 0 ;2,4=44,6=0.000000
L 3.82026614 -1.1424997 3.82586663 -1.13500128 0 P 0 ;2,4=44,6=0.000000
L 3.82586663 -1.13500128 3.8324003 -1.1312498 0 P 0 ;2,4=44,6=0.000000
L 3.8324003 -1.1312498 3.83986703 -1.13 0 P 0 ;2,4=44,6=0.000000
L 3.83986703 -1.13 3.8492001 -1.13249951 0 P 0 ;2,4=44,6=0.000000
L 3.8492001 -1.13249951 3.85573376 -1.13875049 0 P 0 ;2,4=44,6=0.000000
L 3.85573376 -1.13875049 3.8576 -1.14624882 0 P 0 ;2,4=44,6=0.000000
L 3.8576 -1.14624882 3.85666693 -1.15375187 0 P 0 ;2,4=44,6=0.000000
L 3.85666693 -1.15375187 3.85293268 -1.16000049 0 P 0 ;2,4=44,6=0.000000
L 3.85293268 -1.16000049 3.83426654 -1.1725001 0 P 0 ;2,4=44,6=0.000000
L 3.83426654 -1.1725001 3.82586663 -1.18125059 0 P 0 ;2,4=44,6=0.000000
L 3.82586663 -1.18125059 3.82026614 -1.19375246 0 P 0 ;2,4=44,6=0.000000
L 3.82026614 -1.19375246 3.8183999 -1.205 0 P 0 ;2,4=44,6=0.000000
L 3.8183999 -1.205 3.8576 -1.205 0 P 0 ;2,4=44,6=0.000000
L 3.91299911 -1.13 3.90553228 -1.13249951 0 P 0 ;2,4=44,6=0.000000
L 3.90553228 -1.13249951 3.89993346 -1.13875049 0 P 0 ;2,4=44,6=0.000000
L 3.89993346 -1.13875049 3.89619931 -1.14624882 0 P 0 ;2,4=44,6=0.000000
L 3.89619931 -1.14624882 3.8933999 -1.15625128 0 P 0 ;2,4=44,6=0.000000
L 3.8933999 -1.15625128 3.89246673 -1.16750118 0 P 0 ;2,4=44,6=0.000000
L 3.89246673 -1.16750118 3.8933999 -1.17875108 0 P 0 ;2,4=44,6=0.000000
L 3.8933999 -1.17875108 3.89619931 -1.18875128 0 P 0 ;2,4=44,6=0.000000
L 3.89619931 -1.18875128 3.89993346 -1.19625187 0 P 0 ;2,4=44,6=0.000000
L 3.89993346 -1.19625187 3.90553228 -1.20250059 0 P 0 ;2,4=44,6=0.000000
L 3.90553228 -1.20250059 3.91299911 -1.205 0 P 0 ;2,4=44,6=0.000000
L 3.91299911 -1.205 3.92046585 -1.20250059 0 P 0 ;2,4=44,6=0.000000
L 3.92046585 -1.20250059 3.92606644 -1.19625187 0 P 0 ;2,4=44,6=0.000000
L 3.92606644 -1.19625187 3.92980059 -1.18875128 0 P 0 ;2,4=44,6=0.000000
L 3.92980059 -1.18875128 3.9326 -1.17875108 0 P 0 ;2,4=44,6=0.000000
L 3.9326 -1.17875108 3.93353317 -1.16750118 0 P 0 ;2,4=44,6=0.000000
L 3.93353317 -1.16750118 3.9326 -1.15625128 0 P 0 ;2,4=44,6=0.000000
L 3.9326 -1.15625128 3.92980059 -1.14624882 0 P 0 ;2,4=44,6=0.000000
L 3.92980059 -1.14624882 3.92606644 -1.13875049 0 P 0 ;2,4=44,6=0.000000
L 3.92606644 -1.13875049 3.92046585 -1.13249951 0 P 0 ;2,4=44,6=0.000000
L 3.92046585 -1.13249951 3.91299911 -1.13 0 P 0 ;2,4=44,6=0.000000
L 3.97026614 -1.1424997 3.97586663 -1.13500128 0 P 0 ;2,4=44,6=0.000000
L 3.97586663 -1.13500128 3.9824003 -1.1312498 0 P 0 ;2,4=44,6=0.000000
L 3.9824003 -1.1312498 3.98986703 -1.13 0 P 0 ;2,4=44,6=0.000000
L 3.98986703 -1.13 3.9992001 -1.13249951 0 P 0 ;2,4=44,6=0.000000
L 3.9992001 -1.13249951 4.00573376 -1.13875049 0 P 0 ;2,4=44,6=0.000000
L 4.00573376 -1.13875049 4.0076 -1.14624882 0 P 0 ;2,4=44,6=0.000000
L 4.0076 -1.14624882 4.00666693 -1.15375187 0 P 0 ;2,4=44,6=0.000000
L 4.00666693 -1.15375187 4.00293268 -1.16000049 0 P 0 ;2,4=44,6=0.000000
L 4.00293268 -1.16000049 3.98426654 -1.1725001 0 P 0 ;2,4=44,6=0.000000
L 3.98426654 -1.1725001 3.97586663 -1.18125059 0 P 0 ;2,4=44,6=0.000000
L 3.97586663 -1.18125059 3.97026614 -1.19375246 0 P 0 ;2,4=44,6=0.000000
L 3.97026614 -1.19375246 3.9683999 -1.205 0 P 0 ;2,4=44,6=0.000000
L 3.9683999 -1.205 4.0076 -1.205 0 P 0 ;2,4=44,6=0.000000
L 4.04526614 -1.1424997 4.05086663 -1.13500128 0 P 0 ;2,4=44,6=0.000000
L 4.05086663 -1.13500128 4.0574003 -1.1312498 0 P 0 ;2,4=44,6=0.000000
L 4.0574003 -1.1312498 4.06486703 -1.13 0 P 0 ;2,4=44,6=0.000000
L 4.06486703 -1.13 4.0742001 -1.13249951 0 P 0 ;2,4=44,6=0.000000
L 4.0742001 -1.13249951 4.08073376 -1.13875049 0 P 0 ;2,4=44,6=0.000000
L 4.08073376 -1.13875049 4.0826 -1.14624882 0 P 0 ;2,4=44,6=0.000000
L 4.0826 -1.14624882 4.08166693 -1.15375187 0 P 0 ;2,4=44,6=0.000000
L 4.08166693 -1.15375187 4.07793268 -1.16000049 0 P 0 ;2,4=44,6=0.000000
L 4.07793268 -1.16000049 4.05926654 -1.1725001 0 P 0 ;2,4=44,6=0.000000
L 4.05926654 -1.1725001 4.05086663 -1.18125059 0 P 0 ;2,4=44,6=0.000000
L 4.05086663 -1.18125059 4.04526614 -1.19375246 0 P 0 ;2,4=44,6=0.000000
L 4.04526614 -1.19375246 4.0433999 -1.205 0 P 0 ;2,4=44,6=0.000000
L 4.0433999 -1.205 4.0826 -1.205 0 P 0 ;2,4=44,6=0.000000
L 4.12586663 -1.18000079 4.15013327 -1.18000079 0 P 0 ;2,4=44,6=0.000000
L 4.21299911 -1.13 4.20553228 -1.13249951 0 P 0 ;2,4=44,6=0.000000
L 4.20553228 -1.13249951 4.19993346 -1.13875049 0 P 0 ;2,4=44,6=0.000000
L 4.19993346 -1.13875049 4.19619931 -1.14624882 0 P 0 ;2,4=44,6=0.000000
L 4.19619931 -1.14624882 4.1933999 -1.15625128 0 P 0 ;2,4=44,6=0.000000
L 4.1933999 -1.15625128 4.19246673 -1.16750118 0 P 0 ;2,4=44,6=0.000000
L 4.19246673 -1.16750118 4.1933999 -1.17875108 0 P 0 ;2,4=44,6=0.000000
L 4.1933999 -1.17875108 4.19619931 -1.18875128 0 P 0 ;2,4=44,6=0.000000
L 4.19619931 -1.18875128 4.19993346 -1.19625187 0 P 0 ;2,4=44,6=0.000000
L 4.19993346 -1.19625187 4.20553228 -1.20250059 0 P 0 ;2,4=44,6=0.000000
L 4.20553228 -1.20250059 4.21299911 -1.205 0 P 0 ;2,4=44,6=0.000000
L 4.21299911 -1.205 4.22046585 -1.20250059 0 P 0 ;2,4=44,6=0.000000
L 4.22046585 -1.20250059 4.22606644 -1.19625187 0 P 0 ;2,4=44,6=0.000000
L 4.22606644 -1.19625187 4.22980059 -1.18875128 0 P 0 ;2,4=44,6=0.000000
L 4.22980059 -1.18875128 4.2326 -1.17875108 0 P 0 ;2,4=44,6=0.000000
L 4.2326 -1.17875108 4.23353317 -1.16750118 0 P 0 ;2,4=44,6=0.000000
L 4.23353317 -1.16750118 4.2326 -1.15625128 0 P 0 ;2,4=44,6=0.000000
L 4.2326 -1.15625128 4.22980059 -1.14624882 0 P 0 ;2,4=44,6=0.000000
L 4.22980059 -1.14624882 4.22606644 -1.13875049 0 P 0 ;2,4=44,6=0.000000
L 4.22606644 -1.13875049 4.22046585 -1.13249951 0 P 0 ;2,4=44,6=0.000000
L 4.22046585 -1.13249951 4.21299911 -1.13 0 P 0 ;2,4=44,6=0.000000
L 4.27026614 -1.1424997 4.27586663 -1.13500128 0 P 0 ;2,4=44,6=0.000000
L 4.27586663 -1.13500128 4.2824003 -1.1312498 0 P 0 ;2,4=44,6=0.000000
L 4.2824003 -1.1312498 4.28986703 -1.13 0 P 0 ;2,4=44,6=0.000000
L 4.28986703 -1.13 4.2992001 -1.13249951 0 P 0 ;2,4=44,6=0.000000
L 4.2992001 -1.13249951 4.30573376 -1.13875049 0 P 0 ;2,4=44,6=0.000000
L 4.30573376 -1.13875049 4.3076 -1.14624882 0 P 0 ;2,4=44,6=0.000000
L 4.3076 -1.14624882 4.30666693 -1.15375187 0 P 0 ;2,4=44,6=0.000000
L 4.30666693 -1.15375187 4.30293268 -1.16000049 0 P 0 ;2,4=44,6=0.000000
L 4.30293268 -1.16000049 4.28426654 -1.1725001 0 P 0 ;2,4=44,6=0.000000
L 4.28426654 -1.1725001 4.27586663 -1.18125059 0 P 0 ;2,4=44,6=0.000000
L 4.27586663 -1.18125059 4.27026614 -1.19375246 0 P 0 ;2,4=44,6=0.000000
L 4.27026614 -1.19375246 4.2683999 -1.205 0 P 0 ;2,4=44,6=0.000000
L 4.2683999 -1.205 4.3076 -1.205 0 P 0 ;2,4=44,6=0.000000
L 4.35086663 -1.18000079 4.37513327 -1.18000079 0 P 0 ;2,4=44,6=0.000000
L 4.42026614 -1.1424997 4.42586663 -1.13500128 0 P 0 ;2,4=44,6=0.000000
L 4.42586663 -1.13500128 4.4324003 -1.1312498 0 P 0 ;2,4=44,6=0.000000
L 4.4324003 -1.1312498 4.43986703 -1.13 0 P 0 ;2,4=44,6=0.000000
L 4.43986703 -1.13 4.4492001 -1.13249951 0 P 0 ;2,4=44,6=0.000000
L 4.4492001 -1.13249951 4.45573376 -1.13875049 0 P 0 ;2,4=44,6=0.000000
L 4.45573376 -1.13875049 4.4576 -1.14624882 0 P 0 ;2,4=44,6=0.000000
L 4.4576 -1.14624882 4.45666693 -1.15375187 0 P 0 ;2,4=44,6=0.000000
L 4.45666693 -1.15375187 4.45293268 -1.16000049 0 P 0 ;2,4=44,6=0.000000
L 4.45293268 -1.16000049 4.43426654 -1.1725001 0 P 0 ;2,4=44,6=0.000000
L 4.43426654 -1.1725001 4.42586663 -1.18125059 0 P 0 ;2,4=44,6=0.000000
L 4.42586663 -1.18125059 4.42026614 -1.19375246 0 P 0 ;2,4=44,6=0.000000
L 4.42026614 -1.19375246 4.4183999 -1.205 0 P 0 ;2,4=44,6=0.000000
L 4.4183999 -1.205 4.4576 -1.205 0 P 0 ;2,4=44,6=0.000000
L 4.49246673 -1.19375246 4.49806555 -1.20000108 0 P 0 ;2,4=44,6=0.000000
L 4.49806555 -1.20000108 4.50459921 -1.2037503 0 P 0 ;2,4=44,6=0.000000
L 4.50459921 -1.2037503 4.51299911 -1.205 0 P 0 ;2,4=44,6=0.000000
L 4.51299911 -1.205 4.52140069 -1.20250059 0 P 0 ;2,4=44,6=0.000000
L 4.52140069 -1.20250059 4.52793268 -1.19750167 0 P 0 ;2,4=44,6=0.000000
L 4.52793268 -1.19750167 4.5326 -1.18875128 0 P 0 ;2,4=44,6=0.000000
L 4.5326 -1.18875128 4.53353317 -1.17875108 0 P 0 ;2,4=44,6=0.000000
L 4.53353317 -1.17875108 4.53166693 -1.16875089 0 P 0 ;2,4=44,6=0.000000
L 4.53166693 -1.16875089 4.52699951 -1.1625 0 P 0 ;2,4=44,6=0.000000
L 4.52699951 -1.1625 4.52046585 -1.15750108 0 P 0 ;2,4=44,6=0.000000
L 4.52046585 -1.15750108 4.51393396 -1.15625128 0 P 0 ;2,4=44,6=0.000000
L 4.51393396 -1.15625128 4.5074003 -1.15750108 0 P 0 ;2,4=44,6=0.000000
L 4.5074003 -1.15750108 4.49900039 -1.1625 0 P 0 ;2,4=44,6=0.000000
L 4.49900039 -1.1625 4.5017998 -1.13 0 P 0 ;2,4=44,6=0.000000
L 4.5017998 -1.13 4.52699951 -1.13 0 P 0 ;2,4=44,6=0.000000
L 3.29433297 -1.255 3.29433297 -1.33 0 P 0 ;2,4=45,6=0.000000
L 3.29433297 -1.33 3.33166693 -1.33 0 P 0 ;2,4=45,6=0.000000
L 3.40480059 -1.33 3.40480059 -1.28000157 0 P 0 ;2,4=45,6=0.000000
L 3.40480059 -1.2887497 3.40106644 -1.28375079 0 P 0 ;2,4=45,6=0.000000
L 3.40106644 -1.28375079 3.39546585 -1.28125128 0 P 0 ;2,4=45,6=0.000000
L 3.39546585 -1.28125128 3.38893396 -1.28000157 0 P 0 ;2,4=45,6=0.000000
L 3.38893396 -1.28000157 3.3824003 -1.28250108 0 P 0 ;2,4=45,6=0.000000
L 3.3824003 -1.28250108 3.3767998 -1.2875 0 P 0 ;2,4=45,6=0.000000
L 3.3767998 -1.2875 3.37306555 -1.29500069 0 P 0 ;2,4=45,6=0.000000
L 3.37306555 -1.29500069 3.37119931 -1.30500079 0 P 0 ;2,4=45,6=0.000000
L 3.37119931 -1.30500079 3.37306555 -1.31500098 0 P 0 ;2,4=45,6=0.000000
L 3.37306555 -1.31500098 3.3767998 -1.32250167 0 P 0 ;2,4=45,6=0.000000
L 3.3767998 -1.32250167 3.3824003 -1.32750059 0 P 0 ;2,4=45,6=0.000000
L 3.3824003 -1.32750059 3.38893396 -1.33 0 P 0 ;2,4=45,6=0.000000
L 3.38893396 -1.33 3.39546585 -1.3287503 0 P 0 ;2,4=45,6=0.000000
L 3.39546585 -1.3287503 3.40106644 -1.32500108 0 P 0 ;2,4=45,6=0.000000
L 3.40106644 -1.32500108 3.40480059 -1.32000217 0 P 0 ;2,4=45,6=0.000000
L 3.4433999 -1.3524997 3.44900039 -1.35499921 0 P 0 ;2,4=45,6=0.000000
L 3.44900039 -1.35499921 3.45646713 -1.3524997 0 P 0 ;2,4=45,6=0.000000
L 3.45646713 -1.3524997 3.46113287 -1.34750079 0 P 0 ;2,4=45,6=0.000000
L 3.46113287 -1.34750079 3.46486703 -1.3412498 0 P 0 ;2,4=45,6=0.000000
L 3.46486703 -1.3412498 3.47046585 -1.32125187 0 P 0 ;2,4=45,6=0.000000
L 3.47046585 -1.32125187 3.4826 -1.28000157 0 P 0 ;2,4=45,6=0.000000
L 3.45273287 -1.28000157 3.47046585 -1.32125187 0 P 0 ;2,4=45,6=0.000000
L 3.52400039 -1.29625039 3.55386752 -1.29625039 0 P 0 ;2,4=45,6=0.000000
L 3.55386752 -1.29625039 3.55106644 -1.2875 0 P 0 ;2,4=45,6=0.000000
L 3.55106644 -1.2875 3.54640069 -1.28250108 0 P 0 ;2,4=45,6=0.000000
L 3.54640069 -1.28250108 3.53986703 -1.28000157 0 P 0 ;2,4=45,6=0.000000
L 3.53986703 -1.28000157 3.53333346 -1.28125128 0 P 0 ;2,4=45,6=0.000000
L 3.53333346 -1.28125128 3.52773287 -1.28500049 0 P 0 ;2,4=45,6=0.000000
L 3.52773287 -1.28500049 3.52400039 -1.29375089 0 P 0 ;2,4=45,6=0.000000
L 3.52400039 -1.29375089 3.52213238 -1.30125157 0 P 0 ;2,4=45,6=0.000000
L 3.52213238 -1.30125157 3.52213238 -1.30875 0 P 0 ;2,4=45,6=0.000000
L 3.52213238 -1.30875 3.52400039 -1.31625069 0 P 0 ;2,4=45,6=0.000000
L 3.52400039 -1.31625069 3.52866604 -1.32375138 0 P 0 ;2,4=45,6=0.000000
L 3.52866604 -1.32375138 3.53426654 -1.3287503 0 P 0 ;2,4=45,6=0.000000
L 3.53426654 -1.3287503 3.5408002 -1.33 0 P 0 ;2,4=45,6=0.000000
L 3.5408002 -1.33 3.54733386 -1.32750059 0 P 0 ;2,4=45,6=0.000000
L 3.54733386 -1.32750059 3.55386752 -1.32000217 0 P 0 ;2,4=45,6=0.000000
L 3.59993346 -1.33 3.59993346 -1.28000157 0 P 0 ;2,4=45,6=0.000000
L 3.59993346 -1.28999941 3.60459921 -1.28500049 0 P 0 ;2,4=45,6=0.000000
L 3.60459921 -1.28500049 3.60926654 -1.28125128 0 P 0 ;2,4=45,6=0.000000
L 3.60926654 -1.28125128 3.6158002 -1.28000157 0 P 0 ;2,4=45,6=0.000000
L 3.6158002 -1.28000157 3.62046585 -1.28125128 0 P 0 ;2,4=45,6=0.000000
L 3.62046585 -1.28125128 3.62606644 -1.28500049 0 P 0 ;2,4=45,6=0.000000
L 3.68799911 -1.33249941 3.68613287 -1.3312497 0 P 0 ;2,4=45,6=0.000000
L 3.68613287 -1.3312497 3.68613287 -1.3287503 0 P 0 ;2,4=45,6=0.000000
L 3.68613287 -1.3287503 3.68799911 -1.32750059 0 P 0 ;2,4=45,6=0.000000
L 3.68799911 -1.32750059 3.68986703 -1.3287503 0 P 0 ;2,4=45,6=0.000000
L 3.68986703 -1.3287503 3.68986703 -1.3312497 0 P 0 ;2,4=45,6=0.000000
L 3.68986703 -1.3312497 3.68799911 -1.33249941 0 P 0 ;2,4=45,6=0.000000
L 3.68799911 -1.29875217 3.68613287 -1.2975001 0 P 0 ;2,4=45,6=0.000000
L 3.68613287 -1.2975001 3.68613287 -1.29500069 0 P 0 ;2,4=45,6=0.000000
L 3.68613287 -1.29500069 3.68799911 -1.29375089 0 P 0 ;2,4=45,6=0.000000
L 3.68799911 -1.29375089 3.68986703 -1.29500069 0 P 0 ;2,4=45,6=0.000000
L 3.68986703 -1.29500069 3.68986703 -1.2975001 0 P 0 ;2,4=45,6=0.000000
L 3.68986703 -1.2975001 3.68799911 -1.29875217 0 P 0 ;2,4=45,6=0.000000
L 3.36933297 -1.08 3.36933297 -1.005 0 P 0 ;2,4=46,6=0.000000
L 3.36933297 -1.005 3.39266644 -1.005 0 P 0 ;2,4=46,6=0.000000
L 3.39266644 -1.005 3.40013327 -1.00875157 0 P 0 ;2,4=46,6=0.000000
L 3.40013327 -1.00875157 3.40480059 -1.01375049 0 P 0 ;2,4=46,6=0.000000
L 3.40480059 -1.01375049 3.40666693 -1.02375059 0 P 0 ;2,4=46,6=0.000000
L 3.40666693 -1.02375059 3.40480059 -1.03375079 0 P 0 ;2,4=46,6=0.000000
L 3.40480059 -1.03375079 3.3992001 -1.03999941 0 P 0 ;2,4=46,6=0.000000
L 3.3992001 -1.03999941 3.39266644 -1.04375089 0 P 0 ;2,4=46,6=0.000000
L 3.39266644 -1.04375089 3.36933297 -1.04375089 0 P 0 ;2,4=46,6=0.000000
L 3.39266644 -1.04375089 3.40666693 -1.08 0 P 0 ;2,4=46,6=0.000000
L 3.44900039 -1.04625039 3.47886752 -1.04625039 0 P 0 ;2,4=46,6=0.000000
L 3.47886752 -1.04625039 3.47606644 -1.0375 0 P 0 ;2,4=46,6=0.000000
L 3.47606644 -1.0375 3.47140069 -1.03250108 0 P 0 ;2,4=46,6=0.000000
L 3.47140069 -1.03250108 3.46486703 -1.03000157 0 P 0 ;2,4=46,6=0.000000
L 3.46486703 -1.03000157 3.45833346 -1.03125128 0 P 0 ;2,4=46,6=0.000000
L 3.45833346 -1.03125128 3.45273287 -1.03500049 0 P 0 ;2,4=46,6=0.000000
L 3.45273287 -1.03500049 3.44900039 -1.04375089 0 P 0 ;2,4=46,6=0.000000
L 3.44900039 -1.04375089 3.44713238 -1.05125157 0 P 0 ;2,4=46,6=0.000000
L 3.44713238 -1.05125157 3.44713238 -1.05875 0 P 0 ;2,4=46,6=0.000000
L 3.44713238 -1.05875 3.44900039 -1.06625069 0 P 0 ;2,4=46,6=0.000000
L 3.44900039 -1.06625069 3.45366604 -1.07375138 0 P 0 ;2,4=46,6=0.000000
L 3.45366604 -1.07375138 3.45926654 -1.0787503 0 P 0 ;2,4=46,6=0.000000
L 3.45926654 -1.0787503 3.4658002 -1.08 0 P 0 ;2,4=46,6=0.000000
L 3.4658002 -1.08 3.47233386 -1.07750059 0 P 0 ;2,4=46,6=0.000000
L 3.47233386 -1.07750059 3.47886752 -1.07000217 0 P 0 ;2,4=46,6=0.000000
L 3.52119931 -1.03000157 3.53799911 -1.08 0 P 0 ;2,4=46,6=0.000000
L 3.53799911 -1.08 3.55480059 -1.03000157 0 P 0 ;2,4=46,6=0.000000
L 3.68799911 -1.08249941 3.68613287 -1.0812497 0 P 0 ;2,4=46,6=0.000000
L 3.68613287 -1.0812497 3.68613287 -1.0787503 0 P 0 ;2,4=46,6=0.000000
L 3.68613287 -1.0787503 3.68799911 -1.07750059 0 P 0 ;2,4=46,6=0.000000
L 3.68799911 -1.07750059 3.68986703 -1.0787503 0 P 0 ;2,4=46,6=0.000000
L 3.68986703 -1.0787503 3.68986703 -1.0812497 0 P 0 ;2,4=46,6=0.000000
L 3.68986703 -1.0812497 3.68799911 -1.08249941 0 P 0 ;2,4=46,6=0.000000
L 3.68799911 -1.04875217 3.68613287 -1.0475001 0 P 0 ;2,4=46,6=0.000000
L 3.68613287 -1.0475001 3.68613287 -1.04500069 0 P 0 ;2,4=46,6=0.000000
L 3.68613287 -1.04500069 3.68799911 -1.04375089 0 P 0 ;2,4=46,6=0.000000
L 3.68799911 -1.04375089 3.68986703 -1.04500069 0 P 0 ;2,4=46,6=0.000000
L 3.68986703 -1.04500069 3.68986703 -1.0475001 0 P 0 ;2,4=46,6=0.000000
L 3.68986703 -1.0475001 3.68799911 -1.04875217 0 P 0 ;2,4=46,6=0.000000
L 3.83799911 -1.005 3.83053228 -1.00749951 0 P 0 ;2,4=46,6=0.000000
L 3.83053228 -1.00749951 3.82493346 -1.01375049 0 P 0 ;2,4=46,6=0.000000
L 3.82493346 -1.01375049 3.82119931 -1.02124882 0 P 0 ;2,4=46,6=0.000000
L 3.82119931 -1.02124882 3.8183999 -1.03125128 0 P 0 ;2,4=46,6=0.000000
L 3.8183999 -1.03125128 3.81746673 -1.04250118 0 P 0 ;2,4=46,6=0.000000
L 3.81746673 -1.04250118 3.8183999 -1.05375108 0 P 0 ;2,4=46,6=0.000000
L 3.8183999 -1.05375108 3.82119931 -1.06375128 0 P 0 ;2,4=46,6=0.000000
L 3.82119931 -1.06375128 3.82493346 -1.07125187 0 P 0 ;2,4=46,6=0.000000
L 3.82493346 -1.07125187 3.83053228 -1.07750059 0 P 0 ;2,4=46,6=0.000000
L 3.83053228 -1.07750059 3.83799911 -1.08 0 P 0 ;2,4=46,6=0.000000
L 3.83799911 -1.08 3.84546585 -1.07750059 0 P 0 ;2,4=46,6=0.000000
L 3.84546585 -1.07750059 3.85106644 -1.07125187 0 P 0 ;2,4=46,6=0.000000
L 3.85106644 -1.07125187 3.85480059 -1.06375128 0 P 0 ;2,4=46,6=0.000000
L 3.85480059 -1.06375128 3.8576 -1.05375108 0 P 0 ;2,4=46,6=0.000000
L 3.8576 -1.05375108 3.85853317 -1.04250118 0 P 0 ;2,4=46,6=0.000000
L 3.85853317 -1.04250118 3.8576 -1.03125128 0 P 0 ;2,4=46,6=0.000000
L 3.8576 -1.03125128 3.85480059 -1.02124882 0 P 0 ;2,4=46,6=0.000000
L 3.85480059 -1.02124882 3.85106644 -1.01375049 0 P 0 ;2,4=46,6=0.000000
L 3.85106644 -1.01375049 3.84546585 -1.00749951 0 P 0 ;2,4=46,6=0.000000
L 3.84546585 -1.00749951 3.83799911 -1.005 0 P 0 ;2,4=46,6=0.000000
L 3.91299911 -1.08 3.91299911 -1.005 0 P 0 ;2,4=46,6=0.000000
L 3.91299911 -1.005 3.9017998 -1.01999911 0 P 0 ;2,4=46,6=0.000000
L 3.9017998 -1.08 3.92419843 -1.08 0 P 0 ;2,4=46,6=0.000000
S P 0
OB 2.807669980315 1.121430019685 I
OC 2.807669980315 1.121430019685 2.685669980315 1.121430019685 Y
OE
SE
S P 0
OB 2.807669980315 2.559430019685 I
OC 2.807669980315 2.559430019685 2.685669980315 2.559430019685 Y
OE
SE
S P 0
OB 1.582669980315 2.680430019685 I
OC 1.582669980315 2.680430019685 1.460669980315 2.680430019685 Y
OE
SE
S P 0
OB 1.557669980315 1.060430019685 I
OC 1.557669980315 1.060430019685 1.435669980315 1.060430019685 Y
OE
SE
S P 0
OB 6.52038996063 0.65353996063 I
OC 6.52038996063 0.65353996063 6.40038996063 0.65353996063 Y
OE
SE
S P 0
OB 0.415280019685 3.73031003937 I
OC 0.415280019685 3.73031003937 0.295280019685 3.73031003937 Y
OE
SE
S P 0
OB 0.415280019685 0.36811003937 I
OC 0.415280019685 0.36811003937 0.295280019685 0.36811003937 Y
OE
SE
S P 0
OB 6.52038996063 4.17835 I
OC 6.52038996063 4.17835 6.40038996063 4.17835 Y
OE
SE
S P 0
OB 1.638 4.045 I
OS 1.638 4.017
OS 1.624 4.017
OS 1.624 4.045
OS 1.638 4.045
OE
SE
P 3.368 3.947 22 P 0 8 0
P 5.64 2.17 26 P 0 8 0
S P 0
OB 5.6355 2.363430019685 I
OS 5.6545 2.363430019685
OS 5.6545 2.326569980315
OS 5.6355 2.326569980315
OS 5.6355 2.363430019685
OE
SE
S P 0
OB 1.792 -0.00018996063 I
OS 1.772 0.01981003937
OS 1.772 0.22231003937
OS 3.122 0.22231003937
OS 3.122 0.01981003937
OS 3.102 -0.00018996063
OS 1.792 -0.00018996063
OE
SE

### steps/pcb/layers/smt/features
#
#Num Features
#
F 5026

#
#Units
#
U INCH

#
#Feature symbol names
#
$0 r5
$1 r10
$2 r12
$3 r14
$4 r23.6
$5 r28
$6 r40
$7 r61
$8 r90
$9 r94
$10 r104
$11 r108
$12 r110
$13 r120
$14 r128
$15 r135
$16 r248
$17 s1
$18 s24
$19 s35
$20 s108
$21 oval79x39 I
$22 rect100x150 I
$23 rect108x49 I
$24 rect110x12 I
$25 rect12x110 I
$26 rect12x57 I
$27 rect142x120 I
$28 rect144x54 I
$29 rect14x27 I
$30 rect14x28 I
$31 rect150x100 I
$32 rect15x18 I
$33 rect16x19 I
$34 rect16x28 I
$35 rect16x42 I
$36 rect16x45 I
$37 rect16x49 I
$38 rect16x50 I
$39 rect16x53 I
$40 rect16x68 I
$41 rect17x48 I
$42 rect18x15 I
$43 rect18x66 I
$44 rect19x16 I
$45 rect19x36.86 I
$46 rect20x49 I
$47 rect21x28 I
$48 rect22x64 I
$49 rect24x22 I
$50 rect24x28 I
$51 rect24x51 I
$52 rect28x14 I
$53 rect28x16 I
$54 rect28x24 I
$55 rect28x32 I
$56 rect29x39 I
$57 rect31x14 I
$58 rect32x130 I
$59 rect32x169 I
$60 rect32x28 I
$61 rect34x38 I
$62 rect36.86x19 I
$63 rect37x16 I
$64 rect37x21 I
$65 rect38x34 I
$66 rect39x37 I
$67 rect41x12 I
$68 rect42x17 I
$69 rect42x58 I
$70 rect43x45 I
$71 rect43x59 I
$72 rect43x61 I
$73 rect45x16 I
$74 rect45x91 I
$75 rect47x61 I
$76 rect49x108 I
$77 rect49x16 I
$78 rect49x20 I
$79 rect50x16 I
$80 rect51x16 I
$81 rect51x24 I
$82 rect53x16 I
$83 rect54x144 I
$84 rect57x20 I
$85 rect58x42 I
$86 rect59x37 I
$87 rect59x43 I
$88 rect59x51 I
$89 rect64x22 I
$90 rect66x18 I
$91 rect67x122 I
$92 rect68x16 I
$93 rect69x24 I
$94 rect75x14 I
$95 rect76x24 I
$96 rect78.8x74.86xr21.68x12 I
$97 rect78.8x74.86xr21.68x34 I
$98 rect79x63 I
$99 rect92x44 I
$100 rect92x60 I
$101 rect96x60 I
$102 rect98x134 I
$103 sh041x021-l
$104 sh041x021-l+2
$105 sh041x021-l+4
$106 sh041x021-l+6
$107 sh041x021-r
$108 sh041x021-r+2
$109 sh041x021-r+4
$110 sh041x021-r+6
$111 sh052x046

#
#Feature attribute names
#
@0 .smd
@1 .nomenclature
@2 .geometry
@3 .string
@4 .pad_usage
@5 .string_angle

#
#Feature attribute text strings
#
&0 S049X012
&1 V010C020P_TP030B
&2 S028X024
&3 S046X012
&4 S020C_CST_V2
&5 S020X047
&6 V010C020P
&7 V008C018P_ANTI026_TP030B
&8 S014X062
&9 S024X017
&10 S035X025
&11 S039X055
&12 S012X015
&13 S020SQ
&14 016C024P
&15 S012X064
&16 S030X034
&17 S040X088
&18 S038X054
&19 S041X012
&20 SH041X021-R
&21 V008C018P_TP030B
&22 S094X130
&23 V008C018P
&24 SH052X046
&25 S001X001
&26 S062X014
&27 SH041X021-L
&28 S055X047
&29 S056X088
&30 S056X092
&31 S031SQ
&32 S050X140
&33 V008C018P_ANTI28
&34 S072X020
&35 S033X035
&36 S018X020
&37 S018X060
&38 S038X012
&39 059C086P
&40 S057X039
&41 S012X049
&42 S012X046
&43 S014X011
&44 S027X010
&45 S010X023
&46 S033X055
&47 S011X014
&48 S033X012
&49 S039X041
&50 S008X037
&51 S016X053
&52 S045X104
&53 S013X038
&54 S020X065
&55 S116X138
&56 S008X106
&57 S010X024
&58 S020X024
&59 S024X012
&60 S013X044
&61 S045X016
&62 S053X008
&63 S096X146
&64 S047X012
&65 076S104P
&66 076C104P
&67 S063X118
&68 EFT028X165
&69 079C100P
&70 S010X071
&71 S033X017
&72 V010C020P_SM014-NTH
&73 EFT028X126
&74 V012C024-NTH
&75 S057X043
&76 024X063OB035X075P
&77 S045X012
&78 S041X087
&79 166CT244CB198P
&80 S059X075
&81 024X051OB071X075P_R
&82 024X051OB071X075P_L
&83 033C057P
&84 063C090P
&85 FID040
&86 MTH100C090N
&87 MTH125C115N
&88 MTH118C108N
&89 SOLDERMASK TOP
&90 P/N : R4006-B0001-02
&91 Date: 2022-02-25
&92 Layer:
&93 Rev : 01

#
#Layer features
#
P 4.2391 4.03136998 82 P 0 8 0;0,2=0,4=0
P 4.31 4.065 3 P 0 8 0;2=1,4=1
P 4.354 4.065 60 P 0 8 0;0,2=2,4=0
P 4.2406 4.05106004 79 P 0 8 0;0,2=3,4=0
P 4.31 4.115 3 P 0 8 0;2=1,4=1
P 4.354 4.115 60 P 0 8 0;0,2=2,4=0
P 4.61 2.3 3 P 0 8 0;2=1,4=1
P 4.65 2.299 55 P 0 8 0;0,2=2,4=0
P 4.48216998 2.04028002 4 P 0 8 0;0,2=4,4=0
P 4.49 2.275 3 P 0 8 0;2=1,4=1
P 4.62 2.419 55 P 0 8 0;0,2=2,4=0
P 4.4428 2.11901998 4 P 0 8 0;0,2=4,4=0
P 4.435 2.315 3 P 0 8 0;2=1,4=1
P 4.53 2.419 55 P 0 8 0;0,2=2,4=0
P 4.40343002 2.11901998 4 P 0 8 0;0,2=4,4=0
P 4.49 2.325 3 P 0 8 0;2=1,4=1
P 4.535 2.324 55 P 0 8 0;0,2=2,4=0
P 4.4428 2.15838996 4 P 0 8 0;0,2=4,4=0
P 4.435 2.365 3 P 0 8 0;2=1,4=1
P 4.485 2.419 55 P 0 8 0;0,2=2,4=0
P 4.40343002 2.15838996 4 P 0 8 0;0,2=4,4=0
P 3.76 2.426 55 P 0 8 0;0,2=2,4=0
P 3.655 2.465 3 P 0 8 0;2=1,4=1
P 3.6576 2.5135 51 P 0 8 0;0,2=5,4=0
P 3.705 2.426 55 P 0 8 0;0,2=2,4=0
P 2.996 0.57441004 60 P 0 8 0;0,2=2,4=0
P 2.997 0.621 60 P 0 8 0;0,2=2,4=0
P 3.125 1.605 3 P 0 8 0;2=1,4=1
P 3.65 2.68 3 P 0 8 0;2=6,4=1
P 3.6576 2.6265 51 P 0 8 0;0,2=5,4=0
P 3.12 2.645 3 P 0 8 0;2=6,4=1
P 4.20658002 2.07965 4 P 0 8 0;0,2=4,4=0
P 3.765 2.69 3 P 0 8 0;2=1,4=1
P 3.7324 2.6265 51 P 0 8 0;0,2=5,4=0
P 3.731 2.71 60 P 0 8 0;0,2=2,4=0
P 4.48216998 1.52846998 4 P 0 8 0;0,2=4,4=0
P 4.2406 3.93293996 79 P 0 8 0;0,2=3,4=0
P 4.354 3.865 60 P 0 8 0;0,2=2,4=0
P 3.36525 3.305 2 P 0 8 0;2=7,4=1
P 3.2815 3.27661004 90 P 0 8 0;0,2=8,4=0
P 4.8855 0.91956998 90 P 0 8 0;0,2=8,4=0
P 4.736 0.965 60 P 0 8 0;0,2=2,4=0
P 4.736 0.915 60 P 0 8 0;0,2=2,4=0
P 4.20058996 3.4076 47 P 0 8 0;0,2=9,4=0
P 4.1695 3.24556998 90 P 0 8 0;0,2=8,4=0
P 4.015 3.291 60 P 0 8 0;0,2=2,4=0
P 4.015 3.239 60 P 0 8 0;0,2=2,4=0
P 4.00558996 3.4056 47 P 0 8 0;0,2=9,4=0
P 4.0355 3.76456998 90 P 0 8 0;0,2=8,4=0
P 3.881 3.758 60 P 0 8 0;0,2=2,4=0
P 3.881 3.81 60 P 0 8 0;0,2=2,4=0
P 4.08846998 1.60721004 4 P 0 8 0;0,2=4,4=0
P 4.205 0.879 55 P 0 8 0;0,2=2,4=0
P 4.314 0.82366004 56 P 0 8 0;0,2=10,4=0
P 3.82286004 0.86213996 3 P 0 8 0;2=1,4=1
P 3.88 0.75216998 87 P 0 8 0;0,2=11,4=0
P 3.77 0.874 55 P 0 8 0;0,2=2,4=0
P 0.49556998 2.166 33 P 0 8 0;0,2=12,4=0
P 0.496 2.13455 3 P 0 8 0;2=1,4=1
P 0.51743002 2.68 33 P 0 8 0;0,2=12,4=0
P 0.528 2.72 3 P 0 8 0;2=1,4=1
P 0.52443002 1 33 P 0 8 0;0,2=12,4=0
P 0.575 1.015 3 P 0 8 0;2=1,4=1
P 0.48956998 1.57 33 P 0 8 0;0,2=12,4=0
P 0.48956998 1.53618996 3 P 0 8 0;2=1,4=1
P 4.63965 1.96153996 4 P 0 8 0;0,2=4,4=0
P 4.08846998 1.8828 4 P 0 8 0;0,2=4,4=0
P 4.48216998 1.41035 4 P 0 8 0;0,2=4,4=0
P 4.08846998 2.11901998 4 P 0 8 0;0,2=4,4=0
P 3.93098002 2.00091004 4 P 0 8 0;0,2=4,4=0
P 3.93098002 1.96153996 4 P 0 8 0;0,2=4,4=0
P 4.24595 2.04028002 4 P 0 8 0;0,2=4,4=0
P 3.97035 2.04028002 4 P 0 8 0;0,2=4,4=0
P 4.24595 2.00091004 4 P 0 8 0;0,2=4,4=0
P 4.28531998 2.07965 4 P 0 8 0;0,2=4,4=0
P 4.28531998 2.04028002 4 P 0 8 0;0,2=4,4=0
P 4.48216998 1.8828 4 P 0 8 0;0,2=4,4=0
P 4.71838996 2.07965 4 P 0 8 0;0,2=4,4=0
P 4.0491 2.00091004 4 P 0 8 0;0,2=4,4=0
P 4.48216998 1.84343002 4 P 0 8 0;0,2=4,4=0
P 4.67901998 2.04028002 4 P 0 8 0;0,2=4,4=0
P 4.60028002 1.92216998 4 P 0 8 0;0,2=4,4=0
P 4.60028002 1.96153996 4 P 0 8 0;0,2=4,4=0
P 4.28531998 2.00091004 4 P 0 8 0;0,2=4,4=0
P 4.60028002 1.8828 4 P 0 8 0;0,2=4,4=0
P 4.56091004 1.96153996 4 P 0 8 0;0,2=4,4=0
P 3.89161004 2.04028002 4 P 0 8 0;0,2=4,4=0
P 4.52153996 2.00091004 4 P 0 8 0;0,2=4,4=0
P 4.32468996 2.07965 4 P 0 8 0;0,2=4,4=0
P 4.08846998 2.07965 4 P 0 8 0;0,2=4,4=0
P 4.67901998 1.52846998 4 P 0 8 0;0,2=4,4=0
P 4.52153996 1.96153996 4 P 0 8 0;0,2=4,4=0
P 4.08846998 2.04028002 4 P 0 8 0;0,2=4,4=0
P 4.63965 1.52846998 4 P 0 8 0;0,2=4,4=0
P 3.97035 2.07965 4 P 0 8 0;0,2=4,4=0
P 4.60028002 1.56783996 4 P 0 8 0;0,2=4,4=0
P 4.00973002 2.07965 4 P 0 8 0;0,2=4,4=0
P 4.56091004 1.56783996 4 P 0 8 0;0,2=4,4=0
P 4.67901998 1.92216998 4 P 0 8 0;0,2=4,4=0
P 4.48216998 2.00091004 4 P 0 8 0;0,2=4,4=0
P 4.4428 2.00091004 4 P 0 8 0;0,2=4,4=0
P 4.40343002 1.96153996 4 P 0 8 0;0,2=4,4=0
P 4.4428 1.92216998 4 P 0 8 0;0,2=4,4=0
P 4.36406004 1.84343002 4 P 0 8 0;0,2=4,4=0
P 4.36406004 1.80406004 4 P 0 8 0;0,2=4,4=0
P 4.4428 1.96153996 4 P 0 8 0;0,2=4,4=0
P 4.12783996 1.92216998 4 P 0 8 0;0,2=4,4=0
P 4.0491 1.96153996 4 P 0 8 0;0,2=4,4=0
P 4.56091004 2.15838996 4 P 0 8 0;0,2=4,4=0
P 4.71838996 1.8828 4 P 0 8 0;0,2=4,4=0
P 4.52153996 2.11901998 4 P 0 8 0;0,2=4,4=0
P 4.12783996 2.00091004 4 P 0 8 0;0,2=4,4=0
P 4.48216998 2.11901998 4 P 0 8 0;0,2=4,4=0
P 4.00973002 1.92216998 4 P 0 8 0;0,2=4,4=0
P 4.0491 1.92216998 4 P 0 8 0;0,2=4,4=0
P 4.48216998 2.07965 4 P 0 8 0;0,2=4,4=0
P 4.16721004 2.00091004 4 P 0 8 0;0,2=4,4=0
P 4.60028002 2.15838996 4 P 0 8 0;0,2=4,4=0
P 3.93098002 1.92216998 4 P 0 8 0;0,2=4,4=0
P 3.93098002 1.8828 4 P 0 8 0;0,2=4,4=0
P 4.63965 2.15838996 4 P 0 8 0;0,2=4,4=0
P 3.89161004 1.92216998 4 P 0 8 0;0,2=4,4=0
P 4.63965 2.11901998 4 P 0 8 0;0,2=4,4=0
P 3.89161004 1.8828 4 P 0 8 0;0,2=4,4=0
P 4.0491 1.84343002 4 P 0 8 0;0,2=4,4=0
P 4.08846998 1.44973002 4 P 0 8 0;0,2=4,4=0
P 4.52153996 1.56783996 4 P 0 8 0;0,2=4,4=0
P 4.28531998 1.52846998 4 P 0 8 0;0,2=4,4=0
P 4.20658002 1.92216998 4 P 0 8 0;0,2=4,4=0
P 4.16721004 1.4891 4 P 0 8 0;0,2=4,4=0
P 4.20658002 1.4891 4 P 0 8 0;0,2=4,4=0
P 4.20658002 2.11901998 4 P 0 8 0;0,2=4,4=0
P 4.67901998 1.44973002 4 P 0 8 0;0,2=4,4=0
P 4.12783996 1.41035 4 P 0 8 0;0,2=4,4=0
P 4.63965 1.44973002 4 P 0 8 0;0,2=4,4=0
P 4.16721004 1.41035 4 P 0 8 0;0,2=4,4=0
P 4.60028002 1.44973002 4 P 0 8 0;0,2=4,4=0
P 4.12783996 1.44973002 4 P 0 8 0;0,2=4,4=0
P 4.56091004 1.44973002 4 P 0 8 0;0,2=4,4=0
P 4.16721004 1.44973002 4 P 0 8 0;0,2=4,4=0
P 4.20658002 1.44973002 4 P 0 8 0;0,2=4,4=0
P 4.24595 1.44973002 4 P 0 8 0;0,2=4,4=0
P 4.52153996 1.4891 4 P 0 8 0;0,2=4,4=0
P 4.24595 1.41035 4 P 0 8 0;0,2=4,4=0
P 4.48216998 1.4891 4 P 0 8 0;0,2=4,4=0
P 4.28531998 1.41035 4 P 0 8 0;0,2=4,4=0
P 4.60028002 1.4891 4 P 0 8 0;0,2=4,4=0
P 4.28531998 1.33161004 4 P 0 8 0;0,2=4,4=0
P 4.60028002 1.52846998 4 P 0 8 0;0,2=4,4=0
P 4.32468996 1.33161004 4 P 0 8 0;0,2=4,4=0
P 4.56091004 1.4891 4 P 0 8 0;0,2=4,4=0
P 4.32468996 1.37098002 4 P 0 8 0;0,2=4,4=0
P 4.52153996 1.52846998 4 P 0 8 0;0,2=4,4=0
P 4.32468996 1.41035 4 P 0 8 0;0,2=4,4=0
P 4.20658002 1.52846998 4 P 0 8 0;0,2=4,4=0
P 4.4428 1.52846998 4 P 0 8 0;0,2=4,4=0
P 4.24595 1.52846998 4 P 0 8 0;0,2=4,4=0
P 4.28531998 1.44973002 4 P 0 8 0;0,2=4,4=0
P 4.28531998 1.4891 4 P 0 8 0;0,2=4,4=0
P 4.36406004 1.41035 4 P 0 8 0;0,2=4,4=0
P 4.36406004 1.44973002 4 P 0 8 0;0,2=4,4=0
P 4.52153996 1.33161004 4 P 0 8 0;0,2=4,4=0
P 3.89161004 1.33161004 4 P 0 8 0;0,2=4,4=0
P 4.48216998 1.33161004 4 P 0 8 0;0,2=4,4=0
P 3.93098002 1.33161004 4 P 0 8 0;0,2=4,4=0
P 4.32468996 1.96153996 4 P 0 8 0;0,2=4,4=0
P 4.56091004 1.37098002 4 P 0 8 0;0,2=4,4=0
P 3.93098002 1.37098002 4 P 0 8 0;0,2=4,4=0
P 4.52153996 1.37098002 4 P 0 8 0;0,2=4,4=0
P 3.97035 1.37098002 4 P 0 8 0;0,2=4,4=0
P 4.4428 1.37098002 4 P 0 8 0;0,2=4,4=0
P 4.00973002 1.33161004 4 P 0 8 0;0,2=4,4=0
P 4.4428 1.41035 4 P 0 8 0;0,2=4,4=0
P 4.0491 1.33161004 4 P 0 8 0;0,2=4,4=0
P 4.63965 1.37098002 4 P 0 8 0;0,2=4,4=0
P 4.00973002 1.37098002 4 P 0 8 0;0,2=4,4=0
P 4.60028002 1.37098002 4 P 0 8 0;0,2=4,4=0
P 4.0491 1.37098002 4 P 0 8 0;0,2=4,4=0
P 4.67901998 1.84343002 4 P 0 8 0;0,2=4,4=0
P 4.4428 2.04028002 4 P 0 8 0;0,2=4,4=0
P 4.08846998 1.33161004 4 P 0 8 0;0,2=4,4=0
P 4.63965 1.80406004 4 P 0 8 0;0,2=4,4=0
P 4.40343002 2.04028002 4 P 0 8 0;0,2=4,4=0
P 4.12783996 1.33161004 4 P 0 8 0;0,2=4,4=0
P 4.56091004 1.41035 4 P 0 8 0;0,2=4,4=0
P 4.0491 1.41035 4 P 0 8 0;0,2=4,4=0
P 4.52153996 1.41035 4 P 0 8 0;0,2=4,4=0
P 4.08846998 1.41035 4 P 0 8 0;0,2=4,4=0
P 4.71838996 1.76468996 4 P 0 8 0;0,2=4,4=0
P 4.71838996 1.33161004 4 P 0 8 0;0,2=4,4=0
P 4.20658002 1.33161004 4 P 0 8 0;0,2=4,4=0
P 4.71838996 1.72531998 4 P 0 8 0;0,2=4,4=0
P 4.67901998 1.33161004 4 P 0 8 0;0,2=4,4=0
P 4.24595 1.33161004 4 P 0 8 0;0,2=4,4=0
P 4.12783996 1.37098002 4 P 0 8 0;0,2=4,4=0
P 4.16721004 1.37098002 4 P 0 8 0;0,2=4,4=0
P 4.67901998 1.41035 4 P 0 8 0;0,2=4,4=0
P 4.20658002 1.37098002 4 P 0 8 0;0,2=4,4=0
P 4.63965 1.41035 4 P 0 8 0;0,2=4,4=0
P 4.24595 1.37098002 4 P 0 8 0;0,2=4,4=0
P 4.71838996 2.15838996 4 P 0 8 0;0,2=4,4=0
P 4.71838996 2.11901998 4 P 0 8 0;0,2=4,4=0
P 4.56091004 2.07965 4 P 0 8 0;0,2=4,4=0
P 4.52153996 2.07965 4 P 0 8 0;0,2=4,4=0
P 4.56091004 1.84343002 4 P 0 8 0;0,2=4,4=0
P 4.63965 2.04028002 4 P 0 8 0;0,2=4,4=0
P 4.56091004 2.04028002 4 P 0 8 0;0,2=4,4=0
P 4.52153996 1.8828 4 P 0 8 0;0,2=4,4=0
P 4.56091004 2.00091004 4 P 0 8 0;0,2=4,4=0
P 4.24595 1.96153996 4 P 0 8 0;0,2=4,4=0
P 4.28531998 1.92216998 4 P 0 8 0;0,2=4,4=0
P 4.12783996 1.96153996 4 P 0 8 0;0,2=4,4=0
P 4.16721004 1.96153996 4 P 0 8 0;0,2=4,4=0
P 4.60028002 2.11901998 4 P 0 8 0;0,2=4,4=0
P 4.67901998 1.72531998 4 P 0 8 0;0,2=4,4=0
P 4.67901998 1.68595 4 P 0 8 0;0,2=4,4=0
P 1.45 3.59 3 P 0 8 0;2=1,4=1
P 1.56 3.165 3 P 0 8 0;2=6,4=1
P 1.56 3.205 3 P 0 8 0;2=1,4=1
P 1.59668996 3.17 18 P 0 8 0;0,2=13,4=0
P 0.72 3.5065 51 P 0 8 0;0,2=5,4=0
P 0.72 3.463 3 P 0 8 0;2=6,4=1
P 0.42326004 3.4315 5 P 0 8 0;2=14,4=0
P 0.40553996 3.4008 5 P 0 8 0;2=14,4=0
P 0.2815 3.4315 5 P 0 8 0;2=14,4=0
P 0.26378002 3.4008 5 P 0 8 0;2=14,4=0
P 1.11316004 3.578 40 P 0 8 0;0,2=15,4=0
P 1.14 3.52 3 P 0 8 0;2=1,4=1
P 1.245 3.52 3 P 0 8 0;2=1,4=1
P 1.21158002 3.578 40 P 0 8 0;0,2=15,4=0
P 4.652 3.86 61 P 0 8 0;0,2=16,4=0
P 4.705 3.95 2 P 0 8 0;2=7,4=1
P 4.78656004 3.90826998 99 P 0 8 0;0,2=17,4=0
P 4.654 3.927 69 P 0 8 0;0,2=18,4=0
P 4.705 3.91 3 P 0 8 0;2=6,4=1
P 1.62033002 2.99531004 73 P 0 8 0;0,2=19,4=0
P 1.566 2.95 3 P 0 8 0;2=1,4=1
P 1.055 3.731 55 P 0 8 0;0,2=2,4=0
P 1.045 3.77 3 P 0 8 0;2=6,4=1
P 1.515 3.58 3 P 0 8 0;2=6,4=1
P 6.145 4.035 3 P 0 8 0;2=1,4=1
P 1.37 3.64 3 P 0 8 0;2=6,4=1
P 1.667 3.438 3 P 0 8 0;2=6,4=1
P 1.591 3.546 3 P 0 8 0;2=6,4=1
P 1.13 3.445 3 P 0 8 0;2=6,4=1
P 0.894 3.43758002 92 P 0 8 0;0,2=15,4=0
P 0.95 3.445 3 P 0 8 0;2=6,4=1
P 2.19 3.488 3 P 0 8 0;2=6,4=1
P 2.192 3.388 3 P 0 8 0;2=6,4=1
P 1.41916004 3.33916004 3 P 0 8 0;2=6,4=1
P 1.352 3.33916004 92 P 0 8 0;0,2=15,4=0
P 1.352 3.22105 92 P 0 8 0;0,2=15,4=0
P 1.407 3.2 3 P 0 8 0;2=6,4=1
P 1.495 3.11033996 3 P 0 8 0;2=6,4=1
P 1.62033002 3.03468996 73 P 0 8 0;0,2=19,4=0
P 1.62033002 3.05888002 107 P 0 8 0;0,2=20,4=0
P 1.455 3.138 65 P 0 8 0;0,2=16,4=0
P 1.46 3.073 85 P 0 8 0;0,2=18,4=0
P 1.51 3.164 55 P 0 8 0;0,2=2,4=0
P 1.53 3.046 55 P 0 8 0;0,2=2,4=0
P 1.15253002 3.06246998 3 P 0 8 0;2=6,4=1
P 1.15253002 3.12 40 P 0 8 0;0,2=15,4=0
P 0.95 3.215 3 P 0 8 0;2=6,4=1
P 0.894 3.22105 92 P 0 8 0;0,2=15,4=0
P 0.945 3.125 3 P 0 8 0;2=6,4=1
P 1.175 2.9 3 P 0 8 0;2=6,4=1
P 1.175 2.939 55 P 0 8 0;0,2=2,4=0
P 1.025 3.02 3 P 0 8 0;2=6,4=1
P 1.025 2.981 55 P 0 8 0;0,2=2,4=0
P 5.275 3.891 3 P 0 8 0;2=1,4=1
P 5.314 3.902 61 P 0 8 0;0,2=16,4=0
P 5.275 3.931 3 P 0 8 0;2=6,4=1
P 5.275 3.971 3 P 0 8 0;2=1,4=1
P 5.321 3.99 3 P 0 8 0;2=6,4=1
P 5.32 3.957 60 P 0 8 0;0,2=2,4=0
P 5.762 3.467 60 P 0 8 0;0,2=2,4=0
P 5.762 3.425 2 P 0 8 0;2=21,4=1
P 5.567 3.203 3 P 0 8 0;2=6,4=1
P 5.617 3.203 3 P 0 8 0;2=1,4=1
P 5.55091998 3.306 102 P 0 8 0;0,2=22,4=0
P 5.62 3.316 3 P 0 8 0;2=6,4=1
P 5.625 3.261 3 P 0 8 0;2=1,4=1
P 5.625 3.361 3 P 0 8 0;2=6,4=1
P 5.533 3.569 61 P 0 8 0;0,2=16,4=0
P 5.6 3.421 3 P 0 8 0;2=1,4=1
P 5.552 3.71141004 2 P 0 8 0;2=23,4=1
P 5.595 3.569 60 P 0 8 0;0,2=2,4=0
P 5.552 3.74683996 2 P 0 8 0;2=23,4=1
P 5.552 3.78226998 2 P 0 8 0;2=23,4=1
P 5.552 3.67596998 2 P 0 8 0;2=23,4=1
P 5.536 3.64025 111 P 0 8 0;0,2=24,4=0
P 5.55606998 3.63305 17 P 0 8 0;0,2=25,4=0
P 5.52 3.78226998 2 P 0 8 0;2=23,4=1
P 5.52 3.74683996 2 P 0 8 0;2=23,4=1
P 5.52 3.71141004 2 P 0 8 0;2=23,4=1
P 5.52 3.67596998 2 P 0 8 0;2=23,4=1
P 0.928 3.961 3 P 0 8 0;2=6,4=1
P 0.968 3.961 3 P 0 8 0;2=6,4=1
P 0.968 4.021 3 P 0 8 0;2=6,4=1
P 0.928 4.021 3 P 0 8 0;2=1,4=1
P 0.928 4.081 3 P 0 8 0;2=6,4=1
P 0.968 4.081 3 P 0 8 0;2=1,4=1
P 0.928 4.141 3 P 0 8 0;2=1,4=1
P 0.968 4.141 3 P 0 8 0;2=6,4=1
P 0.603 3.951 3 P 0 8 0;2=1,4=1
P 0.643 3.956 3 P 0 8 0;2=6,4=1
P 0.603 4.011 3 P 0 8 0;2=6,4=1
P 0.643 4.016 3 P 0 8 0;2=1,4=1
P 0.603 4.071 3 P 0 8 0;2=1,4=1
P 0.643 4.076 3 P 0 8 0;2=6,4=1
P 0.603 4.131 3 P 0 8 0;2=6,4=1
P 0.643 4.136 3 P 0 8 0;2=1,4=1
P 0.571 3.899 65 P 0 8 0;0,2=16,4=0
P 0.854 3.942 3 P 0 8 0;2=6,4=1
P 0.807 3.942 3 P 0 8 0;2=6,4=1
P 0.76 3.942 3 P 0 8 0;2=6,4=1
P 0.713 3.942 3 P 0 8 0;2=6,4=1
P 0.76 4.042 3 P 0 8 0;2=6,4=1
P 0.76 3.992 3 P 0 8 0;2=6,4=1
P 0.713 3.992 3 P 0 8 0;2=6,4=1
P 0.713 4.042 3 P 0 8 0;2=6,4=1
P 0.713 4.092 3 P 0 8 0;2=6,4=1
P 0.76 4.092 3 P 0 8 0;2=6,4=1
P 0.807 4.092 3 P 0 8 0;2=6,4=1
P 0.807 4.042 3 P 0 8 0;2=6,4=1
P 0.807 3.992 3 P 0 8 0;2=6,4=1
P 0.854 3.992 3 P 0 8 0;2=6,4=1
P 0.854 4.042 3 P 0 8 0;2=6,4=1
P 0.854 4.092 3 P 0 8 0;2=6,4=1
P 0.74 1.005 3 P 0 8 0;2=1,4=1
P 0.76221004 0.9475 43 P 0 8 0;0,2=26,4=0
P 0.79 1.005 3 P 0 8 0;2=1,4=1
P 0.7878 0.9475 43 P 0 8 0;0,2=26,4=0
P 0.81338996 0.9475 43 P 0 8 0;0,2=26,4=0
P 0.84 1.005 3 P 0 8 0;2=1,4=1
P 1.62033002 3.015 73 P 0 8 0;0,2=19,4=0
P 1.568 3.011 3 P 0 8 0;2=1,4=1
P 1.526 2.95 60 P 0 8 0;0,2=2,4=0
P 1.53 3.004 55 P 0 8 0;0,2=2,4=0
P 1.738 3.241 3 P 0 8 0;2=1,4=1
P 1.819 3.19 60 P 0 8 0;0,2=2,4=0
P 1.782 3.26 69 P 0 8 0;0,2=18,4=0
P 1.68331004 3.17 18 P 0 8 0;0,2=13,4=0
P 1.68331004 3.27 18 P 0 8 0;0,2=13,4=0
P 1.76 3.187 65 P 0 8 0;0,2=16,4=0
P 1.73966998 2.97111998 108 P 0 8 0;0,2=20,4=0
P 1.765 2.9 3 P 0 8 0;2=1,4=1
P 1.73543002 2.9 33 P 0 8 0;0,2=12,4=0
P 1.73966998 3.03468996 73 P 0 8 0;0,2=19,4=0
P 1.73966998 3.05888002 103 P 0 8 0;0,2=27,4=0
P 1.822 3.105 69 P 0 8 0;0,2=18,4=0
P 1.78 3.095 3 P 0 8 0;2=1,4=1
P 1.835 2.981 55 P 0 8 0;0,2=2,4=0
P 1.76 3.133 65 P 0 8 0;0,2=16,4=0
P 1.824 3.04 60 P 0 8 0;0,2=2,4=0
P 1.73966998 2.99531004 73 P 0 8 0;0,2=19,4=0
P 1.795 2.946 3 P 0 8 0;2=1,4=1
P 1.885 2.939 55 P 0 8 0;0,2=2,4=0
P 1.835 2.939 55 P 0 8 0;0,2=2,4=0
P 5.2 0.87 3 P 0 8 0;2=1,4=1
P 5.249 0.87 60 P 0 8 0;0,2=2,4=0
P 5.1245 0.89398002 90 P 0 8 0;0,2=8,4=0
P 4.47 3.21998002 3 P 0 8 0;2=1,4=1
P 4.4085 3.21998002 90 P 0 8 0;0,2=8,4=0
P 4.512 3.22 60 P 0 8 0;0,2=2,4=0
P 4.385 3.645 3 P 0 8 0;2=1,4=1
P 4.384 3.745 60 P 0 8 0;0,2=2,4=0
P 4.384 3.7 60 P 0 8 0;0,2=2,4=0
P 4.435 3.6185 71 P 0 8 0;0,2=11,4=0
P 4.2745 3.73898002 90 P 0 8 0;0,2=8,4=0
P 0.894 3.35883996 92 P 0 8 0;0,2=15,4=0
P 1.03 3.515 3 P 0 8 0;2=1,4=1
P 1.01473002 3.578 40 P 0 8 0;0,2=15,4=0
P 1.19 3.52 3 P 0 8 0;2=1,4=1
P 1.17221004 3.578 40 P 0 8 0;0,2=15,4=0
P 0.99505 3.12 40 P 0 8 0;0,2=15,4=0
P 0.97536004 3.12 40 P 0 8 0;0,2=15,4=0
P 0.894 3.20136004 92 P 0 8 0;0,2=15,4=0
P 0.894 3.24073002 92 P 0 8 0;0,2=15,4=0
P 0.894 3.26041998 92 P 0 8 0;0,2=15,4=0
P 0.55 3.36 3 P 0 8 0;2=1,4=1
P 0.589 3.29 60 P 0 8 0;0,2=2,4=0
P 0.3701 3.4008 5 P 0 8 0;2=14,4=0
P 0.55 3.554 3 P 0 8 0;2=1,4=1
P 0.595 3.554 55 P 0 8 0;0,2=2,4=0
P 0.31693996 3.4315 5 P 0 8 0;2=14,4=0
P 1.25095 3.578 40 P 0 8 0;0,2=15,4=0
P 1.29831004 3.91846004 88 P 0 8 0;0,2=28,4=0
P 1.26956998 3.79 33 P 0 8 0;0,2=12,4=0
P 1.271 3.75 60 P 0 8 0;0,2=2,4=0
P 1.23126998 3.578 40 P 0 8 0;0,2=15,4=0
P 1.21168996 3.85153996 88 P 0 8 0;0,2=28,4=0
P 1.23543002 3.79 33 P 0 8 0;0,2=12,4=0
P 1.229 3.75 60 P 0 8 0;0,2=2,4=0
P 5.9945 1.57063002 100 P 0 8 0;0,2=29,4=0
P 5.92 1.57063002 3 P 0 8 0;2=1,4=1
P 6.14648002 1.57063002 101 P 0 8 0;0,2=30,4=0
P 6.22 1.57 3 P 0 8 0;2=1,4=1
P 5.92 1.46 3 P 0 8 0;2=1,4=1
P 5.9945 1.47063002 100 P 0 8 0;0,2=29,4=0
P 6.22 1.465 3 P 0 8 0;2=1,4=1
P 6.14648002 1.47063002 101 P 0 8 0;0,2=30,4=0
P 5.92 1.68 3 P 0 8 0;2=1,4=1
P 5.9945 1.67063002 100 P 0 8 0;0,2=29,4=0
P 6.22035 1.67063002 3 P 0 8 0;2=1,4=1
P 6.14648002 1.67063002 101 P 0 8 0;0,2=30,4=0
P 5.92 1.78 3 P 0 8 0;2=1,4=1
P 5.9945 1.77063002 100 P 0 8 0;0,2=29,4=0
P 6.22 1.755 3 P 0 8 0;2=1,4=1
P 6.14648002 1.77063002 101 P 0 8 0;0,2=30,4=0
P 6.09423996 4.13778996 3 P 0 8 0;2=1,4=1
P 6.1437 4.13778996 19 P 0 8 0;0,2=31,4=0
P 3.51 3.08 3 P 0 8 0;2=1,4=1
P 1.025 2.9 3 P 0 8 0;2=6,4=1
P 1.025 2.939 55 P 0 8 0;0,2=2,4=0
P 1.075 2.939 55 P 0 8 0;0,2=2,4=0
P 4.40343002 1.92216998 4 P 0 8 0;0,2=4,4=0
P 3.46 3.065 3 P 0 8 0;2=1,4=1
P 1.125 2.9 3 P 0 8 0;2=6,4=1
P 1.125 2.939 55 P 0 8 0;0,2=2,4=0
P 4.40343002 1.8828 4 P 0 8 0;0,2=4,4=0
P 3.035 1.64 3 P 0 8 0;2=6,4=1
P 3.44256004 2.765 28 P 0 8 0;0,2=32,4=0
P 1.1737 0.7536 60 P 0 8 0;0,2=2,4=0
P 1.0705 0.7284 81 P 0 8 0;0,2=5,4=0
P 1.1288 0.7302 2 P 0 8 0;2=21,4=1
P 3.075 1.605 3 P 0 8 0;2=6,4=1
P 3.44256004 2.865 28 P 0 8 0;0,2=32,4=0
P 3.365 2.95 2 P 0 8 0;2=7,4=1
P 0.7878 0.7085 43 P 0 8 0;0,2=26,4=0
P 0.715 0.77 3 P 0 8 0;2=1,4=1
P 0.73661998 0.7085 43 P 0 8 0;0,2=26,4=0
P 1.13283996 3.578 40 P 0 8 0;0,2=15,4=0
P 1.105 3.689 55 P 0 8 0;0,2=2,4=0
P 1.15253002 3.578 40 P 0 8 0;0,2=15,4=0
P 1.155 3.689 55 P 0 8 0;0,2=2,4=0
P 0.83 3.445 3 P 0 8 0;2=1,4=1
P 0.894 3.45726998 92 P 0 8 0;0,2=15,4=0
P 0.795 3.485 3 P 0 8 0;2=1,4=1
P 0.894 3.47695 92 P 0 8 0;0,2=15,4=0
P 0.83 3.525 3 P 0 8 0;2=1,4=1
P 0.894 3.49663996 92 P 0 8 0;0,2=15,4=0
P 0.951 3.519 3 P 0 8 0;2=1,4=1
P 0.97536004 3.578 40 P 0 8 0;0,2=15,4=0
P 0.82951004 3.2794 3 P 0 8 0;2=1,4=1
P 0.894 3.29978996 92 P 0 8 0;0,2=15,4=0
P 0.746 3.2 60 P 0 8 0;0,2=2,4=0
P 0.79 3.155 3 P 0 8 0;2=1,4=1
P 0.894 3.2801 92 P 0 8 0;0,2=15,4=0
P 0.78635 3.24491998 3 P 0 8 0;2=1,4=1
P 0.894 3.31946998 92 P 0 8 0;0,2=15,4=0
P 0.746 3.245 60 P 0 8 0;0,2=2,4=0
P 1.26 3.18 3 P 0 8 0;2=1,4=1
P 1.27063996 3.12 40 P 0 8 0;0,2=15,4=0
P 1.295 3.28 3 P 0 8 0;2=1,4=1
P 1.352 3.26041998 92 P 0 8 0;0,2=15,4=0
P 1.075 3.02 3 P 0 8 0;2=1,4=1
P 1.075 2.981 55 P 0 8 0;0,2=2,4=0
P 1.07378996 3.12 40 P 0 8 0;0,2=15,4=0
P 1.125 3.02 3 P 0 8 0;2=1,4=1
P 1.175 2.981 55 P 0 8 0;0,2=2,4=0
P 1.125 2.981 55 P 0 8 0;0,2=2,4=0
P 1.09346998 3.12 40 P 0 8 0;0,2=15,4=0
P 1.073 3.825 2 P 0 8 0;2=33,4=1
P 0.703 3.575 2 P 0 8 0;2=33,4=1
P 1.105 3.731 55 P 0 8 0;0,2=2,4=0
P 0.35238002 3.4315 5 P 0 8 0;2=14,4=0
P 0.6826 3.5065 51 P 0 8 0;0,2=5,4=0
P 0.33466004 3.4008 5 P 0 8 0;2=14,4=0
P 0.735 3.575 2 P 0 8 0;2=33,4=1
P 1.105 3.825 2 P 0 8 0;2=33,4=1
P 1.155 3.731 55 P 0 8 0;0,2=2,4=0
P 0.38781998 3.4315 5 P 0 8 0;2=14,4=0
P 0.29921998 3.4008 5 P 0 8 0;2=14,4=0
P 0.7574 3.5065 51 P 0 8 0;0,2=5,4=0
P 1.055 3.689 55 P 0 8 0;0,2=2,4=0
P 4.285 3.46 3 P 0 8 0;2=6,4=1
P 4.34 3.496 55 P 0 8 0;0,2=2,4=0
P 4.398 3.5315 71 P 0 8 0;0,2=11,4=0
P 2.15 3.438 3 P 0 8 0;2=1,4=1
P 1.352 3.43758002 92 P 0 8 0;0,2=15,4=0
P 1.352 3.47695 92 P 0 8 0;0,2=15,4=0
P 2.05 3.538 3 P 0 8 0;2=1,4=1
P 1.352 3.45726998 92 P 0 8 0;0,2=15,4=0
P 2.05 3.488 3 P 0 8 0;2=1,4=1
P 1.0541 3.12 40 P 0 8 0;0,2=15,4=0
P 1.29 3.215 3 P 0 8 0;2=6,4=1
P 1.352 3.20136004 92 P 0 8 0;0,2=15,4=0
P 1.0541 3.185 3 P 0 8 0;2=1,4=1
P 1.3 3.49663996 3 P 0 8 0;2=6,4=1
P 1.352 3.49663996 92 P 0 8 0;0,2=15,4=0
P 1.04018996 3.47425 3 P 0 8 0;2=6,4=1
P 1.0541 3.578 40 P 0 8 0;0,2=15,4=0
P 4.205 3.66 3 P 0 8 0;2=1,4=1
P 4.2745 3.6622 90 P 0 8 0;0,2=8,4=0
P 0.975 3.41 3 P 0 8 0;2=6,4=1
P 4.225 3.545 3 P 0 8 0;2=1,4=1
P 4.2745 3.58543002 90 P 0 8 0;0,2=8,4=0
P 1.015 3.41 3 P 0 8 0;2=6,4=1
P 3.95 3.6 3 P 0 8 0;2=1,4=1
P 4.0355 3.61101998 90 P 0 8 0;0,2=8,4=0
P 0.835 3.6 3 P 0 8 0;2=6,4=1
P 3.95 3.7 3 P 0 8 0;2=1,4=1
P 4.0355 3.6878 90 P 0 8 0;0,2=8,4=0
P 0.915 3.595 3 P 0 8 0;2=6,4=1
P 4.1184 3.5362 3 P 0 8 0;2=6,4=1
P 4.085 3.11 3 P 0 8 0;2=1,4=1
P 4.1695 3.11761004 90 P 0 8 0;0,2=8,4=0
P 4.0355 3.63661004 90 P 0 8 0;0,2=8,4=0
P 4.51 3.065 3 P 0 8 0;2=6,4=1
P 4.4085 3.09201998 90 P 0 8 0;0,2=8,4=0
P 4.33381998 3.60466004 3 P 0 8 0;2=1,4=1
P 4.2745 3.61101998 90 P 0 8 0;0,2=8,4=0
P 4.34 3.28 3 P 0 8 0;2=6,4=1
P 4.4085 3.1688 90 P 0 8 0;0,2=8,4=0
P 4.335 3.665 3 P 0 8 0;2=1,4=1
P 4.2745 3.6878 90 P 0 8 0;0,2=8,4=0
P 4.09 3.71338996 3 P 0 8 0;2=1,4=1
P 4.1695 3.19438996 90 P 0 8 0;0,2=8,4=0
P 4.0355 3.71338996 90 P 0 8 0;0,2=8,4=0
P 3.38 1.025 3 P 0 8 0;2=6,4=1
P 4.585 0.865 3 P 0 8 0;2=1,4=1
P 4.694 0.915 60 P 0 8 0;0,2=2,4=0
P 0.894 3.37853002 92 P 0 8 0;0,2=15,4=0
P 0.62 3.235 3 P 0 8 0;2=6,4=1
P 3.925 3.239 3 P 0 8 0;2=1,4=1
P 3.973 3.239 60 P 0 8 0;0,2=2,4=0
P 0.825 3.39 3 P 0 8 0;2=6,4=1
P 0.894 3.39821004 92 P 0 8 0;0,2=15,4=0
P 0.795 3.4179 3 P 0 8 0;2=6,4=1
P 0.894 3.4179 92 P 0 8 0;0,2=15,4=0
P 3.795 3.758 3 P 0 8 0;2=1,4=1
P 3.839 3.758 60 P 0 8 0;0,2=2,4=0
P 3.62 1.28 3 P 0 8 0;2=6,4=1
P 5.195 0.755 3 P 0 8 0;2=1,4=1
P 5.1245 0.76601998 90 P 0 8 0;0,2=8,4=0
P 4.96 0.85 3 P 0 8 0;2=6,4=1
P 4.8855 0.86838996 90 P 0 8 0;0,2=8,4=0
P 0.704 3.2 60 P 0 8 0;0,2=2,4=0
P 0.66 3.185 3 P 0 8 0;2=6,4=1
P 3.62 1.235 3 P 0 8 0;2=6,4=1
P 5.195 0.815 3 P 0 8 0;2=1,4=1
P 5.1245 0.8428 90 P 0 8 0;0,2=8,4=0
P 4.8855 0.79161004 90 P 0 8 0;0,2=8,4=0
P 4.937 0.79161004 3 P 0 8 0;2=6,4=1
P 0.66 3.235 3 P 0 8 0;2=6,4=1
P 0.704 3.245 60 P 0 8 0;0,2=2,4=0
P 4.205 3.81 3 P 0 8 0;2=6,4=1
P 4.2745 3.71338996 90 P 0 8 0;0,2=8,4=0
P 5.71056004 2.821 28 P 0 8 0;0,2=32,4=0
P 5.814 2.821 2 P 0 8 0;2=21,4=1
P 4.19 3.735 3 P 0 8 0;2=6,4=1
P 4.2745 3.63661004 90 P 0 8 0;0,2=8,4=0
P 5.71056004 2.721 28 P 0 8 0;0,2=32,4=0
P 5.814 2.721 2 P 0 8 0;2=21,4=1
P 3.895 3.7 3 P 0 8 0;2=6,4=1
P 4.0355 3.6622 90 P 0 8 0;0,2=8,4=0
P 5.71056004 3.021 28 P 0 8 0;0,2=32,4=0
P 5.815 3.021 2 P 0 8 0;2=21,4=1
P 4.135 3.735 3 P 0 8 0;2=6,4=1
P 4.0355 3.73898002 90 P 0 8 0;0,2=8,4=0
P 5.71056004 2.621 28 P 0 8 0;0,2=32,4=0
P 5.814 2.621 2 P 0 8 0;2=21,4=1
P 2.3 3.475 3 P 0 8 0;2=6,4=1
P 5.045 3.405 3 P 0 8 0;2=6,4=1
P 6.22356004 2.715 28 P 0 8 0;0,2=32,4=0
P 6.33 2.67 2 P 0 8 0;2=21,4=1
P 6.22356004 2.615 28 P 0 8 0;0,2=32,4=0
P 1.35 3.12 3 P 0 8 0;2=6,4=1
P 2.255 3.475 3 P 0 8 0;2=6,4=1
P 5.09 3.405 3 P 0 8 0;2=6,4=1
P 6.22356004 2.815 28 P 0 8 0;0,2=32,4=0
P 6.33 2.865 3 P 0 8 0;2=1,4=1
P 6.22356004 2.915 28 P 0 8 0;0,2=32,4=0
P 1.46 3.34 3 P 0 8 0;2=6,4=1
P 4.575 2.235 3 P 0 8 0;2=6,4=1
P 4.48216998 1.92216998 4 P 0 8 0;0,2=4,4=0
P 4.705 0.825 3 P 0 8 0;2=1,4=1
P 4.736 0.865 60 P 0 8 0;0,2=2,4=0
P 4.8855 0.89398002 90 P 0 8 0;0,2=8,4=0
P 4.575 2.275 3 P 0 8 0;2=6,4=1
P 4.36406004 1.96153996 4 P 0 8 0;0,2=4,4=0
P 4.755 0.825 3 P 0 8 0;2=1,4=1
P 4.736 0.785 60 P 0 8 0;0,2=2,4=0
P 4.8855 0.8172 90 P 0 8 0;0,2=8,4=0
P 1.26 0.72 3 P 0 8 0;2=1,4=1
P 4.67901998 1.80406004 4 P 0 8 0;0,2=4,4=0
P 0.842 0.75 3 P 0 8 0;2=1,4=1
P 4.71838996 1.80406004 4 P 0 8 0;0,2=4,4=0
P 3.73648996 1.85735 3 P 0 8 0;2=6,4=1
P 4.694 0.965 60 P 0 8 0;0,2=2,4=0
P 4.12783996 1.8828 4 P 0 8 0;0,2=4,4=0
P 4.345 3.02 3 P 0 8 0;2=6,4=1
P 4.12783996 1.80406004 4 P 0 8 0;0,2=4,4=0
P 4.075 3.005 3 P 0 8 0;2=6,4=1
P 3.925 3.291 3 P 0 8 0;2=1,4=1
P 3.973 3.291 60 P 0 8 0;0,2=2,4=0
P 4.39 3.02 3 P 0 8 0;2=6,4=1
P 4.16721004 1.80406004 4 P 0 8 0;0,2=4,4=0
P 4.13 3.005 3 P 0 8 0;2=6,4=1
P 3.795 3.81 3 P 0 8 0;2=1,4=1
P 3.839 3.81 60 P 0 8 0;0,2=2,4=0
P 4.615 3.11 3 P 0 8 0;2=6,4=1
P 4.67901998 1.8828 4 P 0 8 0;0,2=4,4=0
P 4.34 3.454 55 P 0 8 0;0,2=2,4=0
P 4.4 3.325 3 P 0 8 0;2=1,4=1
P 4.615 2.68408996 3 P 0 8 0;2=6,4=1
P 4.28531998 2.11901998 4 P 0 8 0;0,2=4,4=0
P 4.15 2.468 3 P 0 8 0;2=6,4=1
P 4.15 2.51 55 P 0 8 0;0,2=2,4=0
P 6.22 1.415 3 P 0 8 0;2=1,4=1
P 4.685 2.7 3 P 0 8 0;2=6,4=1
P 4.209 2.51 55 P 0 8 0;0,2=2,4=0
P 4.209 2.468 3 P 0 8 0;2=6,4=1
P 4.32468996 2.11901998 4 P 0 8 0;0,2=4,4=0
P 6.22 1.516 3 P 0 8 0;2=1,4=1
P 4.975 2.26 3 P 0 8 0;2=6,4=1
P 4.093 2.51 55 P 0 8 0;0,2=2,4=0
P 4.093 2.468 3 P 0 8 0;2=6,4=1
P 4.24595 2.15838996 4 P 0 8 0;0,2=4,4=0
P 6.22 1.62 3 P 0 8 0;2=1,4=1
P 4.925 2.26 3 P 0 8 0;2=1,4=1
P 4.037 2.51 55 P 0 8 0;0,2=2,4=0
P 4.037 2.468 3 P 0 8 0;2=6,4=1
P 4.24595 2.11901998 4 P 0 8 0;0,2=4,4=0
P 6.22 1.815 3 P 0 8 0;2=1,4=1
P 5.92 1.41 3 P 0 8 0;2=1,4=1
P 5.09 2.155 3 P 0 8 0;2=6,4=1
P 3.801 2.51 55 P 0 8 0;0,2=2,4=0
P 3.801 2.468 3 P 0 8 0;2=6,4=1
P 4.12783996 2.07965 4 P 0 8 0;0,2=4,4=0
P 5.92 1.515 3 P 0 8 0;2=1,4=1
P 5.135 2.155 3 P 0 8 0;2=6,4=1
P 3.86 2.468 3 P 0 8 0;2=6,4=1
P 3.86 2.51 55 P 0 8 0;0,2=2,4=0
P 4.16721004 2.07965 4 P 0 8 0;0,2=4,4=0
P 5.92 1.63 3 P 0 8 0;2=1,4=1
P 5.115 2.065 3 P 0 8 0;2=6,4=1
P 3.919 2.51 55 P 0 8 0;0,2=2,4=0
P 3.919 2.468 3 P 0 8 0;2=6,4=1
P 4.16721004 2.15838996 4 P 0 8 0;0,2=4,4=0
P 5.92 1.73 3 P 0 8 0;2=1,4=1
P 5.13 2.105 3 P 0 8 0;2=6,4=1
P 4.20658002 2.15838996 4 P 0 8 0;0,2=4,4=0
P 3.978 2.51 55 P 0 8 0;0,2=2,4=0
P 3.978 2.468 3 P 0 8 0;2=6,4=1
P 4.685 2.645 3 P 0 8 0;2=6,4=1
P 4.62 2.461 55 P 0 8 0;0,2=2,4=0
P 4.1 3.38 3 P 0 8 0;2=1,4=1
P 4.14941004 3.4076 47 P 0 8 0;0,2=9,4=0
P 4.08 3.429 55 P 0 8 0;0,2=2,4=0
P 4.53 2.461 55 P 0 8 0;0,2=2,4=0
P 4.53 2.5 3 P 0 8 0;2=6,4=1
P 3.9 3.385 3 P 0 8 0;2=1,4=1
P 3.95441004 3.4056 47 P 0 8 0;0,2=9,4=0
P 3.87 3.424 55 P 0 8 0;0,2=2,4=0
P 4.575 2.419 55 P 0 8 0;0,2=2,4=0
P 4.4085 3.11761004 90 P 0 8 0;0,2=8,4=0
P 4.485 3.115 3 P 0 8 0;2=1,4=1
P 4.535 2.366 55 P 0 8 0;0,2=2,4=0
P 4.575 2.374 3 P 0 8 0;2=6,4=1
P 4.485 2.461 55 P 0 8 0;0,2=2,4=0
P 4.485 2.5 3 P 0 8 0;2=6,4=1
P 4.29441998 3.10075 3 P 0 8 0;2=1,4=1
P 4.1695 3.1432 90 P 0 8 0;0,2=8,4=0
P 4.61 2.345 3 P 0 8 0;2=6,4=1
P 4.65 2.341 55 P 0 8 0;0,2=2,4=0
P 4.4085 3.19438996 90 P 0 8 0;0,2=8,4=0
P 4.54 3.125 3 P 0 8 0;2=1,4=1
P 4.085 3.21998002 3 P 0 8 0;2=1,4=1
P 4.1695 3.21998002 90 P 0 8 0;0,2=8,4=0
P 4.35 2.505 3 P 0 8 0;2=6,4=1
P 5.365 0.79 3 P 0 8 0;2=1,4=1
P 5.1245 0.79161004 90 P 0 8 0;0,2=8,4=0
P 5.249 0.76 60 P 0 8 0;0,2=2,4=0
P 4.71838996 1.96153996 4 P 0 8 0;0,2=4,4=0
P 5.365 0.845 3 P 0 8 0;2=1,4=1
P 5.249 0.82 60 P 0 8 0;0,2=2,4=0
P 5.1245 0.86838996 90 P 0 8 0;0,2=8,4=0
P 4.71838996 1.92216998 4 P 0 8 0;0,2=4,4=0
P 4.0661 3.5341 3 P 0 8 0;2=1,4=1
P 4.08 3.471 55 P 0 8 0;0,2=2,4=0
P 4.14941004 3.4824 47 P 0 8 0;0,2=9,4=0
P 3.83 3.466 2 P 0 8 0;2=21,4=1
P 3.87 3.466 55 P 0 8 0;0,2=2,4=0
P 3.95441004 3.4804 47 P 0 8 0;0,2=9,4=0
P 4.35143002 3.06643002 3 P 0 8 0;2=6,4=1
P 4.4085 3.06643002 90 P 0 8 0;0,2=8,4=0
P 3.7 3.325 3 P 0 8 0;2=1,4=1
P 4.1695 3.09201998 90 P 0 8 0;0,2=8,4=0
P 3.5825 3.4005 2 P 0 8 0;2=7,4=1
P 4.33 3.1432 3 P 0 8 0;2=6,4=1
P 4.4085 3.1432 90 P 0 8 0;0,2=8,4=0
P 3.83 3.235 3 P 0 8 0;2=1,4=1
P 3.769 3.235 95 P 0 8 0;0,2=34,4=0
P 4.085 3.165 3 P 0 8 0;2=6,4=1
P 4.1695 3.1688 90 P 0 8 0;0,2=8,4=0
P 3.415 3.335 2 P 0 8 0;2=7,4=1
P 3.481 3.335 95 P 0 8 0;0,2=34,4=0
P 1.3085 0.658 60 P 0 8 0;0,2=2,4=0
P 1.3085 0.613 60 P 0 8 0;0,2=2,4=0
P 0.805 1.42243996 83 P 0 8 0;0,2=32,4=0
P 0.74 1.3 3 P 0 8 0;2=6,4=1
P 1.2157 0.6586 60 P 0 8 0;0,2=2,4=0
P 1.26 0.62 2 P 0 8 0;2=21,4=1
P 0.785 0.8225 3 P 0 8 0;2=6,4=1
P 0.705 1.42243996 83 P 0 8 0;0,2=32,4=0
P 0.695 1.3 3 P 0 8 0;2=6,4=1
P 0.9575 0.7284 81 P 0 8 0;0,2=5,4=0
P 1.3087 0.708 60 P 0 8 0;0,2=2,4=0
P 1.3087 0.753 60 P 0 8 0;0,2=2,4=0
P 1.1737 0.7086 60 P 0 8 0;0,2=2,4=0
P 1.26 0.67 2 P 0 8 0;2=21,4=1
P 0.76321004 0.783 3 P 0 8 0;2=6,4=1
P 0.76221004 0.7085 43 P 0 8 0;0,2=26,4=0
P 0.606 1.57 3 P 0 8 0;2=1,4=1
P 0.705 1.62756004 83 P 0 8 0;0,2=32,4=0
P 0.835 1.73 3 P 0 8 0;2=1,4=1
P 0.805 1.62756004 83 P 0 8 0;0,2=32,4=0
P 0.355 3.27 3 P 0 8 0;2=1,4=1
P 0.06873996 3.30413996 66 P 0 8 0;0,2=35,4=0
P 0.38 3.231 55 P 0 8 0;0,2=2,4=0
P 0.43 3.231 55 P 0 8 0;0,2=2,4=0
P 0.28 3.27 3 P 0 8 0;2=1,4=1
P 0.08251998 3.2687 49 P 0 8 0;0,2=36,4=0
P 0.28 3.231 55 P 0 8 0;0,2=2,4=0
P 0.33 3.231 55 P 0 8 0;0,2=2,4=0
P 0.13 3.187 3 P 0 8 0;2=1,4=1
P 0.23 3.231 55 P 0 8 0;0,2=2,4=0
P 0.18 3.231 55 P 0 8 0;0,2=2,4=0
P 0.06873996 3.1998 66 P 0 8 0;0,2=35,4=0
P 0.69023002 1.98523996 3 P 0 8 0;2=6,4=1
P 0.74546998 1.975 60 P 0 8 0;0,2=2,4=0
P 0.74546998 1.93 60 P 0 8 0;0,2=2,4=0
P 0.125 2.195 3 P 0 8 0;2=1,4=1
P 0.06873996 2.16241004 66 P 0 8 0;0,2=35,4=0
P 0.69 1.93 3 P 0 8 0;2=6,4=1
P 0.74546998 1.885 60 P 0 8 0;0,2=2,4=0
P 0.74546998 1.84 60 P 0 8 0;0,2=2,4=0
P 0.125 2.145 3 P 0 8 0;2=1,4=1
P 0.08251998 2.12696998 49 P 0 8 0;0,2=36,4=0
P 0.69 1.875 3 P 0 8 0;2=6,4=1
P 0.74546998 1.795 60 P 0 8 0;0,2=2,4=0
P 0.74546998 1.75 60 P 0 8 0;0,2=2,4=0
P 0.125 2.045 3 P 0 8 0;2=1,4=1
P 0.06873996 2.05806998 66 P 0 8 0;0,2=35,4=0
P 0.13 2.73326998 3 P 0 8 0;2=1,4=1
P 0.377 2.70608002 55 P 0 8 0;0,2=2,4=0
P 0.422 2.70608002 55 P 0 8 0;0,2=2,4=0
P 0.06873996 2.73326998 66 P 0 8 0;0,2=35,4=0
P 0.287 2.743 3 P 0 8 0;2=1,4=1
P 0.287 2.70608002 55 P 0 8 0;0,2=2,4=0
P 0.332 2.70608002 55 P 0 8 0;0,2=2,4=0
P 0.08251998 2.69783002 49 P 0 8 0;0,2=36,4=0
P 0.125 2.615 3 P 0 8 0;2=1,4=1
P 0.197 2.70608002 55 P 0 8 0;0,2=2,4=0
P 0.242 2.70608002 55 P 0 8 0;0,2=2,4=0
P 0.06873996 2.62893002 66 P 0 8 0;0,2=35,4=0
P 0.735 1.19 3 P 0 8 0;2=6,4=1
P 0.779 1.25 60 P 0 8 0;0,2=2,4=0
P 0.779 1.3 60 P 0 8 0;0,2=2,4=0
P 0.125 1.06 3 P 0 8 0;2=1,4=1
P 0.06873996 1.02066998 66 P 0 8 0;0,2=35,4=0
P 0.68 1.19 3 P 0 8 0;2=6,4=1
P 0.779 1.2 60 P 0 8 0;0,2=2,4=0
P 0.779 1.15 60 P 0 8 0;0,2=2,4=0
P 0.125 1.01 3 P 0 8 0;2=1,4=1
P 0.08251998 0.98523002 49 P 0 8 0;0,2=36,4=0
P 0.675 1.145 3 P 0 8 0;2=6,4=1
P 0.779 1.1 60 P 0 8 0;0,2=2,4=0
P 0.779 1.05 60 P 0 8 0;0,2=2,4=0
P 0.125 0.91 3 P 0 8 0;2=1,4=1
P 0.06873996 0.91633002 66 P 0 8 0;0,2=35,4=0
P 0.125 1.62 3 P 0 8 0;2=1,4=1
P 0.371 1.56898002 55 P 0 8 0;0,2=2,4=0
P 0.416 1.56898002 55 P 0 8 0;0,2=2,4=0
P 0.06873996 1.59153996 66 P 0 8 0;0,2=35,4=0
P 0.13 1.57 3 P 0 8 0;2=1,4=1
P 0.08251998 1.5561 49 P 0 8 0;0,2=36,4=0
P 0.281 1.56898002 55 P 0 8 0;0,2=2,4=0
P 0.326 1.56898002 55 P 0 8 0;0,2=2,4=0
P 0.1362 1.4872 3 P 0 8 0;2=1,4=1
P 0.06873996 1.4872 66 P 0 8 0;0,2=35,4=0
P 0.191 1.56898002 55 P 0 8 0;0,2=2,4=0
P 0.236 1.56898002 55 P 0 8 0;0,2=2,4=0
P 2.937 3.173 3 P 0 8 0;2=1,4=1
P 3.0425 3.22543002 90 P 0 8 0;0,2=8,4=0
P 2.937 3.206 60 P 0 8 0;0,2=2,4=0
P 3.01 3.17 3 P 0 8 0;2=6,4=1
P 0.896 2.489 2 P 0 8 0;2=7,4=1
P 0.8594 2.4275 48 P 0 8 0;0,2=37,4=0
P 4.2391 4.01168996 82 P 0 8 0;0,2=0,4=0
P 4.31168996 4.01168996 2 P 0 8 0;2=7,4=1
P 4.354 4.015 60 P 0 8 0;0,2=2,4=0
P 4.2391 3.95263002 82 P 0 8 0;0,2=0,4=0
P 4.319 3.922 2 P 0 8 0;2=7,4=1
P 4.354 3.915 60 P 0 8 0;0,2=2,4=0
P 4.5 4.115 3 P 0 8 0;2=1,4=1
P 4.396 4.065 60 P 0 8 0;0,2=2,4=0
P 1.315 2.905 2 P 0 8 0;2=23,4=1
P 2.932 3.295 2 P 0 8 0;2=23,4=1
P 2.895 3.259 60 P 0 8 0;0,2=2,4=0
P 0.915 1.4 3 P 0 8 0;2=6,4=1
P 1.42 0.69535 2 P 0 8 0;2=21,4=1
P 1.3505 0.658 60 P 0 8 0;0,2=2,4=0
P 4.5 4.165 3 P 0 8 0;2=1,4=1
P 4.396 4.115 60 P 0 8 0;0,2=2,4=0
P 1.36 2.905 2 P 0 8 0;2=23,4=1
P 2.896 3.301 2 P 0 8 0;2=23,4=1
P 2.896 3.332 60 P 0 8 0;0,2=2,4=0
P 0.965 1.4 3 P 0 8 0;2=6,4=1
P 1.3507 0.753 60 P 0 8 0;0,2=2,4=0
P 1.4207 0.779 2 P 0 8 0;2=21,4=1
P 4.63965 2.00091004 4 P 0 8 0;0,2=4,4=0
P 4.33 3.535 3 P 0 8 0;2=6,4=1
P 4.44 4.065 2 P 0 8 0;2=7,4=1
P 4.395 3.415 2 P 0 8 0;2=23,4=1
P 4.60028002 2.04028002 4 P 0 8 0;0,2=4,4=0
P 4.44 4.115 2 P 0 8 0;2=7,4=1
P 4.425 3.36088996 2 P 0 8 0;2=23,4=1
P 4.60028002 2.07965 4 P 0 8 0;0,2=4,4=0
P 0.638 2.74 2 P 0 8 0;2=23,4=1
P 0.8338 2.2465 48 P 0 8 0;0,2=37,4=0
P 0.825 2.305 2 P 0 8 0;2=7,4=1
P 0.64248002 2.664 60 P 0 8 0;0,2=2,4=0
P 0.64248002 2.709 60 P 0 8 0;0,2=2,4=0
P 0.80648002 2.831 55 P 0 8 0;0,2=2,4=0
P 0.756 2.79 60 P 0 8 0;0,2=2,4=0
P 0.755 2.825 2 P 0 8 0;2=23,4=1
P 0.795 2.345 2 P 0 8 0;2=7,4=1
P 0.8082 2.2465 48 P 0 8 0;0,2=37,4=0
P 5.97613002 4.13778996 3 P 0 8 0;2=1,4=1
P 6.02558996 4.13778996 19 P 0 8 0;0,2=31,4=0
P 5.90748002 4.18725 3 P 0 8 0;2=1,4=1
P 5.90748002 4.13778996 19 P 0 8 0;0,2=31,4=0
P 0.78746998 1.84 60 P 0 8 0;0,2=2,4=0
P 0.905 1.935 3 P 0 8 0;2=1,4=1
P 4.08846998 2.00091004 4 P 0 8 0;0,2=4,4=0
P 0.945 1.97 3 P 0 8 0;2=1,4=1
P 4.00973002 2.04028002 4 P 0 8 0;0,2=4,4=0
P 0.78746998 1.975 60 P 0 8 0;0,2=2,4=0
P 0.905 1.885 3 P 0 8 0;2=1,4=1
P 4.0491 2.04028002 4 P 0 8 0;0,2=4,4=0
P 0.78746998 1.795 60 P 0 8 0;0,2=2,4=0
P 0.63 2.15 3 P 0 8 0;2=6,4=1
P 0.985 2.185 3 P 0 8 0;2=1,4=1
P 3.97035 2.00091004 4 P 0 8 0;0,2=4,4=0
P 0.287 2.62508002 3 P 0 8 0;2=6,4=1
P 0.287 2.66408002 55 P 0 8 0;0,2=2,4=0
P 0.43 2.555 3 P 0 8 0;2=1,4=1
P 0.422 2.66408002 55 P 0 8 0;0,2=2,4=0
P 0.63 2.105 3 P 0 8 0;2=6,4=1
P 0.99 2.015 3 P 0 8 0;2=6,4=1
P 3.97035 1.96153996 4 P 0 8 0;0,2=4,4=0
P 0.242 2.62508002 3 P 0 8 0;2=1,4=1
P 0.242 2.66408002 55 P 0 8 0;0,2=2,4=0
P 0.63 2.06 3 P 0 8 0;2=6,4=1
P 0.99 1.975 3 P 0 8 0;2=6,4=1
P 4.00973002 1.96153996 4 P 0 8 0;0,2=4,4=0
P 0.935 1.3 3 P 0 8 0;2=1,4=1
P 0.821 1.15 60 P 0 8 0;0,2=2,4=0
P 4.0491 1.80406004 4 P 0 8 0;0,2=4,4=0
P 0.87 1.255 3 P 0 8 0;2=1,4=1
P 0.821 1.25 60 P 0 8 0;0,2=2,4=0
P 3.97035 1.8828 4 P 0 8 0;0,2=4,4=0
P 0.935 1.25 3 P 0 8 0;2=1,4=1
P 0.821 1.1 60 P 0 8 0;0,2=2,4=0
P 3.97035 1.84343002 4 P 0 8 0;0,2=4,4=0
P 0.92 1.73 3 P 0 8 0;2=1,4=1
P 4.08846998 1.92216998 4 P 0 8 0;0,2=4,4=0
P 0.281 1.48798002 3 P 0 8 0;2=6,4=1
P 0.281 1.52698002 55 P 0 8 0;0,2=2,4=0
P 0.985 1.655 3 P 0 8 0;2=1,4=1
P 4.08846998 1.84343002 4 P 0 8 0;0,2=4,4=0
P 0.371 1.52698002 55 P 0 8 0;0,2=2,4=0
P 0.371 1.48798002 3 P 0 8 0;2=6,4=1
P 4.08846998 1.80406004 4 P 0 8 0;0,2=4,4=0
P 0.985 1.59 3 P 0 8 0;2=1,4=1
P 0.236 1.52698002 55 P 0 8 0;0,2=2,4=0
P 0.236 1.48798002 3 P 0 8 0;2=6,4=1
P 0.28 3.189 55 P 0 8 0;0,2=2,4=0
P 0.345 3.09 3 P 0 8 0;2=6,4=1
P 3.84091004 2.00091004 3 P 0 8 0;2=1,4=1
P 3.89161004 2.00091004 4 P 0 8 0;0,2=4,4=0
P 0.99 1.885 3 P 0 8 0;2=6,4=1
P 0.38 3.189 55 P 0 8 0;0,2=2,4=0
P 0.395 3.09 3 P 0 8 0;2=6,4=1
P 3.89161004 2.07965 4 P 0 8 0;0,2=4,4=0
P 0.99 2.065 3 P 0 8 0;2=6,4=1
P 0.23 3.189 55 P 0 8 0;0,2=2,4=0
P 0.445 3.09 3 P 0 8 0;2=1,4=1
P 0.975 2.14 3 P 0 8 0;2=6,4=1
P 3.93098002 2.07965 4 P 0 8 0;0,2=4,4=0
P 0.55708002 1.92086998 35 P 0 8 0;0,2=38,4=0
P 0.53 2.005 3 P 0 8 0;2=1,4=1
P 0.53 2.049 55 P 0 8 0;0,2=2,4=0
P 0.552 2.535 3 P 0 8 0;2=1,4=1
P 0.55708002 2.49173996 35 P 0 8 0;0,2=38,4=0
P 0.53 2.584 55 P 0 8 0;0,2=2,4=0
P 0.455 1.825 3 P 0 8 0;2=1,4=1
P 0.455 1.781 55 P 0 8 0;0,2=2,4=0
P 0.16038996 1.85433002 8 P 0 8 0;2=39,4=0
P 0.2725 2.0965 72 P 0 8 0;0,2=40,4=0
P 0.46 2.195 3 P 0 8 0;2=1,4=1
P 0.46451998 2.233 55 P 0 8 0;0,2=2,4=0
P 0.16038996 2.4252 8 P 0 8 0;2=39,4=0
P 0.2725 2.1835 72 P 0 8 0;0,2=40,4=0
P 0.445 0.735 3 P 0 8 0;2=1,4=1
P 0.16038996 0.7126 8 P 0 8 0;2=39,4=0
P 0.2725 0.9565 72 P 0 8 0;0,2=40,4=0
P 0.455 1.0839 55 P 0 8 0;0,2=2,4=0
P 0.455 1.0439 3 P 0 8 0;2=1,4=1
P 0.16038996 1.28346004 8 P 0 8 0;2=39,4=0
P 0.2725 1.0435 72 P 0 8 0;0,2=40,4=0
P 0.535 1.835 3 P 0 8 0;2=1,4=1
P 0.455 1.739 55 P 0 8 0;0,2=2,4=0
P 0.455 1.686 55 P 0 8 0;0,2=2,4=0
P 0.51771998 1.78778996 35 P 0 8 0;0,2=38,4=0
P 0.5374 1.78778996 35 P 0 8 0;0,2=38,4=0
P 0.532 2.40186998 3 P 0 8 0;2=1,4=1
P 0.46451998 2.275 55 P 0 8 0;0,2=2,4=0
P 0.51771998 2.35866004 35 P 0 8 0;0,2=38,4=0
P 0.5374 2.35866004 35 P 0 8 0;0,2=38,4=0
P 0.452 2.326 55 P 0 8 0;0,2=2,4=0
P 0.505 0.60228002 3 P 0 8 0;2=1,4=1
P 0.5374 0.64606004 35 P 0 8 0;0,2=38,4=0
P 0.51771998 0.64606004 35 P 0 8 0;0,2=38,4=0
P 0.443 0.647 55 P 0 8 0;0,2=2,4=0
P 0.5374 1.26 3 P 0 8 0;2=1,4=1
P 0.5374 1.21691998 35 P 0 8 0;0,2=38,4=0
P 0.51771998 1.21691998 35 P 0 8 0;0,2=38,4=0
P 0.455 1.178 55 P 0 8 0;0,2=2,4=0
P 0.455 1.1259 55 P 0 8 0;0,2=2,4=0
P 0.48 2.005 3 P 0 8 0;2=1,4=1
P 0.5374 1.92086998 35 P 0 8 0;0,2=38,4=0
P 0.48 2.049 55 P 0 8 0;0,2=2,4=0
P 0.485 2.525 3 P 0 8 0;2=1,4=1
P 0.5374 2.49173996 35 P 0 8 0;0,2=38,4=0
P 0.478 2.569 55 P 0 8 0;0,2=2,4=0
P 0.515 0.835 3 P 0 8 0;2=1,4=1
P 0.485 0.884 55 P 0 8 0;0,2=2,4=0
P 0.5374 0.77913996 35 P 0 8 0;0,2=38,4=0
P 0.475 1.405 3 P 0 8 0;2=1,4=1
P 0.48 1.444 55 P 0 8 0;0,2=2,4=0
P 0.5374 1.35 35 P 0 8 0;0,2=38,4=0
P 6.2655 1.0066 89 P 0 8 0;0,2=37,4=0
P 6.335 0.965 3 P 0 8 0;2=1,4=1
P 6.379 0.965 60 P 0 8 0;0,2=2,4=0
P 6.2655 1.0322 89 P 0 8 0;0,2=37,4=0
P 6.335 1.02 3 P 0 8 0;2=1,4=1
P 6.379 1.02 60 P 0 8 0;0,2=2,4=0
P 6.379 1.08 60 P 0 8 0;0,2=2,4=0
P 6.2655 1.0578 89 P 0 8 0;0,2=37,4=0
P 6.335 1.08 3 P 0 8 0;2=1,4=1
P 2.0966 3.0845 48 P 0 8 0;0,2=37,4=0
P 2.085 3.017 2 P 0 8 0;2=21,4=1
P 2.083 2.973 55 P 0 8 0;0,2=2,4=0
P 2.1222 3.0845 48 P 0 8 0;0,2=37,4=0
P 2.135 3.017 2 P 0 8 0;2=21,4=1
P 2.128 2.973 55 P 0 8 0;0,2=2,4=0
P 2.1478 3.0845 48 P 0 8 0;0,2=37,4=0
P 2.185 3.017 2 P 0 8 0;2=21,4=1
P 2.173 2.973 55 P 0 8 0;0,2=2,4=0
P 5.956 1.08 60 P 0 8 0;0,2=2,4=0
P 6.0085 1.1235 3 P 0 8 0;2=1,4=1
P 6.0845 1.0834 89 P 0 8 0;0,2=37,4=0
P 2.1734 3.2655 48 P 0 8 0;0,2=37,4=0
P 2.2628 3.287 55 P 0 8 0;0,2=2,4=0
P 2.22 3.3 2 P 0 8 0;2=21,4=1
P 5.956 0.965 60 P 0 8 0;0,2=2,4=0
P 6.0845 1.0322 89 P 0 8 0;0,2=37,4=0
P 4.32468996 2.00091004 4 P 0 8 0;0,2=4,4=0
P 5.285 2.99 2 P 0 8 0;2=23,4=1
P 4.32468996 2.15838996 4 P 0 8 0;0,2=4,4=0
P 3.125 3.075 3 P 0 8 0;2=6,4=1
P 1.959 3.247 55 P 0 8 0;0,2=2,4=0
P 2.1222 3.2655 48 P 0 8 0;0,2=37,4=0
P 2.97 3.105 3 P 0 8 0;2=1,4=1
P 4.36406004 2.15838996 4 P 0 8 0;0,2=4,4=0
P 6.01843996 2.815 28 P 0 8 0;0,2=32,4=0
P 5.91 2.785 3 P 0 8 0;2=1,4=1
P 6.01843996 2.615 28 P 0 8 0;0,2=32,4=0
P 5.91 2.615 2 P 0 8 0;2=21,4=1
P 4.985 3.504 55 P 0 8 0;0,2=2,4=0
P 5.91 2.915 3 P 0 8 0;2=1,4=1
P 6.01843996 2.915 28 P 0 8 0;0,2=32,4=0
P 4.885 3.504 55 P 0 8 0;0,2=2,4=0
P 5.91 2.715 3 P 0 8 0;2=1,4=1
P 6.01843996 2.715 28 P 0 8 0;0,2=32,4=0
P 0.54 2.135 3 P 0 8 0;2=6,4=1
P 0.53 2.091 55 P 0 8 0;0,2=2,4=0
P 0.67 1.09 3 P 0 8 0;2=1,4=1
P 4.60028002 1.68595 4 P 0 8 0;0,2=4,4=0
P 0.48 2.091 55 P 0 8 0;0,2=2,4=0
P 0.45 2.13 3 P 0 8 0;2=6,4=1
P 4.67901998 2.07965 4 P 0 8 0;0,2=4,4=0
P 0.965 2.355 3 P 0 8 0;2=1,4=1
P 4.56091004 1.68595 4 P 0 8 0;0,2=4,4=0
P 0.735 1.125 3 P 0 8 0;2=1,4=1
P 0.48231998 2.6453 3 P 0 8 0;2=6,4=1
P 0.53 2.626 55 P 0 8 0;0,2=2,4=0
P 3.755 3.505 2 P 0 8 0;2=23,4=1
P 4.67901998 2.11901998 4 P 0 8 0;0,2=4,4=0
P 0.525 2.78 3 P 0 8 0;2=6,4=1
P 0.478 2.611 55 P 0 8 0;0,2=2,4=0
P 4.6 0.76 3 P 0 8 0;2=6,4=1
P 4.60028002 1.76468996 4 P 0 8 0;0,2=4,4=0
P 0.905 1.05 3 P 0 8 0;2=6,4=1
P 4.175 0.75 3 P 0 8 0;2=6,4=1
P 0.51765 0.966 2 P 0 8 0;2=7,4=1
P 0.535 0.926 55 P 0 8 0;0,2=2,4=0
P 2.078 0.8301 3 P 0 8 0;2=6,4=1
P 0.485 0.926 55 P 0 8 0;0,2=2,4=0
P 0.46 0.82 2 P 0 8 0;2=7,4=1
P 4.63965 1.76468996 4 P 0 8 0;0,2=4,4=0
P 0.53 1.486 55 P 0 8 0;0,2=2,4=0
P 0.5413 1.525 3 P 0 8 0;2=1,4=1
P 4.60028002 1.72531998 4 P 0 8 0;0,2=4,4=0
P 0.625 1.005 3 P 0 8 0;2=6,4=1
P 4.63965 1.72531998 4 P 0 8 0;0,2=4,4=0
P 0.935 1.105 3 P 0 8 0;2=1,4=1
P 0.48 1.486 55 P 0 8 0;0,2=2,4=0
P 0.4839 1.28311998 3 P 0 8 0;2=6,4=1
P 1.128 0.666 2 P 0 8 0;2=7,4=1
P 0.9575 0.6536 81 P 0 8 0;0,2=5,4=0
P 1.1737 0.6586 60 P 0 8 0;0,2=2,4=0
P 5.97613002 4.27558002 3 P 0 8 0;2=1,4=1
P 6.02558996 4.27558002 19 P 0 8 0;0,2=31,4=0
P 4.16721004 1.84343002 4 P 0 8 0;0,2=4,4=0
P 0.945 1.63 3 P 0 8 0;2=6,4=1
P 0.58 0.884 55 P 0 8 0;0,2=2,4=0
P 0.57676004 0.77913996 35 P 0 8 0;0,2=38,4=0
P 4.20658002 1.84343002 4 P 0 8 0;0,2=4,4=0
P 0.975 1.72 3 P 0 8 0;2=6,4=1
P 0.55708002 0.64606004 35 P 0 8 0;0,2=38,4=0
P 0.555 0.59 3 P 0 8 0;2=1,4=1
P 4.0489 3.95263002 82 P 0 8 0;0,2=0,4=0
P 3.935 3.91 2 P 0 8 0;2=21,4=1
P 0.835 1.885 3 P 0 8 0;2=6,4=1
P 0.78746998 1.885 60 P 0 8 0;0,2=2,4=0
P 4.0489 3.97231004 82 P 0 8 0;0,2=0,4=0
P 3.885 3.91 2 P 0 8 0;2=21,4=1
P 0.835 1.93 3 P 0 8 0;2=6,4=1
P 0.78746998 1.93 60 P 0 8 0;0,2=2,4=0
P 4.0474 3.93293996 79 P 0 8 0;0,2=3,4=0
P 3.985 3.91 2 P 0 8 0;2=21,4=1
P 0.835 1.78 3 P 0 8 0;2=6,4=1
P 0.78746998 1.75 60 P 0 8 0;0,2=2,4=0
P 0.58 1.444 55 P 0 8 0;0,2=2,4=0
P 0.57676004 1.35 35 P 0 8 0;0,2=38,4=0
P 4.20658002 1.8828 4 P 0 8 0;0,2=4,4=0
P 0.955 1.92 3 P 0 8 0;2=6,4=1
P 0.55708002 1.21691998 35 P 0 8 0;0,2=38,4=0
P 0.505 1.1259 55 P 0 8 0;0,2=2,4=0
P 4.16721004 1.8828 4 P 0 8 0;0,2=4,4=0
P 0.885 1.49 3 P 0 8 0;2=1,4=1
P 0.99 1.755 3 P 0 8 0;2=6,4=1
P 4.0489 4.03136998 82 P 0 8 0;0,2=0,4=0
P 3.935 4 2 P 0 8 0;2=23,4=1
P 0.332 2.62508002 3 P 0 8 0;2=1,4=1
P 0.332 2.66408002 55 P 0 8 0;0,2=2,4=0
P 4.0474 4.05106004 79 P 0 8 0;0,2=3,4=0
P 3.885 4 2 P 0 8 0;2=23,4=1
P 0.405 2.62 3 P 0 8 0;2=1,4=1
P 0.377 2.66408002 55 P 0 8 0;0,2=2,4=0
P 4.0489 4.01168996 82 P 0 8 0;0,2=0,4=0
P 3.985 4 2 P 0 8 0;2=23,4=1
P 0.19 2.625 3 P 0 8 0;2=1,4=1
P 0.197 2.66408002 55 P 0 8 0;0,2=2,4=0
P 0.57676004 1.92086998 35 P 0 8 0;0,2=38,4=0
P 0.575 2.049 55 P 0 8 0;0,2=2,4=0
P 4.32468996 1.80406004 4 P 0 8 0;0,2=4,4=0
P 0.75 1.417 3 P 0 8 0;2=6,4=1
P 4.28531998 1.80406004 4 P 0 8 0;0,2=4,4=0
P 0.952 1.51 3 P 0 8 0;2=1,4=1
P 0.556 1.65 60 P 0 8 0;0,2=2,4=0
P 0.55708002 1.78778996 35 P 0 8 0;0,2=38,4=0
P 4.10463002 4.0871 39 P 0 8 0;0,2=41,4=0
P 0.415 1.275 3 P 0 8 0;2=6,4=1
P 0.821 1.2 60 P 0 8 0;0,2=2,4=0
P 0.87 1.2 3 P 0 8 0;2=6,4=1
P 0.7558 4.19003996 2 P 0 8 0;2=21,4=1
P 3.98 4.185 2 P 0 8 0;2=23,4=1
P 4.12431004 4.0871 39 P 0 8 0;0,2=41,4=0
P 0.465 1.33 3 P 0 8 0;2=6,4=1
P 0.821 1.3 60 P 0 8 0;0,2=2,4=0
P 0.87 1.3 3 P 0 8 0;2=6,4=1
P 0.705 4.19 2 P 0 8 0;2=21,4=1
P 4.03 4.185 2 P 0 8 0;2=23,4=1
P 4.08493996 4.0886 38 P 0 8 0;0,2=42,4=0
P 0.41408996 1.32591004 3 P 0 8 0;2=6,4=1
P 0.821 1.05 60 P 0 8 0;0,2=2,4=0
P 0.89 1.105 3 P 0 8 0;2=6,4=1
P 0.805 4.205 3 P 0 8 0;2=1,4=1
P 3.93 4.185 2 P 0 8 0;2=23,4=1
P 4.24595 1.80406004 4 P 0 8 0;0,2=4,4=0
P 0.939 1.552 3 P 0 8 0;2=6,4=1
P 0.57676004 2.49173996 35 P 0 8 0;0,2=38,4=0
P 0.578 2.569 55 P 0 8 0;0,2=2,4=0
P 0.51451998 2.275 55 P 0 8 0;0,2=2,4=0
P 0.55708002 2.35866004 35 P 0 8 0;0,2=38,4=0
P 4.24595 1.84343002 4 P 0 8 0;0,2=4,4=0
P 0.957 2.275 3 P 0 8 0;2=1,4=1
P 4.18336998 4.0871 39 P 0 8 0;0,2=41,4=0
P 4.168 4.24 2 P 0 8 0;2=23,4=1
P 0.855 4.205 2 P 0 8 0;2=23,4=1
P 0.15 2.79 3 P 0 8 0;2=1,4=1
P 0.326 1.487 3 P 0 8 0;2=6,4=1
P 0.326 1.52698002 55 P 0 8 0;0,2=2,4=0
P 4.20306004 4.0886 38 P 0 8 0;0,2=42,4=0
P 0.09 2.86 3 P 0 8 0;2=1,4=1
P 0.9 4.205 2 P 0 8 0;2=23,4=1
P 4.22336998 4.24 2 P 0 8 0;2=23,4=1
P 0.416 1.52698002 55 P 0 8 0;0,2=2,4=0
P 0.416 1.48798002 3 P 0 8 0;2=6,4=1
P 4.16368996 4.0871 39 P 0 8 0;0,2=41,4=0
P 0.09 2.79 3 P 0 8 0;2=1,4=1
P 0.98 4.2 2 P 0 8 0;2=23,4=1
P 4.14 4.19 2 P 0 8 0;2=23,4=1
P 0.191 1.52698002 55 P 0 8 0;0,2=2,4=0
P 0.191 1.48798002 3 P 0 8 0;2=6,4=1
P 4.10463002 3.8969 39 P 0 8 0;0,2=41,4=0
P 4.10463002 3.83 2 P 0 8 0;2=21,4=1
P 0.33 3.145 3 P 0 8 0;2=6,4=1
P 0.33 3.189 55 P 0 8 0;0,2=2,4=0
P 4.08493996 3.8954 38 P 0 8 0;0,2=42,4=0
P 4.05463002 3.83 2 P 0 8 0;2=21,4=1
P 0.43 3.145 3 P 0 8 0;2=6,4=1
P 0.43 3.189 55 P 0 8 0;0,2=2,4=0
P 4.12431004 3.8969 39 P 0 8 0;0,2=41,4=0
P 4.15463002 3.83 2 P 0 8 0;2=21,4=1
P 0.18 3.145 3 P 0 8 0;2=6,4=1
P 0.18 3.189 55 P 0 8 0;0,2=2,4=0
P 0.89848002 2.632 61 P 0 8 0;0,2=16,4=0
P 0.76948002 2.525 55 P 0 8 0;0,2=2,4=0
P 0.64248002 2.614 60 P 0 8 0;0,2=2,4=0
P 0.80648002 2.789 55 P 0 8 0;0,2=2,4=0
P 0.81998996 2.68068996 42 P 0 8 0;0,2=43,4=0
P 0.909 2.728 60 P 0 8 0;0,2=2,4=0
P 0.90848002 2.683 60 P 0 8 0;0,2=2,4=0
P 0.869 2.672 3 P 0 8 0;2=6,4=1
P 0.871 2.713 2 P 0 8 0;2=7,4=1
P 0.686 2.74 2 P 0 8 0;2=23,4=1
P 0.68448002 2.709 60 P 0 8 0;0,2=2,4=0
P 0.64248002 2.58 3 P 0 8 0;2=6,4=1
P 0.736 2.525 2 P 0 8 0;2=23,4=1
P 0.714 2.329 3 P 0 8 0;2=6,4=1
P 0.7826 2.2465 48 P 0 8 0;0,2=37,4=0
P 0.714 2.294 55 P 0 8 0;0,2=2,4=0
P 3.429 2.468 2 P 0 8 0;2=7,4=1
P 3.435 2.511 55 P 0 8 0;0,2=2,4=0
P 3.491 2.509 65 P 0 8 0;0,2=16,4=0
P 3.38483996 2.511 55 P 0 8 0;0,2=2,4=0
P 3.45151998 2.3829 57 P 0 8 0;0,2=44,4=0
P 3.39983996 2.40503996 29 P 0 8 0;0,2=45,4=0
P 3.51 2.33243002 3 P 0 8 0;2=6,4=1
P 3.45151998 2.34353002 57 P 0 8 0;0,2=44,4=0
P 3.57 2.33243002 86 P 0 8 0;0,2=46,4=0
P 3.63673002 2.34643002 44 P 0 8 0;0,2=12,4=0
P 3.278 2.468 2 P 0 8 0;2=7,4=1
P 3.285 2.511 55 P 0 8 0;0,2=2,4=0
P 3.36046998 2.40503996 29 P 0 8 0;0,2=45,4=0
P 3.243 2.547 2 P 0 8 0;2=7,4=1
P 3.201 2.569 60 P 0 8 0;0,2=2,4=0
P 3.32848002 2.40258002 57 P 0 8 0;0,2=44,4=0
P 3.39983996 2.22296004 29 P 0 8 0;0,2=45,4=0
P 3.24 2.36 2 P 0 8 0;2=7,4=1
P 3.32848002 2.32383996 57 P 0 8 0;0,2=44,4=0
P 3.201 2.479 60 P 0 8 0;0,2=2,4=0
P 3.201 2.434 60 P 0 8 0;0,2=2,4=0
P 3.285 2.38645 2 P 0 8 0;2=7,4=1
P 3.201 2.524 60 P 0 8 0;0,2=2,4=0
P 3.32848002 2.34353002 57 P 0 8 0;0,2=44,4=0
P 0.835 2.566 55 P 0 8 0;0,2=2,4=0
P 0.832 2.603 3 P 0 8 0;2=1,4=1
P 0.79931998 2.63048996 32 P 0 8 0;0,2=47,4=0
P 0.76948002 2.567 55 P 0 8 0;0,2=2,4=0
P 0.77963996 2.601 2 P 0 8 0;2=7,4=1
P 0.77963996 2.63048996 32 P 0 8 0;0,2=47,4=0
P 0.68448002 2.614 60 P 0 8 0;0,2=2,4=0
P 0.695 2.578 3 P 0 8 0;2=1,4=1
P 0.75896998 2.64131004 42 P 0 8 0;0,2=43,4=0
P 0.661 2.79 60 P 0 8 0;0,2=2,4=0
P 0.72 2.714 2 P 0 8 0;2=7,4=1
P 0.75896998 2.68068996 42 P 0 8 0;0,2=43,4=0
P 0.825 2.732 2 P 0 8 0;2=7,4=1
P 0.79931998 2.69151004 32 P 0 8 0;0,2=47,4=0
P 6.01953002 2.14381998 36 P 0 8 0;0,2=19,4=0
P 6.033 2.324 61 P 0 8 0;0,2=16,4=0
P 6.01953002 2.18853002 3 P 0 8 0;2=1,4=1
P 6.029 2.27 60 P 0 8 0;0,2=2,4=0
P 6.029 2.225 60 P 0 8 0;0,2=2,4=0
P 4.41975 2.92521004 63 P 0 8 0;0,2=48,4=0
P 4.524 2.995 60 P 0 8 0;0,2=2,4=0
P 4.415 2.975 2 P 0 8 0;2=7,4=1
P 6.09423996 4.27558002 3 P 0 8 0;2=1,4=1
P 6.1437 4.27558002 19 P 0 8 0;0,2=31,4=0
P 0.959 2.789 3 P 0 8 0;2=6,4=1
P 0.845 2.18 3 P 0 8 0;2=1,4=1
P 0.804 2.15103996 70 P 0 8 0;0,2=49,4=0
P 5.99983996 2.14381998 36 P 0 8 0;0,2=19,4=0
P 5.94153002 2.205 2 P 0 8 0;2=21,4=1
P 5.94153002 2.33 60 P 0 8 0;0,2=2,4=0
P 5.94153002 2.28401998 60 P 0 8 0;0,2=2,4=0
P 5.94153002 2.239 60 P 0 8 0;0,2=2,4=0
P 5.99983996 2.04418002 36 P 0 8 0;0,2=19,4=0
P 6.01901998 2.001 2 P 0 8 0;2=21,4=1
P 6.01901998 1.95065 55 P 0 8 0;0,2=2,4=0
P 3.4593 2.17 2 P 0 8 0;2=21,4=1
P 3.45151998 2.22541998 57 P 0 8 0;0,2=44,4=0
P 3.44 2.12 3 P 0 8 0;2=1,4=1
P 3.41953002 2.22296004 29 P 0 8 0;0,2=45,4=0
P 3.18 2.685 2 P 0 8 0;2=7,4=1
P 4.32468996 1.92216998 4 P 0 8 0;0,2=4,4=0
P 3.523 1.75 2 P 0 8 0;2=23,4=1
P 3.554 1.74548996 55 P 0 8 0;0,2=2,4=0
P 4.40343002 1.52846998 4 P 0 8 0;0,2=4,4=0
P 4.60028002 1.64658002 4 P 0 8 0;0,2=4,4=0
P 4.36406004 1.4891 4 P 0 8 0;0,2=4,4=0
P 4.32468996 1.52846998 4 P 0 8 0;0,2=4,4=0
P 4.63965 1.60721004 4 P 0 8 0;0,2=4,4=0
P 4.32468996 1.4891 4 P 0 8 0;0,2=4,4=0
P 4.40343002 1.37098002 4 P 0 8 0;0,2=4,4=0
P 4.36406004 1.37098002 4 P 0 8 0;0,2=4,4=0
P 4.71838996 1.60721004 4 P 0 8 0;0,2=4,4=0
P 4.40343002 1.4891 4 P 0 8 0;0,2=4,4=0
P 4.56091004 1.64658002 4 P 0 8 0;0,2=4,4=0
P 4.40343002 1.44973002 4 P 0 8 0;0,2=4,4=0
P 4.4428 1.33161004 4 P 0 8 0;0,2=4,4=0
P 4.40343002 1.33161004 4 P 0 8 0;0,2=4,4=0
P 3.83128002 1.78371998 2 P 0 8 0;2=23,4=1
P 6.02558996 4.175 3 P 0 8 0;2=1,4=1
P 6.02558996 4.21653996 19 P 0 8 0;0,2=31,4=0
P 3.89161004 1.80406004 4 P 0 8 0;0,2=4,4=0
P 6.1437 4.175 3 P 0 8 0;2=1,4=1
P 6.1437 4.21653996 19 P 0 8 0;0,2=31,4=0
P 3.89161004 1.84343002 4 P 0 8 0;0,2=4,4=0
P 4.16721004 2.04028002 4 P 0 8 0;0,2=4,4=0
P 5.83 2.97 3 P 0 8 0;2=6,4=1
P 5.89953002 2.366 2 P 0 8 0;2=21,4=1
P 5.89953002 2.33 60 P 0 8 0;0,2=2,4=0
P 3.61123996 3.49876004 2 P 0 8 0;2=7,4=1
P 4.52153996 1.92216998 4 P 0 8 0;0,2=4,4=0
P 4.24595 1.92216998 4 P 0 8 0;0,2=4,4=0
P 1.96496998 0.76501998 2 P 0 8 0;2=21,4=1
P 1.9977 0.632 55 P 0 8 0;0,2=2,4=0
P 3.12 2.565 3 P 0 8 0;2=6,4=1
P 3.119 2.299 3 P 0 8 0;2=1,4=1
P 3.159 2.299 60 P 0 8 0;0,2=2,4=0
P 4.20658002 1.96153996 4 P 0 8 0;0,2=4,4=0
P 3.385 2.59 3 P 0 8 0;2=1,4=1
P 4.28531998 1.8828 4 P 0 8 0;0,2=4,4=0
P 5.155 2.01 3 P 0 8 0;2=6,4=1
P 6.025 1.83 3 P 0 8 0;2=1,4=1
P 6.01901998 1.90865 55 P 0 8 0;0,2=2,4=0
P 4.20658002 2.04028002 4 P 0 8 0;0,2=4,4=0
P 4.32468996 1.8828 4 P 0 8 0;0,2=4,4=0
P 2.554 2.901 3 P 0 8 0;2=1,4=1
P 4.884 1.675 60 P 0 8 0;0,2=2,4=0
P 4.884 1.63 60 P 0 8 0;0,2=2,4=0
P 4.67901998 1.64658002 4 P 0 8 0;0,2=4,4=0
P 3.205 1.7 3 P 0 8 0;2=1,4=1
P 3.166 1.695 60 P 0 8 0;0,2=2,4=0
P 3.166 1.645 60 P 0 8 0;0,2=2,4=0
P 4.71838996 1.68595 4 P 0 8 0;0,2=4,4=0
P 4.775 1.705 3 P 0 8 0;2=6,4=1
P 4.84 1.855 3 P 0 8 0;2=1,4=1
P 4.56091004 1.80406004 4 P 0 8 0;0,2=4,4=0
P 4.63965 1.84343002 4 P 0 8 0;0,2=4,4=0
P 4.815 1.93 3 P 0 8 0;2=1,4=1
P 4.885 3.46 3 P 0 8 0;2=6,4=1
P 4.835 3.504 55 P 0 8 0;0,2=2,4=0
P 4.83501004 3.46 3 P 0 8 0;2=1,4=1
P 4.60028002 1.84343002 4 P 0 8 0;0,2=4,4=0
P 3.125 2.254 3 P 0 8 0;2=6,4=1
P 3.159 2.209 60 P 0 8 0;0,2=2,4=0
P 3.159 2.254 60 P 0 8 0;0,2=2,4=0
P 4.28531998 1.84343002 4 P 0 8 0;0,2=4,4=0
P 3.12 2.69 3 P 0 8 0;2=6,4=1
P 4.565 3.055 3 P 0 8 0;2=6,4=1
P 4.3 3.81 3 P 0 8 0;2=1,4=1
P 1.3825 3.7225 2 P 0 8 0;2=23,4=1
P 1.425 3.851 60 P 0 8 0;0,2=2,4=0
P 5.905 3.015 2 P 0 8 0;2=21,4=1
P 6.01843996 3.015 28 P 0 8 0;0,2=32,4=0
P 4.85033002 1.74933996 3 P 0 8 0;2=6,4=1
P 4.52153996 1.76468996 4 P 0 8 0;0,2=4,4=0
P 4.566 2.995 60 P 0 8 0;0,2=2,4=0
P 5.26 2.955 3 P 0 8 0;2=6,4=1
P 3.625 0.92 2 P 0 8 0;2=33,4=1
P 3.58206998 1.92336004 67 P 0 8 0;0,2=50,4=0
P 6.19961004 2.27673996 2 P 0 8 0;2=33,4=1
P 6.30728996 2.20183996 51 P 0 8 0;0,2=5,4=0
P 6.4105 2.11023996 84 P 0 8 0;0,2=51,4=0
P 6.23248996 2.20183996 51 P 0 8 0;0,2=5,4=0
P 6.4105 2.08465 84 P 0 8 0;0,2=51,4=0
P 3.58206998 1.93911004 67 P 0 8 0;0,2=50,4=0
P 3.657 0.92 2 P 0 8 0;2=33,4=1
P 6.19961004 2.24473996 2 P 0 8 0;2=33,4=1
P 3.3255 2.1355 3 P 0 8 0;2=1,4=1
P 3.201 2.164 60 P 0 8 0;0,2=2,4=0
P 3.296 2.165 60 P 0 8 0;0,2=2,4=0
P 3.38016004 2.22296004 29 P 0 8 0;0,2=45,4=0
P 3.36046998 2.22296004 29 P 0 8 0;0,2=45,4=0
P 3.35153002 2.17875 3 P 0 8 0;2=6,4=1
P 3.44 2.95 2 P 0 8 0;2=7,4=1
P 3.32848002 2.22541998 57 P 0 8 0;0,2=44,4=0
P 3.27923002 2.21576998 3 P 0 8 0;2=6,4=1
P 3.3435 2.82 2 P 0 8 0;2=7,4=1
P 4.41975 2.90553002 63 P 0 8 0;0,2=48,4=0
P 4.46 2.94 3 P 0 8 0;2=1,4=1
P 4.524 2.945 60 P 0 8 0;0,2=2,4=0
P 4.41975 2.84646998 63 P 0 8 0;0,2=48,4=0
P 4.524 2.845 60 P 0 8 0;0,2=2,4=0
P 4.47 2.83 3 P 0 8 0;2=1,4=1
P 5.995 1.165 3 P 0 8 0;2=6,4=1
P 5.956 1.125 60 P 0 8 0;0,2=2,4=0
P 3.106 3.26 3 P 0 8 0;2=6,4=1
P 3.222 3.385 2 P 0 8 0;2=23,4=1
P 3.106 3.35 2 P 0 8 0;2=23,4=1
P 1.959 3.325 3 P 0 8 0;2=6,4=1
P 1.959 3.289 55 P 0 8 0;0,2=2,4=0
P 3.222 3.205 2 P 0 8 0;2=23,4=1
P 3.49 2.955 3 P 0 8 0;2=6,4=1
P 3.98 3.365 3 P 0 8 0;2=6,4=1
P 3.98 3.4056 47 P 0 8 0;0,2=9,4=0
P 3.7 3.37 3 P 0 8 0;2=6,4=1
P 3.55 3.37 3 P 0 8 0;2=6,4=1
P 4.175 3.37 3 P 0 8 0;2=6,4=1
P 4.175 3.4076 47 P 0 8 0;0,2=9,4=0
P 3.71 3.26 3 P 0 8 0;2=6,4=1
P 3.55 3.28 2 P 0 8 0;2=23,4=1
P 3.414 3.235 3 P 0 8 0;2=6,4=1
P 3.481 3.235 95 P 0 8 0;0,2=34,4=0
P 3.41 3.04 3 P 0 8 0;2=6,4=1
P 3.582 2.856 55 P 0 8 0;0,2=2,4=0
P 3.582 2.803 55 P 0 8 0;0,2=2,4=0
P 3.548 2.856 2 P 0 8 0;2=23,4=1
P 3.689 2.71 60 P 0 8 0;0,2=2,4=0
P 3.5768 2.7178 3 P 0 8 0;2=6,4=1
P 3.395 2.82 3 P 0 8 0;2=6,4=1
P 3.485 2.6 3 P 0 8 0;2=6,4=1
P 3.525 2.6 3 P 0 8 0;2=6,4=1
P 3.546 2.555 55 P 0 8 0;0,2=2,4=0
P 3.491 2.563 65 P 0 8 0;0,2=16,4=0
P 3.335 2.553 55 P 0 8 0;0,2=2,4=0
P 3.335 2.589 3 P 0 8 0;2=6,4=1
P 3.24 2.2075 3 P 0 8 0;2=6,4=1
P 3.201 2.209 60 P 0 8 0;0,2=2,4=0
P 3.254 2.165 60 P 0 8 0;0,2=2,4=0
P 4.905 2.1675 3 P 0 8 0;2=6,4=1
P 4.926 2.115 60 P 0 8 0;0,2=2,4=0
P 4.85 2.02738996 3 P 0 8 0;2=6,4=1
P 4.965 1.975 3 P 0 8 0;2=6,4=1
P 3.49128002 1.86628002 3 P 0 8 0;2=6,4=1
P 3.50595 1.89186998 67 P 0 8 0;0,2=50,4=0
P 4.63965 1.68595 4 P 0 8 0;0,2=4,4=0
P 3.76 2.384 55 P 0 8 0;0,2=2,4=0
P 3.795 2.375 3 P 0 8 0;2=6,4=1
P 4.00973002 2.00091004 4 P 0 8 0;0,2=4,4=0
P 4.32468996 1.84343002 4 P 0 8 0;0,2=4,4=0
P 4.0491 1.8828 4 P 0 8 0;0,2=4,4=0
P 3.89161004 1.96153996 4 P 0 8 0;0,2=4,4=0
P 3.93098002 1.84343002 4 P 0 8 0;0,2=4,4=0
P 4.08846998 1.76468996 4 P 0 8 0;0,2=4,4=0
P 4.20658002 1.80406004 4 P 0 8 0;0,2=4,4=0
P 3.86 2.5925 3 P 0 8 0;2=6,4=1
P 4.29225 2.82678996 63 P 0 8 0;0,2=48,4=0
P 4.29225 2.84646998 63 P 0 8 0;0,2=48,4=0
P 4.29225 2.86616004 63 P 0 8 0;0,2=48,4=0
P 4.29225 2.88583996 63 P 0 8 0;0,2=48,4=0
P 4.29225 2.90553002 63 P 0 8 0;0,2=48,4=0
P 4.29225 2.92521004 63 P 0 8 0;0,2=48,4=0
P 4.575 2.461 55 P 0 8 0;0,2=2,4=0
P 3.758 2.552 3 P 0 8 0;2=6,4=1
P 4.209 2.59 3 P 0 8 0;2=6,4=1
P 4.209 2.552 55 P 0 8 0;0,2=2,4=0
P 4.15 2.552 55 P 0 8 0;0,2=2,4=0
P 4.093 2.552 55 P 0 8 0;0,2=2,4=0
P 4.037 2.552 55 P 0 8 0;0,2=2,4=0
P 3.978 2.552 55 P 0 8 0;0,2=2,4=0
P 3.919 2.552 55 P 0 8 0;0,2=2,4=0
P 3.801 2.552 55 P 0 8 0;0,2=2,4=0
P 3.86 2.552 55 P 0 8 0;0,2=2,4=0
P 4.187 2.792 60 P 0 8 0;0,2=2,4=0
P 4.2 2.855 69 P 0 8 0;0,2=18,4=0
P 4.2 2.936 69 P 0 8 0;0,2=18,4=0
P 4.249 2.929 3 P 0 8 0;2=1,4=1
P 4.239 2.785 3 P 0 8 0;2=1,4=1
P 4.249 2.843 3 P 0 8 0;2=1,4=1
P 4.575 2.5 3 P 0 8 0;2=6,4=1
P 4.395 2.461 55 P 0 8 0;0,2=2,4=0
P 4.395 2.5 3 P 0 8 0;2=6,4=1
P 4.77 2.39 3 P 0 8 0;2=6,4=1
P 4.71 2.39 3 P 0 8 0;2=6,4=1
P 4.74 2.4365 23 P 0 8 0;0,2=52,4=0
P 4.48216998 1.76468996 4 P 0 8 0;0,2=4,4=0
P 4.60028002 1.80406004 4 P 0 8 0;0,2=4,4=0
P 4.16721004 1.92216998 4 P 0 8 0;0,2=4,4=0
P 4.28531998 1.96153996 4 P 0 8 0;0,2=4,4=0
P 4.40343002 2.00091004 4 P 0 8 0;0,2=4,4=0
P 4.4428 1.8828 4 P 0 8 0;0,2=4,4=0
P 4.56091004 1.92216998 4 P 0 8 0;0,2=4,4=0
P 4.71838996 1.84343002 4 P 0 8 0;0,2=4,4=0
P 4.67901998 1.96153996 4 P 0 8 0;0,2=4,4=0
P 3.97035 2.11901998 4 P 0 8 0;0,2=4,4=0
P 4.08846998 2.15838996 4 P 0 8 0;0,2=4,4=0
P 4.12783996 2.04028002 4 P 0 8 0;0,2=4,4=0
P 4.24595 2.07965 4 P 0 8 0;0,2=4,4=0
P 4.36406004 2.11901998 4 P 0 8 0;0,2=4,4=0
P 4.48216998 2.15838996 4 P 0 8 0;0,2=4,4=0
P 4.52153996 2.04028002 4 P 0 8 0;0,2=4,4=0
P 4.63965 2.07965 4 P 0 8 0;0,2=4,4=0
P 4.075 2.25 3 P 0 8 0;2=6,4=1
P 3.695 2.5135 51 P 0 8 0;0,2=5,4=0
P 3.735 2.47 3 P 0 8 0;2=6,4=1
P 3.7324 2.5135 51 P 0 8 0;0,2=5,4=0
P 5.001 1.335 60 P 0 8 0;0,2=2,4=0
P 5.001 1.385 60 P 0 8 0;0,2=2,4=0
P 5.0395 1.335 3 P 0 8 0;2=6,4=1
P 4.926 1.765 60 P 0 8 0;0,2=2,4=0
P 4.97 1.75 3 P 0 8 0;2=1,4=1
P 4.96 1.63 3 P 0 8 0;2=6,4=1
P 6.22 1.27063002 3 P 0 8 0;2=6,4=1
P 3.839 3.846 3 P 0 8 0;2=6,4=1
P 4.384 3.824 3 P 0 8 0;2=6,4=1
P 4.384 3.79 60 P 0 8 0;0,2=2,4=0
P 4.2745 3.76456998 90 P 0 8 0;0,2=8,4=0
P 4.95 3.46 3 P 0 8 0;2=6,4=1
P 4.935 3.504 55 P 0 8 0;0,2=2,4=0
P 5.94003002 1.87 3 P 0 8 0;2=6,4=1
P 6.379 1.169 3 P 0 8 0;2=6,4=1
P 6.2655 1.0834 89 P 0 8 0;0,2=37,4=0
P 6.379 1.135 60 P 0 8 0;0,2=2,4=0
P 6.105 1.905 3 P 0 8 0;2=6,4=1
P 5.92 1.27063002 3 P 0 8 0;2=6,4=1
P 5.9945 1.27063002 100 P 0 8 0;0,2=29,4=0
P 5.88 0.965 3 P 0 8 0;2=6,4=1
P 6.421 0.965 60 P 0 8 0;0,2=2,4=0
P 6.421 1.02 60 P 0 8 0;0,2=2,4=0
P 6.47 1.08 3 P 0 8 0;2=6,4=1
P 6.421 1.08 60 P 0 8 0;0,2=2,4=0
P 6.087 2.324 61 P 0 8 0;0,2=16,4=0
P 5.19 3.075 3 P 0 8 0;2=6,4=1
P 5.375 3.04 3 P 0 8 0;2=6,4=1
P 5.41 2.815 3 P 0 8 0;2=6,4=1
P 5.544 2.675 3 P 0 8 0;2=6,4=1
P 6.1865 2.493 3 P 0 8 0;2=6,4=1
P 6.141 2.32 55 P 0 8 0;0,2=2,4=0
P 6.141 2.364 3 P 0 8 0;2=6,4=1
P 5.85 2.265 3 P 0 8 0;2=6,4=1
P 5.89953002 2.239 60 P 0 8 0;0,2=2,4=0
P 5.62 2.5487 3 P 0 8 0;2=6,4=1
P 5.42 2.9645 3 P 0 8 0;2=6,4=1
P 5.96901998 1.90865 55 P 0 8 0;0,2=2,4=0
P 4.645 2.985 3 P 0 8 0;2=6,4=1
P 4.2391 3.97231004 82 P 0 8 0;0,2=0,4=0
P 4.61 3.025 3 P 0 8 0;2=6,4=1
P 4.43 3.865 2 P 0 8 0;2=23,4=1
P 4.396 3.865 60 P 0 8 0;0,2=2,4=0
P 5.221 4.165 3 P 0 8 0;2=6,4=1
P 4.354 3.965 60 P 0 8 0;0,2=2,4=0
P 4.32 3.965 2 P 0 8 0;2=23,4=1
P 4.535 3.815 3 P 0 8 0;2=6,4=1
P 4.53 3.849 55 P 0 8 0;0,2=2,4=0
P 4.598 3.86 61 P 0 8 0;0,2=16,4=0
P 4.4085 3.24556998 90 P 0 8 0;0,2=8,4=0
P 4.509 3.27 60 P 0 8 0;0,2=2,4=0
P 4.509 3.309 3 P 0 8 0;2=6,4=1
P 4.235 4.155 3 P 0 8 0;2=6,4=1
P 4.505 3.685 3 P 0 8 0;2=6,4=1
P 4.426 3.7 60 P 0 8 0;0,2=2,4=0
P 5.975 4.219 3 P 0 8 0;2=6,4=1
P 5.84 4.219 3 P 0 8 0;2=6,4=1
P 6.145 3.98 3 P 0 8 0;2=6,4=1
P 6.14648002 1.27063002 101 P 0 8 0;0,2=30,4=0
P 4.694 0.865 60 P 0 8 0;0,2=2,4=0
P 4.694 0.785 60 P 0 8 0;0,2=2,4=0
P 4.655 0.785 3 P 0 8 0;2=6,4=1
P 4.635 0.92 3 P 0 8 0;2=6,4=1
P 5.1245 0.91956998 90 P 0 8 0;0,2=8,4=0
P 5.249 0.92 60 P 0 8 0;0,2=2,4=0
P 5.249 0.99 3 P 0 8 0;2=6,4=1
P 5.53 1.085 3 P 0 8 0;2=6,4=1
P 5.291 0.82 60 P 0 8 0;0,2=2,4=0
P 5.33 0.82 3 P 0 8 0;2=6,4=1
P 5.291 0.76 60 P 0 8 0;0,2=2,4=0
P 5.265 0.675 3 P 0 8 0;2=6,4=1
P 2.964 0.702 3 P 0 8 0;2=6,4=1
P 2.848 0.63058996 68 P 0 8 0;0,2=53,4=0
P 2.955 0.621 60 P 0 8 0;0,2=2,4=0
P 2.9552 0.6678 60 P 0 8 0;0,2=2,4=0
P 5.515 0.59596998 3 P 0 8 0;2=6,4=1
P 2.0477 0.6778 3 P 0 8 0;2=6,4=1
P 2.285 0.79 3 P 0 8 0;2=6,4=1
P 2.285 0.755 3 P 0 8 0;2=6,4=1
P 2.0477 0.632 55 P 0 8 0;0,2=2,4=0
P 3.09 1.645 3 P 0 8 0;2=6,4=1
P 3.124 1.645 60 P 0 8 0;0,2=2,4=0
P 1.605 0.715 3 P 0 8 0;2=6,4=1
P 1.605 0.755 3 P 0 8 0;2=6,4=1
P 1.826 2.895 3 P 0 8 0;2=6,4=1
P 1.401 3.069 3 P 0 8 0;2=6,4=1
P 1.455 3.192 65 P 0 8 0;0,2=16,4=0
P 2.218 2.973 55 P 0 8 0;0,2=2,4=0
P 3.159 2.434 60 P 0 8 0;0,2=2,4=0
P 3.159 2.389 60 P 0 8 0;0,2=2,4=0
P 3.119 2.434 3 P 0 8 0;2=6,4=1
P 2.245 3.02 2 P 0 8 0;2=23,4=1
P 2.49 2.903 3 P 0 8 0;2=6,4=1
P 2.128 2.895 2 P 0 8 0;2=23,4=1
P 2.173 2.931 55 P 0 8 0;0,2=2,4=0
P 2.083 2.931 55 P 0 8 0;0,2=2,4=0
P 2.128 2.931 55 P 0 8 0;0,2=2,4=0
P 2.1734 3.0845 48 P 0 8 0;0,2=37,4=0
P 0.08251998 3.23523996 49 P 0 8 0;0,2=36,4=0
P 0.11976004 3.23523996 3 P 0 8 0;2=6,4=1
P 0.78 2.915 3 P 0 8 0;2=6,4=1
P 0.241 3.109 3 P 0 8 0;2=6,4=1
P 0.16 2.975 3 P 0 8 0;2=6,4=1
P 0.374 2.829 3 P 0 8 0;2=6,4=1
P 0.5459 2.6687 3 P 0 8 0;2=6,4=1
P 0.578 2.611 55 P 0 8 0;0,2=2,4=0
P 0.674 2.271 3 P 0 8 0;2=6,4=1
P 0.57676004 2.35866004 35 P 0 8 0;0,2=38,4=0
P 0.64 2.271 55 P 0 8 0;0,2=2,4=0
P 0.857 2.365 3 P 0 8 0;2=6,4=1
P 0.677 2.402 3 P 0 8 0;2=6,4=1
P 0.08251998 2.66436998 49 P 0 8 0;0,2=36,4=0
P 0.11963002 2.66436998 3 P 0 8 0;2=6,4=1
P 0.51451998 2.233 55 P 0 8 0;0,2=2,4=0
P 0.51451998 2.199 3 P 0 8 0;2=6,4=1
P 0.575 2.091 55 P 0 8 0;0,2=2,4=0
P 0.58 2.135 3 P 0 8 0;2=6,4=1
P 0.08251998 2.09351004 49 P 0 8 0;0,2=36,4=0
P 0.125 2.095 3 P 0 8 0;2=6,4=1
P 0.57676004 1.78778996 35 P 0 8 0;0,2=38,4=0
P 0.606 1.68945 55 P 0 8 0;0,2=2,4=0
P 0.64445 1.68945 3 P 0 8 0;2=6,4=1
P 0.884 1.549 3 P 0 8 0;2=6,4=1
P 0.883 1.639 2 P 0 8 0;2=23,4=1
P 0.514 1.65 60 P 0 8 0;0,2=2,4=0
P 0.514 1.616 3 P 0 8 0;2=6,4=1
P 0.605 1.52 3 P 0 8 0;2=6,4=1
P 0.58 1.486 55 P 0 8 0;0,2=2,4=0
P 0.08251998 1.52263996 49 P 0 8 0;0,2=36,4=0
P 0.11263996 1.52263996 3 P 0 8 0;2=6,4=1
P 0.57676004 1.21691998 35 P 0 8 0;0,2=38,4=0
P 0.625 1.126 55 P 0 8 0;0,2=2,4=0
P 0.625 1.17 3 P 0 8 0;2=6,4=1
P 0.59 0.965 3 P 0 8 0;2=1,4=1
P 0.58 0.926 55 P 0 8 0;0,2=2,4=0
P 0.505 1.0839 55 P 0 8 0;0,2=2,4=0
P 0.505 1.048 3 P 0 8 0;2=6,4=1
P 0.08251998 0.95176998 49 P 0 8 0;0,2=36,4=0
P 0.125 0.96 3 P 0 8 0;2=6,4=1
P 0.81338996 0.7085 43 P 0 8 0;0,2=26,4=0
P 0.821 0.793 3 P 0 8 0;2=6,4=1
P 0.764 0.872 3 P 0 8 0;2=6,4=1
P 1.2157 0.7536 60 P 0 8 0;0,2=2,4=0
P 1.2157 0.7086 60 P 0 8 0;0,2=2,4=0
P 1.25 0.765 3 P 0 8 0;2=6,4=1
P 1.0705 0.6536 81 P 0 8 0;0,2=5,4=0
P 1.1133 0.5981 3 P 0 8 0;2=6,4=1
P 1.1737 0.6136 60 P 0 8 0;0,2=2,4=0
P 0.86 0.631 3 P 0 8 0;2=6,4=1
P 0.601 0.73 3 P 0 8 0;2=6,4=1
P 0.57676004 0.64606004 35 P 0 8 0;0,2=38,4=0
P 0.596 0.602 3 P 0 8 0;2=6,4=1
P 1.548 0.6212 55 P 0 8 0;0,2=2,4=0
P 1.6622 0.59 93 P 0 8 0;0,2=54,4=0
P 1.5327 0.584 3 P 0 8 0;2=6,4=1
P 5.914 0.965 60 P 0 8 0;0,2=2,4=0
P 5.914 1.025 60 P 0 8 0;0,2=2,4=0
P 4.67901998 1.56783996 4 P 0 8 0;0,2=4,4=0
P 4.56091004 1.52846998 4 P 0 8 0;0,2=4,4=0
P 4.16721004 1.52846998 4 P 0 8 0;0,2=4,4=0
P 4.71838996 1.44973002 4 P 0 8 0;0,2=4,4=0
P 4.60028002 1.41035 4 P 0 8 0;0,2=4,4=0
P 4.48216998 1.37098002 4 P 0 8 0;0,2=4,4=0
P 4.4428 1.4891 4 P 0 8 0;0,2=4,4=0
P 4.36406004 1.33161004 4 P 0 8 0;0,2=4,4=0
P 4.32468996 1.44973002 4 P 0 8 0;0,2=4,4=0
P 4.20658002 1.41035 4 P 0 8 0;0,2=4,4=0
P 4.08846998 1.37098002 4 P 0 8 0;0,2=4,4=0
P 3.97035 1.33161004 4 P 0 8 0;0,2=4,4=0
P 4.999 1.264 69 P 0 8 0;0,2=18,4=0
P 5.039 1.2869 3 P 0 8 0;2=6,4=1
P 5.0386 1.2415 3 P 0 8 0;2=6,4=1
P 4.625 1.17 3 P 0 8 0;2=6,4=1
P 4.53 1.139 55 P 0 8 0;0,2=2,4=0
P 4.585 1.139 55 P 0 8 0;0,2=2,4=0
P 4.485 1.005 3 P 0 8 0;2=6,4=1
P 3.69171998 1.02828002 3 P 0 8 0;2=6,4=1
P 3.6931 1.095 3 P 0 8 0;2=6,4=1
P 3.732 1.06 69 P 0 8 0;0,2=18,4=0
P 6.04 3.98 3 P 0 8 0;2=6,4=1
P 5.404 0.69 60 P 0 8 0;0,2=2,4=0
P 5.56533002 0.69868996 73 P 0 8 0;0,2=19,4=0
P 5.527 0.792 60 P 0 8 0;0,2=2,4=0
P 5.484 0.863 69 P 0 8 0;0,2=18,4=0
P 5.494 0.816 3 P 0 8 0;2=6,4=1
P 5.443 0.871 3 P 0 8 0;2=6,4=1
P 5.56533002 0.72288002 107 P 0 8 0;0,2=20,4=0
P 5.49 0.78223002 3 P 0 8 0;2=6,4=1
P 3.795 4.175 3 P 0 8 0;2=6,4=1
P 3.66 3.5085 3 P 0 8 0;2=6,4=1
P 3.105 3.21 3 P 0 8 0;2=6,4=1
P 5.55 4.02 3 P 0 8 0;2=6,4=1
P 5.04833002 2.68731004 73 P 0 8 0;0,2=19,4=0
P 5.04833002 2.66311998 104 P 0 8 0;0,2=27,4=0
P 5.01 2.635 3 P 0 8 0;2=1,4=1
P 4.96 2.594 55 P 0 8 0;0,2=2,4=0
P 4.933 2.52 65 P 0 8 0;0,2=16,4=0
P 5.014 2.534 69 P 0 8 0;0,2=18,4=0
P 5.042 2.597 60 P 0 8 0;0,2=2,4=0
P 5.04833002 2.75088002 107 P 0 8 0;0,2=20,4=0
P 5 2.78798996 2 P 0 8 0;2=21,4=1
P 4.97343002 2.777 33 P 0 8 0;0,2=12,4=0
P 5.16766998 2.72668996 73 P 0 8 0;0,2=19,4=0
P 5.226 2.762 2 P 0 8 0;2=21,4=1
P 5.26956998 2.725 33 P 0 8 0;0,2=12,4=0
P 5.315 2.769 55 P 0 8 0;0,2=2,4=0
P 5.27 2.769 55 P 0 8 0;0,2=2,4=0
P 3.682 2.205 61 P 0 8 0;0,2=16,4=0
P 3.775 2.235 3 P 0 8 0;2=6,4=1
P 3.775 2.265 3 P 0 8 0;2=1,4=1
P 3.775 2.21 3 P 0 8 0;2=6,4=1
P 3.775 2.185 3 P 0 8 0;2=6,4=1
P 4.40343002 1.76468996 4 P 0 8 0;0,2=4,4=0
P 4.4428 1.72531998 4 P 0 8 0;0,2=4,4=0
P 4.32468996 1.76468996 4 P 0 8 0;0,2=4,4=0
P 4.24595 1.76468996 4 P 0 8 0;0,2=4,4=0
P 4.24595 1.68595 4 P 0 8 0;0,2=4,4=0
P 4.16721004 1.76468996 4 P 0 8 0;0,2=4,4=0
P 4.0491 1.76468996 4 P 0 8 0;0,2=4,4=0
P 5.315 2.811 55 P 0 8 0;0,2=2,4=0
P 1.385 3.875 2 P 0 8 0;2=21,4=1
P 5.31 2.855 3 P 0 8 0;2=6,4=1
P 4.608 2.942 3 P 0 8 0;2=6,4=1
P 4.25 3.81 3 P 0 8 0;2=6,4=1
P 0.95248002 2.632 61 P 0 8 0;0,2=16,4=0
P 0.949 2.58048002 60 P 0 8 0;0,2=2,4=0
P 0.99 2.60025 3 P 0 8 0;2=6,4=1
P 0.985 2.56661004 3 P 0 8 0;2=6,4=1
P 3.628 2.205 61 P 0 8 0;0,2=16,4=0
P 3.555 2.23 3 P 0 8 0;2=6,4=1
P 3.555 2.255 3 P 0 8 0;2=6,4=1
P 3.555 2.205 3 P 0 8 0;2=6,4=1
P 3.555 2.18 3 P 0 8 0;2=6,4=1
P 5.16766998 2.68731004 73 P 0 8 0;0,2=19,4=0
P 5.16766998 2.66311998 108 P 0 8 0;0,2=20,4=0
P 5.22 2.47 3 P 0 8 0;2=6,4=1
P 5.254 2.47 3 P 0 8 0;2=6,4=1
P 5.239 2.571 3 P 0 8 0;2=6,4=1
P 5.243 2.617 3 P 0 8 0;2=6,4=1
P 5.278 2.611 55 P 0 8 0;0,2=2,4=0
P 5.204 2.592 60 P 0 8 0;0,2=2,4=0
P 5.228 2.521 69 P 0 8 0;0,2=18,4=0
P 5.16766998 2.707 73 P 0 8 0;0,2=19,4=0
P 5.278 2.653 55 P 0 8 0;0,2=2,4=0
P 5.328 2.653 55 P 0 8 0;0,2=2,4=0
P 5.224 2.707 2 P 0 8 0;2=21,4=1
P 5.04833002 2.72668996 73 P 0 8 0;0,2=19,4=0
P 5.005 2.711 2 P 0 8 0;2=21,4=1
P 4.889 2.686 55 P 0 8 0;0,2=2,4=0
P 4.961 2.686 55 P 0 8 0;0,2=2,4=0
P 4.96 2.636 55 P 0 8 0;0,2=2,4=0
P 3.708 3.099 61 P 0 8 0;0,2=16,4=0
P 3.797 3.011 55 P 0 8 0;0,2=2,4=0
P 3.732 3.018 85 P 0 8 0;0,2=18,4=0
P 3.89231004 3.00466998 36 P 0 8 0;0,2=19,4=0
P 3.86811998 3.00466998 105 P 0 8 0;0,2=27,4=0
P 3.793 3.05 2 P 0 8 0;2=7,4=1
P 3.96981004 3.04481998 3 P 0 8 0;2=1,4=1
P 3.95588002 3.00466998 109 P 0 8 0;0,2=20,4=0
P 3.982 3.07956998 44 P 0 8 0;0,2=12,4=0
P 3.948 2.813 3 P 0 8 0;2=1,4=1
P 3.926 2.68 60 P 0 8 0;0,2=2,4=0
P 3.93168996 2.88533002 36 P 0 8 0;0,2=19,4=0
P 3.94156998 2.774 33 P 0 8 0;0,2=12,4=0
P 3.926 2.725 60 P 0 8 0;0,2=2,4=0
P 3.968 2.725 60 P 0 8 0;0,2=2,4=0
P 4.889 2.728 55 P 0 8 0;0,2=2,4=0
P 3.55 1.415 3 P 0 8 0;2=6,4=1
P 3.525 1.415 3 P 0 8 0;2=6,4=1
P 3.5 1.415 3 P 0 8 0;2=6,4=1
P 3.475 1.415 3 P 0 8 0;2=6,4=1
P 3.816 2.775 60 P 0 8 0;0,2=2,4=0
P 3.89231004 2.88533002 36 P 0 8 0;0,2=19,4=0
P 3.797 2.849 55 P 0 8 0;0,2=2,4=0
P 3.86811998 2.88533002 110 P 0 8 0;0,2=20,4=0
P 3.729 2.804 85 P 0 8 0;0,2=18,4=0
P 3.745 2.76 3 P 0 8 0;2=6,4=1
P 3.7 2.76 3 P 0 8 0;2=6,4=1
P 3.822 2.81 3 P 0 8 0;2=6,4=1
P 3.78 2.81 3 P 0 8 0;2=6,4=1
P 3.858 2.68 60 P 0 8 0;0,2=2,4=0
P 3.894 2.811 3 P 0 8 0;2=1,4=1
P 3.912 2.88533002 36 P 0 8 0;0,2=19,4=0
P 3.858 2.775 60 P 0 8 0;0,2=2,4=0
P 3.858 2.725 60 P 0 8 0;0,2=2,4=0
P 3.835 3.092 60 P 0 8 0;0,2=2,4=0
P 3.93168996 3.00466998 36 P 0 8 0;0,2=19,4=0
P 3.916 3.048 2 P 0 8 0;2=7,4=1
P 3.891 3.092 60 P 0 8 0;0,2=2,4=0
P 5.597 1.94528996 27 P 0 8 0;0,2=55,4=0
P 5.589 2.025 3 P 0 8 0;2=1,4=1
P 5.546 2.024 3 P 0 8 0;2=6,4=1
P 5.5622 2.13138002 25 P 0 8 0;0,2=56,4=0
P 5.5878 2.13138002 25 P 0 8 0;0,2=56,4=0
P 5.56516004 2.21996004 30 P 0 8 0;0,2=57,4=0
P 5.6 2.324 55 P 0 8 0;0,2=2,4=0
P 5.69943002 2.233 3 P 0 8 0;2=1,4=1
P 5.62913002 2.21996004 50 P 0 8 0;0,2=58,4=0
P 5.729 2.245 60 P 0 8 0;0,2=2,4=0
P 5.52086998 2.21996004 50 P 0 8 0;0,2=58,4=0
P 5.48158002 2.28033002 2 P 0 8 0;2=21,4=1
P 5.51 2.32956998 44 P 0 8 0;0,2=12,4=0
P 5.465 2.324 55 P 0 8 0;0,2=2,4=0
P 4.48216998 1.68595 4 P 0 8 0;0,2=4,4=0
P 4.40343002 1.68595 4 P 0 8 0;0,2=4,4=0
P 4.36406004 1.72531998 4 P 0 8 0;0,2=4,4=0
P 4.28531998 1.72531998 4 P 0 8 0;0,2=4,4=0
P 4.16721004 1.68595 4 P 0 8 0;0,2=4,4=0
P 4.20658002 1.72531998 4 P 0 8 0;0,2=4,4=0
P 4.48216998 1.60721004 4 P 0 8 0;0,2=4,4=0
P 4.4428 1.64658002 4 P 0 8 0;0,2=4,4=0
P 4.4428 1.56783996 4 P 0 8 0;0,2=4,4=0
P 4.36406004 1.56783996 4 P 0 8 0;0,2=4,4=0
P 4.40343002 1.60721004 4 P 0 8 0;0,2=4,4=0
P 4.32468996 1.60721004 4 P 0 8 0;0,2=4,4=0
P 4.28531998 1.56783996 4 P 0 8 0;0,2=4,4=0
P 4.24595 1.60721004 4 P 0 8 0;0,2=4,4=0
P 4.16721004 1.60721004 4 P 0 8 0;0,2=4,4=0
P 4.20658002 1.64658002 4 P 0 8 0;0,2=4,4=0
P 4.20658002 1.56783996 4 P 0 8 0;0,2=4,4=0
P 5.183 1.725 61 P 0 8 0;0,2=16,4=0
P 5.145 1.57 3 P 0 8 0;2=6,4=1
P 5.145 1.54 3 P 0 8 0;2=6,4=1
P 5.1925 1.345 76 P 0 8 0;0,2=52,4=0
P 5.207 1.24 69 P 0 8 0;0,2=18,4=0
P 5.1925 1.47 76 P 0 8 0;0,2=52,4=0
P 5.1925 1.595 76 P 0 8 0;0,2=52,4=0
P 5.145 1.44 3 P 0 8 0;2=1,4=1
P 5.145 1.48 3 P 0 8 0;2=6,4=1
P 5.145 1.51 3 P 0 8 0;2=6,4=1
P 4.2136 3.5997 2 P 0 8 0;2=7,4=1
P 5.465 2.366 55 P 0 8 0;0,2=2,4=0
P 3.755 3.092 3 P 0 8 0;2=6,4=1
P 3.793 3.092 60 P 0 8 0;0,2=2,4=0
P 4.00973002 1.68595 4 P 0 8 0;0,2=4,4=0
P 4.08846998 1.56783996 4 P 0 8 0;0,2=4,4=0
P 4.08846998 1.64658002 4 P 0 8 0;0,2=4,4=0
P 4.0491 1.60721004 4 P 0 8 0;0,2=4,4=0
P 4.00973002 1.52846998 4 P 0 8 0;0,2=4,4=0
P 3.679 1.54228002 3 P 0 8 0;2=6,4=1
P 3.714 1.543 3 P 0 8 0;2=6,4=1
P 3.784 1.543 3 P 0 8 0;2=6,4=1
P 3.749 1.54228002 3 P 0 8 0;2=6,4=1
P 3.672 1.47 61 P 0 8 0;0,2=16,4=0
P 3.705 1.582 85 P 0 8 0;0,2=18,4=0
P 3.618 1.47 61 P 0 8 0;0,2=16,4=0
P 3.575 1.579 55 P 0 8 0;0,2=2,4=0
P 3.515 1.582 85 P 0 8 0;0,2=18,4=0
P 3.605 1.545 3 P 0 8 0;2=6,4=1
P 3.50085 1.543 3 P 0 8 0;2=6,4=1
P 3.53481998 1.54156998 3 P 0 8 0;2=6,4=1
P 3.57 1.542 3 P 0 8 0;2=6,4=1
P 5.237 1.725 61 P 0 8 0;0,2=16,4=0
P 5.597 1.73071998 27 P 0 8 0;0,2=55,4=0
P 5.4227 1.724 3 P 0 8 0;2=6,4=1
P 5.3977 1.724 3 P 0 8 0;2=6,4=1
P 5.3977 1.699 3 P 0 8 0;2=6,4=1
P 5.3977 1.749 3 P 0 8 0;2=6,4=1
P 5.4227 1.699 3 P 0 8 0;2=6,4=1
P 5.41 1.794 55 P 0 8 0;0,2=2,4=0
P 5.657 1.61 69 P 0 8 0;0,2=18,4=0
P 5.39 1.663 85 P 0 8 0;0,2=18,4=0
P 5.35 1.787 85 P 0 8 0;0,2=18,4=0
P 5.654 2.4 60 P 0 8 0;0,2=2,4=0
P 5.4352 1.7497 3 P 0 8 0;2=6,4=1
P 5.654 2.447 3 P 0 8 0;2=6,4=1
P 5.667 2.275 2 P 0 8 0;2=21,4=1
P 5.60453002 2.21996004 30 P 0 8 0;0,2=57,4=0
P 5.695 2.33456998 44 P 0 8 0;0,2=12,4=0
P 5.754 2.324 55 P 0 8 0;0,2=2,4=0
P 5.595 2.28 2 P 0 8 0;2=21,4=1
P 5.58483996 2.21996004 30 P 0 8 0;0,2=57,4=0
P 5.64 2.32956998 44 P 0 8 0;0,2=12,4=0
P 5.483 2.226 3 P 0 8 0;2=1,4=1
P 5.51003996 2.1924 53 P 0 8 0;0,2=59,4=0
P 5.63996004 2.1924 53 P 0 8 0;0,2=59,4=0
P 5.6695 2.2 3 P 0 8 0;2=6,4=1
P 5.771 2.245 60 P 0 8 0;0,2=2,4=0
P 5.771 2.279 2 P 0 8 0;2=21,4=1
P 5.789 2.366 3 P 0 8 0;2=6,4=1
P 5.6 2.4 3 P 0 8 0;2=6,4=1
P 5.6 2.366 55 P 0 8 0;0,2=2,4=0
P 5.64 2.35043002 44 P 0 8 0;0,2=12,4=0
P 5.55568996 3.83456004 41 P 0 8 0;0,2=60,4=0
P 5.55568996 3.88051004 2 P 0 8 0;2=7,4=1
P 5.559 3.96 60 P 0 8 0;0,2=2,4=0
P 5.559 3.915 60 P 0 8 0;0,2=2,4=0
P 5.395 2.229 65 P 0 8 0;0,2=16,4=0
P 5.765 2.197 3 P 0 8 0;2=1,4=1
P 5.71 2.179 3 P 0 8 0;2=6,4=1
P 5.76 2.153 85 P 0 8 0;0,2=18,4=0
P 5.62913002 2.16878002 78 P 0 8 0;0,2=61,4=0
P 5.7 2.151 55 P 0 8 0;0,2=2,4=0
P 5.41 2.164 3 P 0 8 0;2=1,4=1
P 5.385 2.123 85 P 0 8 0;0,2=18,4=0
P 5.52086998 2.16878002 78 P 0 8 0;0,2=61,4=0
P 5.45 2.131 55 P 0 8 0;0,2=2,4=0
P 5.458 2.165 3 P 0 8 0;2=6,4=1
P 5.465 2.405 3 P 0 8 0;2=6,4=1
P 5.555 2.324 55 P 0 8 0;0,2=2,4=0
P 5.54546998 2.21996004 30 P 0 8 0;0,2=57,4=0
P 5.53121998 2.27978996 2 P 0 8 0;2=21,4=1
P 5.696 2.4 60 P 0 8 0;0,2=2,4=0
P 5.754 2.366 55 P 0 8 0;0,2=2,4=0
P 5.695 2.35543002 44 P 0 8 0;0,2=12,4=0
P 3.817 0.924 2 P 0 8 0;2=21,4=1
P 3.869 0.97 60 P 0 8 0;0,2=2,4=0
P 3.811 0.97 60 P 0 8 0;0,2=2,4=0
P 3.77 0.916 55 P 0 8 0;0,2=2,4=0
P 3.88 0.89783002 87 P 0 8 0;0,2=11,4=0
P 4.25 0.877 3 P 0 8 0;2=1,4=1
P 4.205 0.921 55 P 0 8 0;0,2=2,4=0
P 4.314 0.90633996 56 P 0 8 0;0,2=10,4=0
P 5.446 0.69 60 P 0 8 0;0,2=2,4=0
P 5.56533002 0.679 73 P 0 8 0;0,2=19,4=0
P 5.495 0.694 2 P 0 8 0;2=21,4=1
P 5.49 0.635 3 P 0 8 0;2=1,4=1
P 5.46043002 0.635 33 P 0 8 0;0,2=12,4=0
P 5.56533002 0.65931004 73 P 0 8 0;0,2=19,4=0
P 5.725 0.60301004 2 P 0 8 0;2=21,4=1
P 5.68466998 0.63511998 108 P 0 8 0;0,2=20,4=0
P 5.75956998 0.609 33 P 0 8 0;0,2=12,4=0
P 5.775 0.796 55 P 0 8 0;0,2=2,4=0
P 5.7 0.933 65 P 0 8 0;0,2=16,4=0
P 5.691 0.792 60 P 0 8 0;0,2=2,4=0
P 5.698 0.859 69 P 0 8 0;0,2=18,4=0
P 5.68466998 0.69868996 73 P 0 8 0;0,2=19,4=0
P 5.68466998 0.72288002 103 P 0 8 0;0,2=27,4=0
P 5.686 0.76 2 P 0 8 0;2=21,4=1
P 5.775 0.754 55 P 0 8 0;0,2=2,4=0
P 5.68466998 0.65931004 73 P 0 8 0;0,2=19,4=0
P 5.772 0.7 55 P 0 8 0;0,2=2,4=0
P 5.7287 0.6757 2 P 0 8 0;2=21,4=1
P 5.38558002 4.13778996 3 P 0 8 0;2=1,4=1
P 5.43503996 4.13778996 19 P 0 8 0;0,2=31,4=0
P 5.485 4.11 3 P 0 8 0;2=1,4=1
P 5.55315 4.13778996 19 P 0 8 0;0,2=31,4=0
P 5.725 4.135 3 P 0 8 0;2=1,4=1
P 5.78936998 4.13778996 19 P 0 8 0;0,2=31,4=0
P 5.6218 4.13778996 3 P 0 8 0;2=1,4=1
P 5.67126004 4.13778996 19 P 0 8 0;0,2=31,4=0
P 5.323 4.257 2 P 0 8 0;2=21,4=1
P 5.283 4.20953002 19 P 0 8 0;0,2=31,4=0
P 3.83 3.335 2 P 0 8 0;2=7,4=1
P 3.769 3.335 95 P 0 8 0;0,2=34,4=0
P 3.415 3.285 2 P 0 8 0;2=7,4=1
P 3.481 3.285 95 P 0 8 0;0,2=34,4=0
P 3.83 3.285 2 P 0 8 0;2=7,4=1
P 3.769 3.285 95 P 0 8 0;0,2=34,4=0
P 3.415 3.385 2 P 0 8 0;2=7,4=1
P 3.481 3.385 95 P 0 8 0;0,2=34,4=0
P 4.83871004 1.98241004 3 P 0 8 0;2=1,4=1
P 4.71838996 2.00091004 4 P 0 8 0;0,2=4,4=0
P 4.884 1.975 60 P 0 8 0;0,2=2,4=0
P 4.80288002 2.03788002 3 P 0 8 0;2=1,4=1
P 4.884 2.025 60 P 0 8 0;0,2=2,4=0
P 4.67901998 2.00091004 4 P 0 8 0;0,2=4,4=0
P 4.97 3.41 3 P 0 8 0;2=1,4=1
P 4.36406004 1.8828 4 P 0 8 0;0,2=4,4=0
P 4.81 3.41 3 P 0 8 0;2=6,4=1
P 4.40343002 2.07965 4 P 0 8 0;0,2=4,4=0
P 3.48863002 4.105 3 P 0 8 0;2=1,4=1
P 3.52656998 4.121 33 P 0 8 0;0,2=12,4=0
P 3.41796004 4.06613002 54 P 0 8 0;0,2=58,4=0
P 2.937 3.259 60 P 0 8 0;0,2=2,4=0
P 2.987 3.235 2 P 0 8 0;2=23,4=1
P 3.0425 3.25101998 90 P 0 8 0;0,2=8,4=0
P 0.7595 1.642 2 P 0 8 0;2=21,4=1
P 2.987 3.27 2 P 0 8 0;2=23,4=1
P 3.0425 3.27661004 90 P 0 8 0;0,2=8,4=0
P 2.938 3.332 60 P 0 8 0;0,2=2,4=0
P 0.761 1.544 2 P 0 8 0;2=21,4=1
P 4.79246004 1.78463996 3 P 0 8 0;2=1,4=1
P 4.52153996 1.80406004 4 P 0 8 0;0,2=4,4=0
P 4.52153996 2.15838996 4 P 0 8 0;0,2=4,4=0
P 0.955 1.455 3 P 0 8 0;2=1,4=1
P 1.512 0.75191004 3 P 0 8 0;2=6,4=1
P 1.6622 0.64 93 P 0 8 0;0,2=54,4=0
P 1.8091 0.6339 2 P 0 8 0;2=21,4=1
P 1.8832 0.64 93 P 0 8 0;0,2=54,4=0
P 1.459 0.752 2 P 0 8 0;2=23,4=1
P 0.905 1.445 3 P 0 8 0;2=6,4=1
P 2.40508002 0.731 2 P 0 8 0;2=23,4=1
P 4.08846998 1.68595 4 P 0 8 0;0,2=4,4=0
P 2.40508002 0.699 2 P 0 8 0;2=23,4=1
P 4.0491 1.68595 4 P 0 8 0;0,2=4,4=0
P 4.414 0.90633996 56 P 0 8 0;0,2=10,4=0
P 4.414 1.031 55 P 0 8 0;0,2=2,4=0
P 4.418 0.973 60 P 0 8 0;0,2=2,4=0
P 4.369 1.031 55 P 0 8 0;0,2=2,4=0
P 4.364 0.90633996 56 P 0 8 0;0,2=10,4=0
P 4.364 0.973 60 P 0 8 0;0,2=2,4=0
P 4.055 1.029 55 P 0 8 0;0,2=2,4=0
P 4.08 0.89783002 87 P 0 8 0;0,2=11,4=0
P 4.059 0.97 60 P 0 8 0;0,2=2,4=0
P 4.01 1.029 55 P 0 8 0;0,2=2,4=0
P 3.98 0.89783002 87 P 0 8 0;0,2=11,4=0
P 4.006 0.97 60 P 0 8 0;0,2=2,4=0
P 4.4085 1.16598996 2 P 0 8 0;2=23,4=1
P 4.414 1.073 55 P 0 8 0;0,2=2,4=0
P 4.4165 1.123 60 P 0 8 0;0,2=2,4=0
P 4.4428 1.44973002 4 P 0 8 0;0,2=4,4=0
P 4.3765 1.16598996 2 P 0 8 0;2=23,4=1
P 4.369 1.073 55 P 0 8 0;0,2=2,4=0
P 4.3665 1.123 60 P 0 8 0;0,2=2,4=0
P 4.48216998 1.44973002 4 P 0 8 0;0,2=4,4=0
P 4.055 1.071 55 P 0 8 0;0,2=2,4=0
P 4.0485 1.16098996 2 P 0 8 0;2=23,4=1
P 4.08846998 1.52846998 4 P 0 8 0;0,2=4,4=0
P 4.01 1.071 55 P 0 8 0;0,2=2,4=0
P 4.0165 1.16098996 2 P 0 8 0;2=23,4=1
P 4.0491 1.52846998 4 P 0 8 0;0,2=4,4=0
P 4.884 2.115 60 P 0 8 0;0,2=2,4=0
P 4.884 2.07 60 P 0 8 0;0,2=2,4=0
P 4.36406004 1.76468996 4 P 0 8 0;0,2=4,4=0
P 3.54663996 1.04706998 2 P 0 8 0;2=23,4=1
P 4.67901998 1.4891 4 P 0 8 0;0,2=4,4=0
P 3.259 2.106 55 P 0 8 0;0,2=2,4=0
P 3.21 2.11 60 P 0 8 0;0,2=2,4=0
P 3.51463996 1.04706998 2 P 0 8 0;2=23,4=1
P 4.71838996 1.4891 4 P 0 8 0;0,2=4,4=0
P 3.259 2.064 55 P 0 8 0;0,2=2,4=0
P 3.21 2.06 60 P 0 8 0;0,2=2,4=0
P 3.44998996 1.085 2 P 0 8 0;2=23,4=1
P 4.71838996 1.41035 4 P 0 8 0;0,2=4,4=0
P 3.259 2.011 55 P 0 8 0;0,2=2,4=0
P 3.21 2.015 60 P 0 8 0;0,2=2,4=0
P 3.41798996 1.085 2 P 0 8 0;2=23,4=1
P 4.71838996 1.37098002 4 P 0 8 0;0,2=4,4=0
P 3.259 1.969 55 P 0 8 0;0,2=2,4=0
P 3.21 1.965 60 P 0 8 0;0,2=2,4=0
P 3.445 1.815 3 P 0 8 0;2=6,4=1
P 4.56091004 1.8828 4 P 0 8 0;0,2=4,4=0
P 4.785 3.504 55 P 0 8 0;0,2=2,4=0
P 4.63965 1.92216998 4 P 0 8 0;0,2=4,4=0
P 4.785 3.46 3 P 0 8 0;2=1,4=1
P 3.93098002 1.72531998 4 P 0 8 0;0,2=4,4=0
P 3.674 1.744 3 P 0 8 0;2=6,4=1
P 3.97035 1.60721004 4 P 0 8 0;0,2=4,4=0
P 3.93098002 1.56783996 4 P 0 8 0;0,2=4,4=0
P 3.93098002 1.64658002 4 P 0 8 0;0,2=4,4=0
P 3.97035 1.44973002 4 P 0 8 0;0,2=4,4=0
P 3.93098002 1.4891 4 P 0 8 0;0,2=4,4=0
P 3.82 1.42 3 P 0 8 0;2=1,4=1
P 3.79 1.41 3 P 0 8 0;2=6,4=1
P 3.74 1.41 3 P 0 8 0;2=6,4=1
P 3.765 1.41 3 P 0 8 0;2=6,4=1
P 4.52153996 1.64658002 4 P 0 8 0;0,2=4,4=0
P 4.959 1.43 60 P 0 8 0;0,2=2,4=0
P 4.9097 1.385 2 P 0 8 0;2=21,4=1
P 4.959 1.385 60 P 0 8 0;0,2=2,4=0
P 4.52153996 1.68595 4 P 0 8 0;0,2=4,4=0
P 4.84 1.66 3 P 0 8 0;2=1,4=1
P 4.81 1.725 3 P 0 8 0;2=1,4=1
P 4.52153996 1.72531998 4 P 0 8 0;0,2=4,4=0
P 4.884 1.72 60 P 0 8 0;0,2=2,4=0
P 4.884 1.765 60 P 0 8 0;0,2=2,4=0
P 3.375 1.194 2 P 0 8 0;2=23,4=1
P 4.5413 1.22166998 2 P 0 8 0;2=23,4=1
P 4.53 1.181 55 P 0 8 0;0,2=2,4=0
P 4.60028002 1.33161004 4 P 0 8 0;0,2=4,4=0
P 3.165 1.8 60 P 0 8 0;0,2=2,4=0
P 3.375 1.162 2 P 0 8 0;2=23,4=1
P 4.5733 1.22166998 2 P 0 8 0;2=23,4=1
P 4.585 1.181 55 P 0 8 0;0,2=2,4=0
P 4.63965 1.33161004 4 P 0 8 0;0,2=4,4=0
P 3.165 1.75 60 P 0 8 0;0,2=2,4=0
P 4.12783996 1.72531998 4 P 0 8 0;0,2=4,4=0
P 4.44 2.419 55 P 0 8 0;0,2=2,4=0
P 4.365 2.33 3 P 0 8 0;2=6,4=1
P 4.395 2.419 55 P 0 8 0;0,2=2,4=0
P 4.36406004 2.00091004 4 P 0 8 0;0,2=4,4=0
P 4.36406004 2.04028002 4 P 0 8 0;0,2=4,4=0
P 4.485 2.375 3 P 0 8 0;2=1,4=1
P 4.36406004 2.07965 4 P 0 8 0;0,2=4,4=0
P 4.52153996 1.60721004 4 P 0 8 0;0,2=4,4=0
P 4.9097 1.335 2 P 0 8 0;2=21,4=1
P 4.959 1.335 60 P 0 8 0;0,2=2,4=0
P 4.365 2.375 3 P 0 8 0;2=1,4=1
P 4.28531998 1.76468996 4 P 0 8 0;0,2=4,4=0
P 0.1975 1.0435 72 P 0 8 0;0,2=40,4=0
P 0.1975 2.1835 72 P 0 8 0;0,2=40,4=0
P 3.465 1.74 3 P 0 8 0;2=6,4=1
P 3.44 1.03 3 P 0 8 0;2=1,4=1
P 3.554 1.78748996 55 P 0 8 0;0,2=2,4=0
P 3.53613996 1.88543002 26 P 0 8 0;0,2=62,4=0
P 6.285 1.895 3 P 0 8 0;2=6,4=1
P 6.26988996 2.20183996 51 P 0 8 0;0,2=5,4=0
P 6.258 2.15873996 2 P 0 8 0;2=23,4=1
P 6.4105 2.05906004 84 P 0 8 0;0,2=51,4=0
P 6.275 2.05373996 3 P 0 8 0;2=6,4=1
P 6.289 2.01273996 55 P 0 8 0;0,2=2,4=0
P 6.225 2.03673996 85 P 0 8 0;0,2=18,4=0
P 6.335 2.05906004 2 P 0 8 0;2=21,4=1
P 1.77 3.98 3 P 0 8 0;2=1,4=1
P 1.84386998 3.976 22 P 0 8 0;0,2=63,4=0
P 1.75 3.945 3 P 0 8 0;2=6,4=1
P 1.66961998 3.9532 24 P 0 8 0;0,2=56,4=0
P 1.66961998 3.9788 24 P 0 8 0;0,2=56,4=0
P 1.5315 3.9459 2 P 0 8 0;2=21,4=1
P 1.477 3.991 60 P 0 8 0;0,2=2,4=0
P 1.58103996 3.95616004 52 P 0 8 0;0,2=57,4=0
P 1.517 4.113 3 P 0 8 0;2=1,4=1
P 1.556 4.12 55 P 0 8 0;0,2=2,4=0
P 1.58103996 4.02013002 54 P 0 8 0;0,2=58,4=0
P 1.467 3.851 60 P 0 8 0;0,2=2,4=0
P 1.511 3.863 2 P 0 8 0;2=21,4=1
P 1.58103996 3.91186998 54 P 0 8 0;0,2=58,4=0
P 1.47143002 3.901 33 P 0 8 0;0,2=12,4=0
P 1.477 4.142 60 P 0 8 0;0,2=2,4=0
P 1.5153 4.063 2 P 0 8 0;2=21,4=1
P 1.46643002 4.086 33 P 0 8 0;0,2=12,4=0
P 1.58103996 3.99553002 52 P 0 8 0;0,2=57,4=0
P 1.47143002 4.031 33 P 0 8 0;0,2=12,4=0
P 1.58103996 3.97583996 52 P 0 8 0;0,2=57,4=0
P 1.521 3.993 2 P 0 8 0;2=21,4=1
P 1.579 3.874 3 P 0 8 0;2=1,4=1
P 1.6086 3.90103996 34 P 0 8 0;0,2=59,4=0
P 1.585 4.052 3 P 0 8 0;2=6,4=1
P 1.6086 4.03096004 34 P 0 8 0;0,2=59,4=0
P 1.435 4.18 3 P 0 8 0;2=6,4=1
P 1.522 4.163 2 P 0 8 0;2=21,4=1
P 1.556 4.162 55 P 0 8 0;0,2=2,4=0
P 1.4 4.01 3 P 0 8 0;2=6,4=1
P 1.45056998 4.031 33 P 0 8 0;0,2=12,4=0
P 1.435 3.991 60 P 0 8 0;0,2=2,4=0
P 5.14 3.74 3 P 0 8 0;2=6,4=1
P 5.175 3.74 3 P 0 8 0;2=6,4=1
P 5.131 3.775 60 P 0 8 0;0,2=2,4=0
P 5.12 3.853 65 P 0 8 0;0,2=16,4=0
P 5.18 3.825 3 P 0 8 0;2=6,4=1
P 5.675 4.03 3 P 0 8 0;2=6,4=1
P 1.56 3.29 3 P 0 8 0;2=6,4=1
P 1.59668996 3.27 18 P 0 8 0;0,2=13,4=0
P 1.56 3.25 3 P 0 8 0;2=6,4=1
P 3.245 2.955 3 P 0 8 0;2=6,4=1
P 3.21 2.955 3 P 0 8 0;2=6,4=1
P 3.175 2.955 3 P 0 8 0;2=6,4=1
P 2.59 3.445 3 P 0 8 0;2=6,4=1
P 2.55 3.445 3 P 0 8 0;2=6,4=1
P 2.51 3.445 3 P 0 8 0;2=6,4=1
P 2.47 3.445 3 P 0 8 0;2=6,4=1
P 2.2 3.96 3 P 0 8 0;2=6,4=1
P 2.176 3.887 55 P 0 8 0;0,2=2,4=0
P 2.236 3.894 85 P 0 8 0;0,2=18,4=0
P 2.261 4.038 85 P 0 8 0;0,2=18,4=0
P 2.186 4.038 85 P 0 8 0;0,2=18,4=0
P 1.351 4.126 3 P 0 8 0;2=6,4=1
P 1.385 4.126 55 P 0 8 0;0,2=2,4=0
P 2.165 3.96 3 P 0 8 0;2=6,4=1
P 2.07813002 3.976 22 P 0 8 0;0,2=63,4=0
P 2.155 3.925 3 P 0 8 0;2=6,4=1
P 2.19 3.925 3 P 0 8 0;2=6,4=1
P 3.23 4.015 3 P 0 8 0;2=1,4=1
P 3.2 3.985 3 P 0 8 0;2=6,4=1
P 3.32938002 4.0248 24 P 0 8 0;0,2=56,4=0
P 3.32938002 3.9992 24 P 0 8 0;0,2=56,4=0
P 3.05 3.98213002 31 P 0 8 0;0,2=63,4=0
P 3.41796004 4.02183996 52 P 0 8 0;0,2=57,4=0
P 3.522 3.987 60 P 0 8 0;0,2=2,4=0
P 3.443 3.858 55 P 0 8 0;0,2=2,4=0
P 3.41796004 3.95786998 54 P 0 8 0;0,2=58,4=0
P 5.9065 2.4568 3 P 0 8 0;2=6,4=1
P 3.47 3.912 3 P 0 8 0;2=1,4=1
P 3.536 3.78 60 P 0 8 0;0,2=2,4=0
P 3.522 3.833 60 P 0 8 0;0,2=2,4=0
P 3.41796004 3.98246998 52 P 0 8 0;0,2=57,4=0
P 3.52756998 3.892 33 P 0 8 0;0,2=12,4=0
P 3.41796004 4.04153002 52 P 0 8 0;0,2=57,4=0
P 3.522 4.077 60 P 0 8 0;0,2=2,4=0
P 3.522 4.032 60 P 0 8 0;0,2=2,4=0
P 3.48278996 4.05678002 3 P 0 8 0;2=6,4=1
P 3.476 3.988 3 P 0 8 0;2=1,4=1
P 3.41796004 4.00216004 52 P 0 8 0;0,2=57,4=0
P 3.52756998 3.947 33 P 0 8 0;0,2=12,4=0
P 3.3904 4.07696004 34 P 0 8 0;0,2=59,4=0
P 3.437 4.099 3 P 0 8 0;2=1,4=1
P 3.598 3.977 3 P 0 8 0;2=6,4=1
P 3.564 3.987 60 P 0 8 0;0,2=2,4=0
P 3.54843002 3.947 33 P 0 8 0;0,2=12,4=0
P 3.477 3.816 3 P 0 8 0;2=1,4=1
P 3.443 3.816 55 P 0 8 0;0,2=2,4=0
P 3.494 3.78 60 P 0 8 0;0,2=2,4=0
P 3.405 3.916 3 P 0 8 0;2=6,4=1
P 3.3904 3.94703996 34 P 0 8 0;0,2=59,4=0
P 5.59271004 3.71731004 80 P 0 8 0;0,2=64,4=0
P 5.68326004 3.712 3 P 0 8 0;2=1,4=1
P 5.71056998 3.712 33 P 0 8 0;0,2=12,4=0
P 5.59271004 3.75668996 80 P 0 8 0;0,2=64,4=0
P 5.686 3.807 3 P 0 8 0;2=1,4=1
P 5.72 3.807 60 P 0 8 0;0,2=2,4=0
P 5.51631004 3.83456004 41 P 0 8 0;0,2=60,4=0
P 5.50643002 4.009 2 P 0 8 0;2=7,4=1
P 5.50643002 3.967 60 P 0 8 0;0,2=2,4=0
P 5.50643002 3.912 33 P 0 8 0;0,2=12,4=0
P 5.362 3.957 60 P 0 8 0;0,2=2,4=0
P 5.59271004 3.737 80 P 0 8 0;0,2=64,4=0
P 5.686 3.76 3 P 0 8 0;2=1,4=1
P 5.72 3.757 60 P 0 8 0;0,2=2,4=0
P 5.59271004 3.79606004 80 P 0 8 0;0,2=64,4=0
P 5.72 3.857 60 P 0 8 0;0,2=2,4=0
P 5.675 3.865 3 P 0 8 0;2=1,4=1
P 5.59271004 3.81573996 80 P 0 8 0;0,2=64,4=0
P 5.72 3.907 60 P 0 8 0;0,2=2,4=0
P 6.05315 3.67518996 20 P 0 8 0;2=65,4=0
P 6.05315 3.50983996 11 P 0 8 0;2=66,4=0
P 6.05315 3.34448996 11 P 0 8 0;2=66,4=0
P 0.865 3.645 3 P 0 8 0;2=6,4=1
P 0.905 3.645 3 P 0 8 0;2=6,4=1
P 0.945 3.645 3 P 0 8 0;2=6,4=1
P 0.945 3.69 3 P 0 8 0;2=6,4=1
P 0.945 3.73 3 P 0 8 0;2=6,4=1
P 0.945 3.765 3 P 0 8 0;2=6,4=1
P 0.865 3.845 3 P 0 8 0;2=6,4=1
P 0.905 3.845 3 P 0 8 0;2=6,4=1
P 0.94 3.845 3 P 0 8 0;2=6,4=1
P 0.945 3.805 3 P 0 8 0;2=1,4=1
P 0.828 3.846 3 P 0 8 0;2=6,4=1
P 0.873 3.736 91 P 0 8 0;0,2=67,4=0
P 0.828 3.646 3 P 0 8 0;2=6,4=1
P 5.59271004 3.65826004 80 P 0 8 0;0,2=64,4=0
P 5.72 3.467 60 P 0 8 0;0,2=2,4=0
P 5.72 3.517 60 P 0 8 0;0,2=2,4=0
P 5.72 3.567 60 P 0 8 0;0,2=2,4=0
P 5.68 3.567 2 P 0 8 0;2=7,4=1
P 5.47928996 3.81573996 80 P 0 8 0;0,2=64,4=0
P 5.364 3.827 69 P 0 8 0;0,2=18,4=0
P 5.368 3.902 61 P 0 8 0;0,2=16,4=0
P 5.406 3.863 3 P 0 8 0;2=1,4=1
P 3.46 4.16 3 P 0 8 0;2=6,4=1
P 3.495 4.15 3 P 0 8 0;2=6,4=1
P 3.5 4.195 3 P 0 8 0;2=6,4=1
P 3.53 4.165 3 P 0 8 0;2=6,4=1
P 3.552 4.197 60 P 0 8 0;0,2=2,4=0
P 3.465 4.202 61 P 0 8 0;0,2=16,4=0
P 5.769 4.031 3 P 0 8 0;2=6,4=1
P 5.644 3.967 3 P 0 8 0;2=1,4=1
P 5.601 3.96 60 P 0 8 0;0,2=2,4=0
P 5.803 3.907 3 P 0 8 0;2=6,4=1
P 5.762 3.907 60 P 0 8 0;0,2=2,4=0
P 1.445 3.746 55 P 0 8 0;0,2=2,4=0
P 1.45 3.78 3 P 0 8 0;2=6,4=1
P 1.485 3.76 2 P 0 8 0;2=21,4=1
P 1.485 3.8 3 P 0 8 0;2=6,4=1
P 1.534 3.776 61 P 0 8 0;0,2=16,4=0
P 5.331 2.28 55 P 0 8 0;0,2=2,4=0
P 5.375 2.32 3 P 0 8 0;2=6,4=1
P 5.34 2.315 3 P 0 8 0;2=6,4=1
P 5.395 2.283 65 P 0 8 0;0,2=16,4=0
P 5.47928996 3.79606004 80 P 0 8 0;0,2=64,4=0
P 5.47928996 3.77636998 80 P 0 8 0;0,2=64,4=0
P 5.47928996 3.75668996 80 P 0 8 0;0,2=64,4=0
P 5.47928996 3.737 80 P 0 8 0;0,2=64,4=0
P 5.47928996 3.71731004 80 P 0 8 0;0,2=64,4=0
P 5.47928996 3.69763002 80 P 0 8 0;0,2=64,4=0
P 5.47928996 3.67793996 80 P 0 8 0;0,2=64,4=0
P 5.47928996 3.65826004 80 P 0 8 0;0,2=64,4=0
P 5.43 3.6 3 P 0 8 0;2=1,4=1
P 5.433 3.651 3 P 0 8 0;2=6,4=1
P 5.43 3.7 3 P 0 8 0;2=6,4=1
P 5.336 3.672 85 P 0 8 0;0,2=18,4=0
P 5.39 3.6 3 P 0 8 0;2=6,4=1
P 5.393 3.651 3 P 0 8 0;2=6,4=1
P 5.39 3.7 3 P 0 8 0;2=6,4=1
P 5.254 3.672 85 P 0 8 0;0,2=18,4=0
P 5.479 3.569 61 P 0 8 0;0,2=16,4=0
P 1.588 3.776 61 P 0 8 0;0,2=16,4=0
P 1.65 4.091 60 P 0 8 0;0,2=2,4=0
P 1.648 4.151 69 P 0 8 0;0,2=18,4=0
P 1.63221998 4.02013002 46 P 0 8 0;0,2=61,4=0
P 1.63221998 3.91186998 46 P 0 8 0;0,2=61,4=0
P 1.67 3.841 60 P 0 8 0;0,2=2,4=0
P 1.678 3.776 69 P 0 8 0;0,2=18,4=0
P 1.6055 4.134 3 P 0 8 0;2=6,4=1
P 1.60581998 4.1 3 P 0 8 0;2=6,4=1
P 1.606 4.174 2 P 0 8 0;2=21,4=1
P 1.636 3.786 3 P 0 8 0;2=6,4=1
P 1.591 3.826 3 P 0 8 0;2=6,4=1
P 1.633 3.829 2 P 0 8 0;2=21,4=1
P 3.411 4.202 61 P 0 8 0;0,2=16,4=0
P 3.329 4.137 60 P 0 8 0;0,2=2,4=0
P 3.321 4.202 69 P 0 8 0;0,2=18,4=0
P 3.408 4.152 3 P 0 8 0;2=6,4=1
P 3.363 4.192 3 P 0 8 0;2=6,4=1
P 3.363 4.152 3 P 0 8 0;2=6,4=1
P 3.363 4.232 3 P 0 8 0;2=1,4=1
P 3.36678002 4.06613002 46 P 0 8 0;0,2=61,4=0
P 3.36678002 3.95786998 46 P 0 8 0;0,2=61,4=0
P 3.349 3.887 60 P 0 8 0;0,2=2,4=0
P 3.351 3.827 69 P 0 8 0;0,2=18,4=0
P 3.393 3.877 3 P 0 8 0;2=6,4=1
P 3.393 3.84 3 P 0 8 0;2=6,4=1
P 3.392 3.803 3 P 0 8 0;2=6,4=1
P 3.607 4.062 3 P 0 8 0;2=6,4=1
P 3.564 3.833 60 P 0 8 0;0,2=2,4=0
P 3.54843002 3.892 33 P 0 8 0;0,2=12,4=0
P 3.623 3.878 55 P 0 8 0;0,2=2,4=0
P 1.435 4.142 60 P 0 8 0;0,2=2,4=0
P 1.352 4.084 3 P 0 8 0;2=1,4=1
P 1.385 4.084 55 P 0 8 0;0,2=2,4=0
P 1.44556998 4.086 33 P 0 8 0;0,2=12,4=0
P 1.95 0.5455 2 P 0 8 0;2=21,4=1
P 1.8832 0.59 93 P 0 8 0;0,2=54,4=0
P 2.0477 0.59 55 P 0 8 0;0,2=2,4=0
P 1.9977 0.59 55 P 0 8 0;0,2=2,4=0
P 5.59271004 3.67793996 80 P 0 8 0;0,2=64,4=0
P 5.681 3.617 3 P 0 8 0;2=1,4=1
P 5.72 3.617 60 P 0 8 0;0,2=2,4=0
P 5.59271004 3.69763002 80 P 0 8 0;0,2=64,4=0
P 5.681 3.664 3 P 0 8 0;2=1,4=1
P 5.72 3.667 60 P 0 8 0;0,2=2,4=0
P 5.40318002 2.70436004 2 P 0 8 0;2=21,4=1
P 5.50543996 2.721 28 P 0 8 0;0,2=32,4=0
P 0.53 1.444 55 P 0 8 0;0,2=2,4=0
P 0.55921998 1.40543002 3 P 0 8 0;2=1,4=1
P 0.55708002 1.35 35 P 0 8 0;0,2=38,4=0
P 0.535 0.884 55 P 0 8 0;0,2=2,4=0
P 0.55708002 0.77913996 35 P 0 8 0;0,2=38,4=0
P 0.57 0.835 3 P 0 8 0;2=1,4=1
P 3.584 1.827 2 P 0 8 0;2=21,4=1
P 3.55188996 1.88543002 26 P 0 8 0;0,2=62,4=0
P 3.604 1.78748996 55 P 0 8 0;0,2=2,4=0
P 1.58103996 3.93646998 52 P 0 8 0;0,2=57,4=0
P 1.477 3.946 60 P 0 8 0;0,2=2,4=0
P 1.535 3.905 2 P 0 8 0;2=23,4=1
P 1.98135 0.365 2 P 0 8 0;2=23,4=1
P 1.7317 0.7084 3 P 0 8 0;2=1,4=1
P 1.6622 0.69 93 P 0 8 0;0,2=54,4=0
P 1.99408996 0.13781004 59 P 0 8 0;0,2=68,4=0
P 1.91535 0.412 2 P 0 8 0;2=23,4=1
P 1.95471998 0.13781004 59 P 0 8 0;0,2=68,4=0
P 1.8039 0.7072 2 P 0 8 0;2=21,4=1
P 1.8832 0.69 93 P 0 8 0;0,2=54,4=0
P 3.161 1.895 60 P 0 8 0;0,2=2,4=0
P 3.2271 1.90298996 2 P 0 8 0;2=33,4=1
P 3.45301004 1.89898996 2 P 0 8 0;2=33,4=1
P 3.50595 1.90761998 67 P 0 8 0;0,2=50,4=0
P 3.161 1.85 60 P 0 8 0;0,2=2,4=0
P 3.2591 1.90298996 2 P 0 8 0;2=33,4=1
P 3.45301004 1.93098996 2 P 0 8 0;2=33,4=1
P 3.50595 1.92336004 67 P 0 8 0;0,2=50,4=0
P 1.26066998 2.64043002 10 P 0 8 0;2=69,4=0
P 5.50543996 2.821 28 P 0 8 0;0,2=32,4=0
P 5.71056004 2.921 28 P 0 8 0;0,2=32,4=0
P 5.50543996 2.921 28 P 0 8 0;0,2=32,4=0
P 1.6622 0.74 93 P 0 8 0;0,2=54,4=0
P 5.12 3.907 65 P 0 8 0;0,2=16,4=0
P 5.035 3.945 3 P 0 8 0;2=1,4=1
P 5.075 3.945 3 P 0 8 0;2=6,4=1
P 4.91548996 3.90826998 99 P 0 8 0;0,2=17,4=0
P 5.05 3.903 85 P 0 8 0;0,2=18,4=0
P 2.97771998 1.88693996 3 P 0 8 0;2=6,4=1
P 3.00995 1.87611004 3 P 0 8 0;2=6,4=1
P 2.92733996 1.88963002 94 P 0 8 0;0,2=70,4=0
P 2.86066998 2.64043002 10 P 0 8 0;2=69,4=0
P 2.105 0.305 2 P 0 8 0;2=23,4=1
P 2.07283002 0.13781004 59 P 0 8 0;0,2=68,4=0
P 2.235 0.5825 3 P 0 8 0;2=6,4=1
P 3.405 0.635 3 P 0 8 0;2=6,4=1
P 5.295 0.605 3 P 0 8 0;2=1,4=1
P 5.91 4.04 3 P 0 8 0;2=1,4=1
P 2.135 0.54 3 P 0 8 0;2=6,4=1
P 2.105 0.594 55 P 0 8 0;0,2=2,4=0
P 2.15 0.594 55 P 0 8 0;0,2=2,4=0
P 2.15156998 0.13781004 59 P 0 8 0;0,2=68,4=0
P 5.215 0.6 3 P 0 8 0;2=1,4=1
P 6.025 4.04 3 P 0 8 0;2=1,4=1
P 3.36 0.6106 3 P 0 8 0;2=6,4=1
P 0.96 2.41 3 P 0 8 0;2=6,4=1
P 0.68 2.355 3 P 0 8 0;2=6,4=1
P 0.715 2.402 55 P 0 8 0;0,2=2,4=0
P 0.7826 2.4275 48 P 0 8 0;0,2=37,4=0
P 2.38 3.45 3 P 0 8 0;2=6,4=1
P 1.41 3.795 3 P 0 8 0;2=6,4=1
P 3.255 3.664 55 P 0 8 0;0,2=2,4=0
P 3.623 3.836 55 P 0 8 0;0,2=2,4=0
P 3.445 3.613 3 P 0 8 0;2=6,4=1
P 3.365 3.613 3 P 0 8 0;2=1,4=1
P 3.48 3.652 85 P 0 8 0;0,2=18,4=0
P 3.4 3.652 85 P 0 8 0;0,2=18,4=0
P 3.25 3.63 3 P 0 8 0;2=6,4=1
P 3.325 3.613 3 P 0 8 0;2=6,4=1
P 3.405 3.613 3 P 0 8 0;2=6,4=1
P 3.48418002 3.613 3 P 0 8 0;2=6,4=1
P 3.05 3.74786998 31 P 0 8 0;0,2=63,4=0
P 3.32 3.652 85 P 0 8 0;0,2=18,4=0
P 3.645 4.135 3 P 0 8 0;2=6,4=1
P 3.655 3.059 3 P 0 8 0;2=6,4=1
P 3.614 3.099 3 P 0 8 0;2=6,4=1
P 3.614 3.058 3 P 0 8 0;2=6,4=1
P 3.614 3.015 3 P 0 8 0;2=6,4=1
P 3.654 3.099 61 P 0 8 0;0,2=16,4=0
P 3.662 3.018 55 P 0 8 0;0,2=2,4=0
P 5.236 2.811 3 P 0 8 0;2=6,4=1
P 5.27 2.811 55 P 0 8 0;0,2=2,4=0
P 4.41975 2.82428996 64 P 0 8 0;0,2=71,4=0
P 4.41975 2.86616004 63 P 0 8 0;0,2=48,4=0
P 4.3305 2.914 3 P 0 8 0;2=72,4=1
P 4.3815 2.838 3 P 0 8 0;2=72,4=1
P 4.455 2.738 85 P 0 8 0;0,2=18,4=0
P 4.39 2.741 55 P 0 8 0;0,2=2,4=0
P 4.456 2.783 3 P 0 8 0;2=6,4=1
P 4.355 2.745 3 P 0 8 0;2=6,4=1
P 4.346 2.783 3 P 0 8 0;2=6,4=1
P 4.4 2.785 3 P 0 8 0;2=6,4=1
P 4 2.655 3 P 0 8 0;2=6,4=1
P 3.968 2.68 60 P 0 8 0;0,2=2,4=0
P 4.524 2.895 60 P 0 8 0;0,2=2,4=0
P 5.022 2.407 3 P 0 8 0;2=6,4=1
P 4.923 2.408 3 P 0 8 0;2=6,4=1
P 4.972 2.406 3 P 0 8 0;2=6,4=1
P 4.971 2.447 3 P 0 8 0;2=6,4=1
P 4.933 2.466 65 P 0 8 0;0,2=16,4=0
P 5.014 2.474 60 P 0 8 0;0,2=2,4=0
P 5.2871 2.275 3 P 0 8 0;2=6,4=1
P 5.64 0.986 55 P 0 8 0;0,2=2,4=0
P 5.7 0.987 65 P 0 8 0;0,2=16,4=0
P 5.62533002 1.02001004 3 P 0 8 0;2=6,4=1
P 5.65933002 1.02 3 P 0 8 0;2=6,4=1
P 5.575 0.998 85 P 0 8 0;0,2=18,4=0
P 3.804 0.816 2 P 0 8 0;2=23,4=1
P 4.23 0.7295 3 P 0 8 0;2=6,4=1
P 2.31 0.715 3 P 0 8 0;2=6,4=1
P 2.31 0.68 3 P 0 8 0;2=6,4=1
P 2.595 0.547 3 P 0 8 0;2=6,4=1
P 2.595 0.605 60 P 0 8 0;0,2=2,4=0
P 1.87598002 0.289 2 P 0 8 0;2=23,4=1
P 1.86 0.33 2 P 0 8 0;2=23,4=1
P 1.87598002 0.13781004 59 P 0 8 0;0,2=68,4=0
P 1.83661004 0.13781004 59 P 0 8 0;0,2=68,4=0
P 1.79723996 0.13781004 59 P 0 8 0;0,2=68,4=0
P 1.895 0.33 2 P 0 8 0;2=23,4=1
P 1.87598002 0.369 2 P 0 8 0;2=23,4=1
P 0.571 3.845 65 P 0 8 0;0,2=16,4=0
P 0.693 3.736 91 P 0 8 0;0,2=67,4=0
P 0.705 3.82 3 P 0 8 0;2=6,4=1
P 0.665 3.82 3 P 0 8 0;2=6,4=1
P 0.625 3.82 3 P 0 8 0;2=6,4=1
P 0.625 3.78 3 P 0 8 0;2=1,4=1
P 0.625 3.73 3 P 0 8 0;2=1,4=1
P 0.66 3.65 3 P 0 8 0;2=6,4=1
P 0.695 3.65 3 P 0 8 0;2=6,4=1
P 0.73 3.65 3 P 0 8 0;2=6,4=1
P 0.625 3.69 3 P 0 8 0;2=6,4=1
P 0.625 3.65 3 P 0 8 0;2=6,4=1
P 3.63673002 2.39156998 44 P 0 8 0;0,2=12,4=0
P 3.51 2.37 3 P 0 8 0;2=6,4=1
P 3.45151998 2.36321004 57 P 0 8 0;0,2=44,4=0
P 3.57 2.38556998 86 P 0 8 0;0,2=46,4=0
P 0.29 2.915 3 P 0 8 0;2=1,4=1
P 0.28 2.965 3 P 0 8 0;2=1,4=1
P 0.285 3.02 3 P 0 8 0;2=1,4=1
P 2.977 3.351 2 P 0 8 0;2=7,4=1
P 3.0425 3.3022 90 P 0 8 0;0,2=8,4=0
P 3.36525 3.255 2 P 0 8 0;2=7,4=1
P 3.2815 3.25101998 90 P 0 8 0;0,2=8,4=0
P 3.36525 3.205 2 P 0 8 0;2=7,4=1
P 3.2815 3.22543002 90 P 0 8 0;0,2=8,4=0
P 1.8062 0.7789 2 P 0 8 0;2=21,4=1
P 3.05708002 0.15731004 58 P 0 8 0;0,2=73,4=0
P 3.073 0.613 2 P 0 8 0;2=21,4=1
P 2.54526998 0.339 2 P 0 8 0;2=23,4=1
P 2.5059 0.13781004 59 P 0 8 0;0,2=68,4=0
P 2.527 0.44 2 P 0 8 0;2=7,4=1
P 2.51121998 0.584 55 P 0 8 0;0,2=2,4=0
P 5.73991004 4.27558002 3 P 0 8 0;2=1,4=1
P 5.78936998 4.27558002 19 P 0 8 0;0,2=31,4=0
P 5.38558002 4.27558002 3 P 0 8 0;2=1,4=1
P 5.43503996 4.27558002 19 P 0 8 0;0,2=31,4=0
P 5.50368996 4.27558002 3 P 0 8 0;2=1,4=1
P 5.55315 4.27558002 19 P 0 8 0;0,2=31,4=0
P 5.6218 4.27558002 3 P 0 8 0;2=1,4=1
P 5.67126004 4.27558002 19 P 0 8 0;0,2=31,4=0
P 3.2815 3.35338996 90 P 0 8 0;0,2=8,4=0
P 5.91901998 1.90865 55 P 0 8 0;0,2=2,4=0
P 5.875 1.9 3 P 0 8 0;2=1,4=1
P 3.865 3.65 3 P 0 8 0;2=6,4=1
P 3.2815 3.37898002 90 P 0 8 0;0,2=8,4=0
P 6.06901998 1.86 3 P 0 8 0;2=1,4=1
P 6.06901998 1.90865 55 P 0 8 0;0,2=2,4=0
P 3.81 3.65 3 P 0 8 0;2=6,4=1
P 5.98016004 2.04418002 36 P 0 8 0;0,2=19,4=0
P 5.97 1.999 2 P 0 8 0;2=21,4=1
P 5.96901998 1.95065 55 P 0 8 0;0,2=2,4=0
P 5.762 3.667 60 P 0 8 0;0,2=2,4=0
P 4.62 2.245 3 P 0 8 0;2=6,4=1
P 5.801 3.667 3 P 0 8 0;2=6,4=1
P 3.8 2.045 3 P 0 8 0;2=6,4=1
P 1.275 2.905 3 P 0 8 0;2=6,4=1
P 5.061 2.806 3 P 0 8 0;2=6,4=1
P 3.705 1.648 85 P 0 8 0;0,2=18,4=0
P 3.515 1.648 85 P 0 8 0;0,2=18,4=0
P 3.575 1.621 55 P 0 8 0;0,2=2,4=0
P 3.995 1.2 3 P 0 8 0;2=6,4=1
P 4.07 1.2 3 P 0 8 0;2=6,4=1
P 4.0805 1.16098996 2 P 0 8 0;2=23,4=1
P 4.092 1.005 2 P 0 8 0;2=23,4=1
P 4.135 0.885 3 P 0 8 0;2=6,4=1
P 4.13621998 0.75 2 P 0 8 0;2=23,4=1
P 4.13401998 0.54196998 2 P 0 8 0;2=23,4=1
P 4.09401998 0.54196998 2 P 0 8 0;2=23,4=1
P 4.05401998 0.54196998 2 P 0 8 0;2=23,4=1
P 4.01401998 0.54196998 2 P 0 8 0;2=23,4=1
P 2.985 1.845 3 P 0 8 0;2=6,4=1
P 2.845 1.907 2 P 0 8 0;2=23,4=1
P 2.845 1.811 2 P 0 8 0;2=23,4=1
P 2.822 1.79121004 3 P 0 8 0;2=6,4=1
P 2.71 1.845 3 P 0 8 0;2=6,4=1
P 2.2 0.69 3 P 0 8 0;2=6,4=1
P 2.15 0.69 3 P 0 8 0;2=6,4=1
P 2.105 0.636 55 P 0 8 0;0,2=2,4=0
P 2.15 0.636 55 P 0 8 0;0,2=2,4=0
P 1.9216 0.7784 3 P 0 8 0;2=6,4=1
P 2.0195 0.2905 2 P 0 8 0;2=23,4=1
P 2.03346004 0.13781004 59 P 0 8 0;0,2=68,4=0
P 1.91535 0.289 2 P 0 8 0;2=23,4=1
P 1.91535 0.13781004 59 P 0 8 0;0,2=68,4=0
P 1.78196004 0.50601004 2 P 0 8 0;2=23,4=1
P 1.80341004 0.47225 2 P 0 8 0;2=23,4=1
P 1.63543002 0.52158996 2 P 0 8 0;2=23,4=1
P 3.65101004 1.85158996 2 P 0 8 0;2=23,4=1
P 3.45301004 1.86698996 2 P 0 8 0;2=23,4=1
P 3.473 1.79 3 P 0 8 0;2=6,4=1
P 3.1951 1.90298996 2 P 0 8 0;2=23,4=1
P 3.2911 1.90298996 2 P 0 8 0;2=23,4=1
P 2.958 0.289 2 P 0 8 0;2=23,4=1
P 2.97833996 0.13781004 59 P 0 8 0;0,2=68,4=0
P 2.88056998 0.289 2 P 0 8 0;2=23,4=1
P 2.86023002 0.13781004 59 P 0 8 0;0,2=68,4=0
P 2.95835 0.321 2 P 0 8 0;2=23,4=1
P 2.82086004 0.13781004 59 P 0 8 0;0,2=68,4=0
P 2.80051998 0.289 2 P 0 8 0;2=23,4=1
P 2.80086998 0.321 2 P 0 8 0;2=23,4=1
P 2.63506998 0.763 2 P 0 8 0;2=23,4=1
P 2.78655 0.763 2 P 0 8 0;2=23,4=1
P 2.73106998 0.763 2 P 0 8 0;2=23,4=1
P 2.7233 0.54871004 3 P 0 8 0;2=6,4=1
P 2.754 0.57941004 68 P 0 8 0;0,2=53,4=0
P 2.64338996 0.417 2 P 0 8 0;2=23,4=1
P 2.70275 0.13781004 59 P 0 8 0;0,2=68,4=0
P 2.72308996 0.289 2 P 0 8 0;2=23,4=1
P 2.66338002 0.13781004 59 P 0 8 0;0,2=68,4=0
P 2.64303996 0.289 2 P 0 8 0;2=23,4=1
P 2.64338996 0.321 2 P 0 8 0;2=23,4=1
P 2.53421998 0.763 2 P 0 8 0;2=23,4=1
P 2.595 0.701 3 P 0 8 0;2=6,4=1
P 2.595 0.655 60 P 0 8 0;0,2=2,4=0
P 2.44618996 0.289 2 P 0 8 0;2=23,4=1
P 2.46653002 0.13781004 59 P 0 8 0;0,2=68,4=0
P 2.54526998 0.289 2 P 0 8 0;2=23,4=1
P 2.54526998 0.13781004 59 P 0 8 0;0,2=68,4=0
P 2.43821998 0.763 2 P 0 8 0;2=23,4=1
P 2.40508002 0.667 2 P 0 8 0;2=23,4=1
P 2.40508002 0.763 2 P 0 8 0;2=23,4=1
P 2.327 0.291 2 P 0 8 0;2=23,4=1
P 2.34841998 0.13781004 59 P 0 8 0;0,2=68,4=0
P 3.56 1.305 3 P 0 8 0;2=6,4=1
P 3.535 1.305 3 P 0 8 0;2=6,4=1
P 3.51 1.305 3 P 0 8 0;2=6,4=1
P 3.54 1.28 3 P 0 8 0;2=6,4=1
P 3.57863996 1.04706998 2 P 0 8 0;2=23,4=1
P 3.593 0.92 2 P 0 8 0;2=23,4=1
P 3.65401998 0.54196998 2 P 0 8 0;2=23,4=1
P 3.61401998 0.54196998 2 P 0 8 0;2=23,4=1
P 3.57401998 0.54196998 2 P 0 8 0;2=23,4=1
P 3.53401998 0.54196998 2 P 0 8 0;2=23,4=1
P 3.49401998 0.54196998 2 P 0 8 0;2=23,4=1
P 3.375 1.226 2 P 0 8 0;2=23,4=1
P 3.375 1.13 2 P 0 8 0;2=23,4=1
P 3.48263996 1.04706998 2 P 0 8 0;2=23,4=1
P 3.48198996 1.085 2 P 0 8 0;2=23,4=1
P 3.38598996 1.085 2 P 0 8 0;2=23,4=1
P 3.33401998 0.54196998 2 P 0 8 0;2=23,4=1
P 3.45401998 0.54196998 2 P 0 8 0;2=23,4=1
P 3.41401998 0.54196998 2 P 0 8 0;2=23,4=1
P 3.37401998 0.54196998 2 P 0 8 0;2=23,4=1
P 3.17025 0.82975 2 P 0 8 0;2=23,4=1
P 3.17401998 0.54196998 2 P 0 8 0;2=23,4=1
P 3.21401998 0.54196998 2 P 0 8 0;2=23,4=1
P 3.25401998 0.54196998 2 P 0 8 0;2=23,4=1
P 3.29401998 0.54196998 2 P 0 8 0;2=23,4=1
P 3.10236998 0.89763002 2 P 0 8 0;2=23,4=1
P 3.035 0.694 3 P 0 8 0;2=6,4=1
P 2.9972 0.6678 60 P 0 8 0;0,2=2,4=0
P 2.98726004 0.49471004 2 P 0 8 0;2=23,4=1
P 2.98726004 0.43528996 2 P 0 8 0;2=23,4=1
P 3.07708002 0.289 2 P 0 8 0;2=23,4=1
P 2.88255 0.763 2 P 0 8 0;2=23,4=1
P 2.95835 0.417 2 P 0 8 0;2=23,4=1
P 2.80086998 0.417 2 P 0 8 0;2=23,4=1
P 3.9845 1.16098996 2 P 0 8 0;2=23,4=1
P 3.9 1.005 2 P 0 8 0;2=23,4=1
P 3.964 1.005 2 P 0 8 0;2=21,4=1
P 3.97401998 0.54196998 2 P 0 8 0;2=23,4=1
P 3.93401998 0.54196998 2 P 0 8 0;2=23,4=1
P 3.89401998 0.54196998 2 P 0 8 0;2=23,4=1
P 3.85401998 0.54196998 2 P 0 8 0;2=23,4=1
P 3.798 1.771 3 P 0 8 0;2=6,4=1
P 3.647 1.694 3 P 0 8 0;2=6,4=1
P 3.676 1.693 3 P 0 8 0;2=6,4=1
P 3.718 1.32 3 P 0 8 0;2=6,4=1
P 3.743 1.32 3 P 0 8 0;2=6,4=1
P 3.718 1.29 3 P 0 8 0;2=6,4=1
P 3.743 1.29 3 P 0 8 0;2=6,4=1
P 3.67 1.26 3 P 0 8 0;2=6,4=1
P 3.84 1.095 3 P 0 8 0;2=6,4=1
P 3.798 1.06 69 P 0 8 0;0,2=18,4=0
P 3.84 1.0298 3 P 0 8 0;2=6,4=1
P 3.76838002 1.0023 3 P 0 8 0;2=6,4=1
P 3.735 0.94 2 P 0 8 0;2=23,4=1
P 3.689 0.92 2 P 0 8 0;2=23,4=1
P 3.805 0.774 2 P 0 8 0;2=23,4=1
P 3.735 0.78 2 P 0 8 0;2=23,4=1
P 3.795 0.725 2 P 0 8 0;2=21,4=1
P 4.101 0.97 60 P 0 8 0;0,2=2,4=0
P 4.08 0.75216998 87 P 0 8 0;0,2=11,4=0
P 3.769 0.97 60 P 0 8 0;0,2=2,4=0
P 3.964 0.97 60 P 0 8 0;0,2=2,4=0
P 3.911 0.97 60 P 0 8 0;0,2=2,4=0
P 3.81401998 0.54196998 2 P 0 8 0;2=23,4=1
P 3.77401998 0.54196998 2 P 0 8 0;2=23,4=1
P 3.73401998 0.54196998 2 P 0 8 0;2=23,4=1
P 3.69401998 0.54196998 2 P 0 8 0;2=23,4=1
P 3.551 1.694 3 P 0 8 0;2=6,4=1
P 3.576 1.694 3 P 0 8 0;2=6,4=1
P 3.526 1.694 3 P 0 8 0;2=6,4=1
P 3.501 1.694 3 P 0 8 0;2=6,4=1
P 3.636 1.766 3 P 0 8 0;2=6,4=1
P 3.604 1.74548996 55 P 0 8 0;0,2=2,4=0
P 3.09645 0.13781004 59 P 0 8 0;0,2=68,4=0
P 2.86066998 1.04043002 10 P 0 8 0;2=69,4=0
P 4.6053 1.22166998 2 P 0 8 0;2=23,4=1
P 1.041 3.825 2 P 0 8 0;2=23,4=1
P 1.137 3.825 2 P 0 8 0;2=23,4=1
P 6.56038996 1.41205 2 P 0 8 0;2=23,4=1
P 6.56038996 1.37205 2 P 0 8 0;2=23,4=1
P 6.56038996 1.33205 2 P 0 8 0;2=23,4=1
P 6.56038996 1.29205 2 P 0 8 0;2=23,4=1
P 6.56038996 1.25205 2 P 0 8 0;2=23,4=1
P 6.56038996 1.21205 2 P 0 8 0;2=23,4=1
P 6.56038996 1.17205 2 P 0 8 0;2=23,4=1
P 6.56038996 1.13205 2 P 0 8 0;2=23,4=1
P 6.56038996 1.09205 2 P 0 8 0;2=23,4=1
P 5.9645 2.1035 3 P 0 8 0;2=72,4=1
P 6.0155 2.0845 3 P 0 8 0;2=72,4=1
P 0.22703996 0.43635 5 P 0 8 0;2=74,4=0
P 0.19878002 0.36811004 5 P 0 8 0;2=74,4=0
P 0.22703996 0.29986998 5 P 0 8 0;2=74,4=0
P 0.29528002 0.27161004 5 P 0 8 0;2=74,4=0
P 0.36351998 0.29986998 5 P 0 8 0;2=74,4=0
P 0.39178002 0.36811004 5 P 0 8 0;2=74,4=0
P 0.36351998 0.43635 5 P 0 8 0;2=74,4=0
P 0.29528002 0.46461004 5 P 0 8 0;2=74,4=0
P 6.33215 0.72178002 5 P 0 8 0;2=74,4=0
P 6.30388996 0.65353996 5 P 0 8 0;2=74,4=0
P 6.33215 0.5853 5 P 0 8 0;2=74,4=0
P 6.40038996 0.55703996 5 P 0 8 0;2=74,4=0
P 6.46863002 0.5853 5 P 0 8 0;2=74,4=0
P 6.49688996 0.65353996 5 P 0 8 0;2=74,4=0
P 6.46863002 0.72178002 5 P 0 8 0;2=74,4=0
P 6.40038996 0.75003996 5 P 0 8 0;2=74,4=0
P 6.33215 4.24658996 5 P 0 8 0;2=74,4=0
P 6.30388996 4.17835 5 P 0 8 0;2=74,4=0
P 6.33215 4.11011004 5 P 0 8 0;2=74,4=0
P 6.40038996 4.08185 5 P 0 8 0;2=74,4=0
P 6.46863002 4.11011004 5 P 0 8 0;2=74,4=0
P 6.49688996 4.17835 5 P 0 8 0;2=74,4=0
P 6.46863002 4.24658996 5 P 0 8 0;2=74,4=0
P 6.40038996 4.27485 5 P 0 8 0;2=74,4=0
P 5.9945 1.37063002 100 P 0 8 0;0,2=29,4=0
P 5.92 1.36 3 P 0 8 0;2=1,4=1
P 6.22 1.36 3 P 0 8 0;2=6,4=1
P 6.14648002 1.37063002 101 P 0 8 0;0,2=30,4=0
P 5.99 0.925 3 P 0 8 0;2=6,4=1
P 6.0845 1.0066 89 P 0 8 0;0,2=37,4=0
P 5.803 3.857 3 P 0 8 0;2=6,4=1
P 1.355 3.905 3 P 0 8 0;2=6,4=1
P 1.29831004 3.85153996 88 P 0 8 0;0,2=28,4=0
P 1.21168996 3.96891998 3 P 0 8 0;2=6,4=1
P 1.21168996 3.91846004 88 P 0 8 0;0,2=28,4=0
P 0.42 2.368 3 P 0 8 0;2=6,4=1
P 0.452 2.368 55 P 0 8 0;0,2=2,4=0
P 5.325 2.725 3 P 0 8 0;2=6,4=1
P 5.29043002 2.725 33 P 0 8 0;0,2=12,4=0
P 5.96046998 2.14381998 36 P 0 8 0;0,2=19,4=0
P 5.98016004 2.14381998 36 P 0 8 0;0,2=19,4=0
P 1.6985 2.9895 3 P 0 8 0;2=72,4=1
P 1.6615 3.0405 3 P 0 8 0;2=72,4=1
P 1.62033002 2.97111998 104 P 0 8 0;0,2=27,4=0
P 5.6435 0.6535 3 P 0 8 0;2=72,4=1
P 5.1265 2.6815 3 P 0 8 0;2=72,4=1
P 5.0895 2.7325 3 P 0 8 0;2=72,4=1
P 5.16766998 2.75088002 103 P 0 8 0;0,2=27,4=0
P 5.59271004 3.77636998 80 P 0 8 0;0,2=64,4=0
P 4.0489 3.992 82 P 0 8 0;0,2=0,4=0
P 4.144 3.8969 39 P 0 8 0;0,2=41,4=0
P 4.144 4.0871 39 P 0 8 0;0,2=41,4=0
P 4.1915 4.0395 3 P 0 8 0;2=72,4=1
P 4.0965 3.9445 3 P 0 8 0;2=72,4=1
P 4.1235 3.9715 3 P 0 8 0;2=72,4=1
P 4.1645 3.9715 3 P 0 8 0;2=72,4=1
P 4.1645 4.0125 3 P 0 8 0;2=72,4=1
P 4.1235 4.0125 3 P 0 8 0;2=72,4=1
P 4.0965 4.0395 3 P 0 8 0;2=72,4=1
P 4.1915 3.9445 3 P 0 8 0;2=72,4=1
P 4.41975 2.88583996 63 P 0 8 0;0,2=48,4=0
P 4.5 4.07 3 P 0 8 0;2=6,4=1
P 4.31 4.16 3 P 0 8 0;2=6,4=1
P 1.41 2.985 3 P 0 8 0;2=6,4=1
P 1.484 2.95 60 P 0 8 0;0,2=2,4=0
P 1.46 3.007 85 P 0 8 0;0,2=18,4=0
P 1.45 2.965 3 P 0 8 0;2=6,4=1
P 2.0966 3.2655 48 P 0 8 0;0,2=37,4=0
P 1.51 3.206 55 P 0 8 0;0,2=2,4=0
P 1.51 3.242 3 P 0 8 0;2=6,4=1
P 1.848 3.26 69 P 0 8 0;0,2=18,4=0
P 1.888 3.105 69 P 0 8 0;0,2=18,4=0
P 1.861 3.19 60 P 0 8 0;0,2=2,4=0
P 1.885 2.981 55 P 0 8 0;0,2=2,4=0
P 1.866 3.04 60 P 0 8 0;0,2=2,4=0
P 1.89 3.26 3 P 0 8 0;2=6,4=1
P 1.895 3.19 3 P 0 8 0;2=6,4=1
P 1.9 3.055 3 P 0 8 0;2=6,4=1
P 1.9 3.015 3 P 0 8 0;2=6,4=1
P 1.65 2.94 3 P 0 8 0;2=6,4=1
P 1.685 2.94 3 P 0 8 0;2=6,4=1
P 1.71456998 2.9 33 P 0 8 0;0,2=12,4=0
P 5.17 2.125 3 P 0 8 0;2=6,4=1
P 4.96 1.79258002 3 P 0 8 0;2=6,4=1
P 4.59 3.26 3 P 0 8 0;2=6,4=1
P 4.551 3.27 60 P 0 8 0;0,2=2,4=0
P 2.866 1.987 2 P 0 8 0;2=23,4=1
P 2.77 1.987 2 P 0 8 0;2=23,4=1
P 4.4585 1.123 60 P 0 8 0;0,2=2,4=0
P 4.3245 1.123 60 P 0 8 0;0,2=2,4=0
P 4.5093 1.22166998 2 P 0 8 0;2=23,4=1
P 0.04 2.85618996 2 P 0 8 0;2=23,4=1
P 0.04 2.81618996 2 P 0 8 0;2=23,4=1
P 0.04 3.13618996 2 P 0 8 0;2=23,4=1
P 0.04 3.09618996 2 P 0 8 0;2=23,4=1
P 0.04 3.05618996 2 P 0 8 0;2=23,4=1
P 0.04 3.01618996 2 P 0 8 0;2=23,4=1
P 3.49 3.03 3 P 0 8 0;2=6,4=1
P 3.555 3.065 3 P 0 8 0;2=6,4=1
P 3.695 2.675 3 P 0 8 0;2=6,4=1
P 3.695 2.6265 51 P 0 8 0;0,2=5,4=0
P 3.725 2.32 3 P 0 8 0;2=6,4=1
P 3.705 2.384 55 P 0 8 0;0,2=2,4=0
P 0.945 1.05 3 P 0 8 0;2=6,4=1
P 4.635 0.865 3 P 0 8 0;2=6,4=1
P 0.866 1.413 3 P 0 8 0;2=6,4=1
P 2.885 3.17 3 P 0 8 0;2=6,4=1
P 2.895 3.206 60 P 0 8 0;0,2=2,4=0
P 0.83 4.17 3 P 0 8 0;2=6,4=1
P 0.455 1.26 3 P 0 8 0;2=6,4=1
P 0.455 1.22 55 P 0 8 0;0,2=2,4=0
P 0.175 0.91 3 P 0 8 0;2=6,4=1
P 0.2055 0.9565 75 P 0 8 0;0,2=75,4=0
P 0.17 2.045 3 P 0 8 0;2=6,4=1
P 0.2055 2.0965 75 P 0 8 0;0,2=75,4=0
P 0.455 1.61 3 P 0 8 0;2=6,4=1
P 0.455 1.644 55 P 0 8 0;0,2=2,4=0
P 1.32 3.755 3 P 0 8 0;2=6,4=1
P 1.25095 3.06095 3 P 0 8 0;2=6,4=1
P 1.25095 3.12 40 P 0 8 0;0,2=15,4=0
P 0.95593002 3.33346998 3 P 0 8 0;2=6,4=1
P 0.894 3.33916004 92 P 0 8 0;0,2=15,4=0
P 0.575 2.89 3 P 0 8 0;2=1,4=1
P 0.16 3.025 3 P 0 8 0;2=6,4=1
P 0.16 3.075 3 P 0 8 0;2=6,4=1
P 1.445 3.704 55 P 0 8 0;0,2=2,4=0
P 0.631 3.29 60 P 0 8 0;0,2=2,4=0
P 0.72 3.35 3 P 0 8 0;2=6,4=1
P 0.72 3.3935 51 P 0 8 0;0,2=5,4=0
P 0.635 3.596 3 P 0 8 0;2=6,4=1
P 0.595 3.596 55 P 0 8 0;0,2=2,4=0
P 0.671 3.575 2 P 0 8 0;2=23,4=1
P 0.767 3.575 2 P 0 8 0;2=23,4=1
P 1.4213 3.2563 3 P 0 8 0;2=6,4=1
P 1.352 3.24073002 92 P 0 8 0;0,2=15,4=0
P 4.426 3.745 60 P 0 8 0;0,2=2,4=0
P 4.472 3.475 3 P 0 8 0;2=6,4=1
P 4.472 3.5315 71 P 0 8 0;0,2=11,4=0
P 4.735 3.504 55 P 0 8 0;0,2=2,4=0
P 5.97703002 1.87 3 P 0 8 0;2=6,4=1
P 0.606 1.612 3 P 0 8 0;2=6,4=1
P 0.606 1.64745 55 P 0 8 0;0,2=2,4=0
P 5.33 0.87 3 P 0 8 0;2=6,4=1
P 5.291 0.87 60 P 0 8 0;0,2=2,4=0
P 5.291 0.92 60 P 0 8 0;0,2=2,4=0
P 6.26988996 2.37988996 3 P 0 8 0;2=6,4=1
P 6.26988996 2.31483996 51 P 0 8 0;0,2=5,4=0
P 4.46 3.745 3 P 0 8 0;2=6,4=1
P 4.426 3.79 60 P 0 8 0;0,2=2,4=0
P 3.769 3.385 95 P 0 8 0;0,2=34,4=0
P 3.83 3.415 3 P 0 8 0;2=6,4=1
P 3.55 3.325 2 P 0 8 0;2=23,4=1
P 6.335 3.015 3 P 0 8 0;2=6,4=1
P 6.22356004 3.015 28 P 0 8 0;0,2=32,4=0
P 1.667 3.388 3 P 0 8 0;2=6,4=1
P 0.51043002 1.57 33 P 0 8 0;0,2=12,4=0
P 1.591 3.504 3 P 0 8 0;2=6,4=1
P 1.045 3.055 3 P 0 8 0;2=6,4=1
P 1.01473002 3.12 40 P 0 8 0;0,2=15,4=0
P 1.42 3.5 3 P 0 8 0;2=6,4=1
P 1.235 3.475 3 P 0 8 0;2=6,4=1
P 1.2 3.715 3 P 0 8 0;2=6,4=1
P 1.409 3.554 3 P 0 8 0;2=6,4=1
P 1.2 3.68 3 P 0 8 0;2=6,4=1
P 1.155 3.89 3 P 0 8 0;2=6,4=1
P 1.17 3.97 3 P 0 8 0;2=6,4=1
P 1.27 3.97061004 3 P 0 8 0;2=6,4=1
P 1.29 3.705 3 P 0 8 0;2=6,4=1
P 1.355 3.83 3 P 0 8 0;2=6,4=1
P 1.355 3.96 3 P 0 8 0;2=6,4=1
P 1.185 3.79 3 P 0 8 0;2=6,4=1
P 1.21456998 3.79 33 P 0 8 0;0,2=12,4=0
P 1.32 3.79 3 P 0 8 0;2=6,4=1
P 1.29043002 3.79 33 P 0 8 0;0,2=12,4=0
P 1.29 3.65 3 P 0 8 0;2=6,4=1
P 1.27063996 3.578 40 P 0 8 0;0,2=15,4=0
P 5.803 3.567 3 P 0 8 0;2=6,4=1
P 5.43 3.967 3 P 0 8 0;2=6,4=1
P 6.165 1.94873996 3 P 0 8 0;2=6,4=1
P 6.4105 2.16141998 84 P 0 8 0;0,2=51,4=0
P 1.038 0.7624 3 P 0 8 0;2=6,4=1
P 4.037 2.593 3 P 0 8 0;2=6,4=1
P 3.978 2.593 3 P 0 8 0;2=6,4=1
P 4.81 0.707 3 P 0 8 0;2=6,4=1
P 4.8855 0.74043002 90 P 0 8 0;0,2=8,4=0
P 5.2975 1.345 76 P 0 8 0;0,2=52,4=0
P 5.273 1.24 69 P 0 8 0;0,2=18,4=0
P 6.47 1.135 3 P 0 8 0;2=6,4=1
P 6.421 1.135 60 P 0 8 0;0,2=2,4=0
P 4.595 3.22 3 P 0 8 0;2=6,4=1
P 4.554 3.22 60 P 0 8 0;0,2=2,4=0
P 4.175 3.52 3 P 0 8 0;2=6,4=1
P 4.175 3.4824 47 P 0 8 0;0,2=9,4=0
P 3.98 3.52 3 P 0 8 0;2=6,4=1
P 3.98 3.4804 47 P 0 8 0;0,2=9,4=0
P 3.973 3.207 3 P 0 8 0;2=6,4=1
P 4.075 3.05 3 P 0 8 0;2=6,4=1
P 4.1695 3.06643002 90 P 0 8 0;0,2=8,4=0
P 3.839 3.726 3 P 0 8 0;2=6,4=1
P 4.0355 3.58543002 90 P 0 8 0;0,2=8,4=0
P 4.1 3.58543002 3 P 0 8 0;2=6,4=1
P 5.637 3.569 60 P 0 8 0;0,2=2,4=0
P 5.637 3.524 3 P 0 8 0;2=1,4=1
P 5.276 3.189 3 P 0 8 0;2=6,4=1
P 5.329 3.189 3 P 0 8 0;2=6,4=1
P 5.386 3.189 3 P 0 8 0;2=6,4=1
P 5.271 3.456 3 P 0 8 0;2=6,4=1
P 5.271 3.406 3 P 0 8 0;2=6,4=1
P 5.324 3.456 3 P 0 8 0;2=6,4=1
P 5.381 3.456 3 P 0 8 0;2=6,4=1
P 5.324 3.406 3 P 0 8 0;2=6,4=1
P 5.381 3.406 3 P 0 8 0;2=6,4=1
P 5.29108002 3.306 102 P 0 8 0;0,2=22,4=0
P 5.762 3.617 60 P 0 8 0;0,2=2,4=0
P 5.802 3.617 3 P 0 8 0;2=6,4=1
P 5.73143002 3.712 33 P 0 8 0;0,2=12,4=0
P 5.763 3.712 3 P 0 8 0;2=6,4=1
P 5.762 3.807 60 P 0 8 0;0,2=2,4=0
P 5.762 3.757 60 P 0 8 0;0,2=2,4=0
P 5.762 3.857 60 P 0 8 0;0,2=2,4=0
P 5.803 3.757 3 P 0 8 0;2=6,4=1
P 5.803 3.807 3 P 0 8 0;2=6,4=1
P 5.601 3.915 60 P 0 8 0;0,2=2,4=0
P 5.602 3.865 3 P 0 8 0;2=6,4=1
P 5.645 3.79 3 P 0 8 0;2=6,4=1
P 5.48556998 3.912 33 P 0 8 0;0,2=12,4=0
P 5.48556998 3.877 3 P 0 8 0;2=1,4=1
P 5.237 3.777 3 P 0 8 0;2=6,4=1
P 5.282 3.777 3 P 0 8 0;2=6,4=1
P 5.237 3.841 3 P 0 8 0;2=6,4=1
P 5.322 3.777 3 P 0 8 0;2=6,4=1
P 5.298 3.827 69 P 0 8 0;0,2=18,4=0
P 5.254 3.738 85 P 0 8 0;0,2=18,4=0
P 5.336 3.738 85 P 0 8 0;0,2=18,4=0
P 5.385 4.07875 3 P 0 8 0;2=6,4=1
P 5.43503996 4.07875 19 P 0 8 0;0,2=31,4=0
P 5.55315 4.07875 19 P 0 8 0;0,2=31,4=0
P 5.67126004 4.07875 19 P 0 8 0;0,2=31,4=0
P 5.78936998 4.07875 19 P 0 8 0;0,2=31,4=0
P 5.90748002 4.07875 19 P 0 8 0;0,2=31,4=0
P 6.1437 4.07875 19 P 0 8 0;0,2=31,4=0
P 6.02558996 4.07875 19 P 0 8 0;0,2=31,4=0
P 0.199 2.83 3 P 0 8 0;2=6,4=1
P 1.2 3.645 3 P 0 8 0;2=6,4=1
P 1.1919 3.578 40 P 0 8 0;0,2=15,4=0
P 1.1 3.64 3 P 0 8 0;2=6,4=1
P 1.09346998 3.578 40 P 0 8 0;0,2=15,4=0
P 1.065 3.64 3 P 0 8 0;2=6,4=1
P 1.07378996 3.578 40 P 0 8 0;0,2=15,4=0
P 1.03 3.64 3 P 0 8 0;2=6,4=1
P 0.99 3.5 3 P 0 8 0;2=6,4=1
P 0.99505 3.578 40 P 0 8 0;0,2=15,4=0
P 0.664 0.774 3 P 0 8 0;2=6,4=1
P 0.833 0.871 3 P 0 8 0;2=6,4=1
P 0.66 0.911 3 P 0 8 0;2=6,4=1
P 0.73661998 0.9475 43 P 0 8 0;0,2=26,4=0
P 0.695 1 3 P 0 8 0;2=6,4=1
P 0.485 2.715 3 P 0 8 0;2=6,4=1
P 0.49656998 2.68 33 P 0 8 0;0,2=12,4=0
P 0.51771998 2.45073996 3 P 0 8 0;2=6,4=1
P 0.51771998 2.49173996 35 P 0 8 0;0,2=38,4=0
P 0.675 2.229 3 P 0 8 0;2=6,4=1
P 0.64 2.229 55 P 0 8 0;0,2=2,4=0
P 0.575 2.185 3 P 0 8 0;2=6,4=1
P 0.51643002 2.166 33 P 0 8 0;0,2=12,4=0
P 0.51771998 1.87986998 3 P 0 8 0;2=6,4=1
P 0.51771998 1.92086998 35 P 0 8 0;0,2=38,4=0
P 0.539 1.57 3 P 0 8 0;2=6,4=1
P 0.51771998 1.305 3 P 0 8 0;2=6,4=1
P 0.51771998 1.35 35 P 0 8 0;0,2=38,4=0
P 0.476 0.689 3 P 0 8 0;2=6,4=1
P 0.443 0.689 55 P 0 8 0;0,2=2,4=0
P 0.614 1.049 3 P 0 8 0;2=6,4=1
P 0.625 1.084 55 P 0 8 0;0,2=2,4=0
P 0.51771998 0.736 3 P 0 8 0;2=6,4=1
P 0.51771998 0.77913996 35 P 0 8 0;0,2=38,4=0
P 0.47 1 3 P 0 8 0;2=6,4=1
P 0.677 0.65 3 P 0 8 0;2=6,4=1
P 4.546 1.085 3 P 0 8 0;2=6,4=1
P 0.43705 3.51576004 21 P 0 8 0;2=76,4=0
P 0.43705 3.31655 21 P 0 8 0;2=76,4=0
P 0.24806998 3.47245 21 P 0 8 0;2=76,4=0
P 0.24806998 3.35985 21 P 0 8 0;2=76,4=0
P 0.24606004 3.4315 5 P 0 8 0;2=14,4=0
P 0.4587 3.4315 5 P 0 8 0;2=14,4=0
P 0.44098002 3.4008 5 P 0 8 0;2=14,4=0
P 0.22833996 3.4008 5 P 0 8 0;2=14,4=0
P 3.816 2.68 60 P 0 8 0;0,2=2,4=0
P 4.566 2.845 60 P 0 8 0;0,2=2,4=0
P 0.835 2.524 55 P 0 8 0;0,2=2,4=0
P 0.619 2.79 60 P 0 8 0;0,2=2,4=0
P 5.75071998 1.655 3 P 0 8 0;2=6,4=1
P 1.76 4.16 3 P 0 8 0;2=6,4=1
P 2.26 3.785 3 P 0 8 0;2=6,4=1
P 2.215 3.785 3 P 0 8 0;2=6,4=1
P 3.843 3.687 3 P 0 8 0;2=6,4=1
P 0.61488996 3.32328996 3 P 0 8 0;2=6,4=1
P 5.335 1.245 3 P 0 8 0;2=6,4=1
P 5.345 1.3 3 P 0 8 0;2=6,4=1
P 5.345 1.365 3 P 0 8 0;2=6,4=1
P 3.645 2.13 3 P 0 8 0;2=6,4=1
P 3.67 2.13 3 P 0 8 0;2=6,4=1
P 3.11 1.935 3 P 0 8 0;2=6,4=1
P 4.294 1.075 3 P 0 8 0;2=6,4=1
P 4.5 1.082 3 P 0 8 0;2=6,4=1
P 5.41 1.836 55 P 0 8 0;0,2=2,4=0
P 5.35 1.853 85 P 0 8 0;0,2=18,4=0
P 5.385 1.895 3 P 0 8 0;2=6,4=1
P 5.425 1.895 3 P 0 8 0;2=6,4=1
P 5.76458996 1.61971004 3 P 0 8 0;2=6,4=1
P 5.34 1.605 3 P 0 8 0;2=6,4=1
P 5.44 1.59 3 P 0 8 0;2=6,4=1
P 5.723 1.61 69 P 0 8 0;0,2=18,4=0
P 5.39 1.597 85 P 0 8 0;0,2=18,4=0
P 0.951 2.728 60 P 0 8 0;0,2=2,4=0
P 0.95048002 2.683 60 P 0 8 0;0,2=2,4=0
P 2.261 4.104 85 P 0 8 0;0,2=18,4=0
P 2.186 4.104 85 P 0 8 0;0,2=18,4=0
P 1.692 4.091 60 P 0 8 0;0,2=2,4=0
P 1.714 4.151 69 P 0 8 0;0,2=18,4=0
P 1.70111998 4.02013002 37 P 0 8 0;0,2=77,4=0
P 1.67946004 4.02013002 37 P 0 8 0;0,2=77,4=0
P 1.65781004 4.02013002 37 P 0 8 0;0,2=77,4=0
P 2.176 3.845 55 P 0 8 0;0,2=2,4=0
P 2.236 3.828 85 P 0 8 0;0,2=18,4=0
P 1.65781004 3.91186998 37 P 0 8 0;0,2=77,4=0
P 1.67946004 3.91186998 37 P 0 8 0;0,2=77,4=0
P 1.70111998 3.91186998 37 P 0 8 0;0,2=77,4=0
P 1.744 3.776 69 P 0 8 0;0,2=18,4=0
P 1.712 3.841 60 P 0 8 0;0,2=2,4=0
P 0.12878002 0.21716998 2 P 0 8 0;2=23,4=1
P 0.16878002 0.21716998 2 P 0 8 0;2=23,4=1
P 0.20878002 0.21716998 2 P 0 8 0;2=23,4=1
P 0.24878002 0.21716998 2 P 0 8 0;2=23,4=1
P 0.08413002 4.33598002 2 P 0 8 0;2=23,4=1
P 0.04413002 4.33598002 2 P 0 8 0;2=23,4=1
P 0.04 4.29618996 2 P 0 8 0;2=23,4=1
P 0.04 4.25618996 2 P 0 8 0;2=23,4=1
P 0.04 4.21618996 2 P 0 8 0;2=23,4=1
P 0.04 4.17618996 2 P 0 8 0;2=23,4=1
P 0.04 4.13618996 2 P 0 8 0;2=23,4=1
P 0.04 4.09618996 2 P 0 8 0;2=23,4=1
P 0.04 4.05618996 2 P 0 8 0;2=23,4=1
P 0.04 4.01618996 2 P 0 8 0;2=23,4=1
P 0.04 3.97618996 2 P 0 8 0;2=23,4=1
P 0.04 3.93618996 2 P 0 8 0;2=23,4=1
P 0.04 3.89618996 2 P 0 8 0;2=23,4=1
P 0.04 3.85618996 2 P 0 8 0;2=23,4=1
P 0.04 3.81618996 2 P 0 8 0;2=23,4=1
P 0.04 3.77618996 2 P 0 8 0;2=23,4=1
P 0.04 3.73618996 2 P 0 8 0;2=23,4=1
P 0.04 3.69618996 2 P 0 8 0;2=23,4=1
P 0.04 3.65618996 2 P 0 8 0;2=23,4=1
P 0.04 3.61618996 2 P 0 8 0;2=23,4=1
P 0.04 3.57618996 2 P 0 8 0;2=23,4=1
P 0.04 3.53618996 2 P 0 8 0;2=23,4=1
P 0.04 3.49618996 2 P 0 8 0;2=23,4=1
P 0.04 3.45618996 2 P 0 8 0;2=23,4=1
P 0.04 3.41618996 2 P 0 8 0;2=23,4=1
P 0.04 3.37618996 2 P 0 8 0;2=23,4=1
P 0.04 2.97618996 2 P 0 8 0;2=23,4=1
P 0.04 2.93618996 2 P 0 8 0;2=23,4=1
P 0.04 2.89618996 2 P 0 8 0;2=23,4=1
P 0.04 0.49618996 2 P 0 8 0;2=23,4=1
P 0.04 0.45618996 2 P 0 8 0;2=23,4=1
P 0.04 0.41618996 2 P 0 8 0;2=23,4=1
P 0.04 0.37618996 2 P 0 8 0;2=23,4=1
P 0.04 0.33618996 2 P 0 8 0;2=23,4=1
P 0.04 0.29618996 2 P 0 8 0;2=23,4=1
P 0.04 0.25618996 2 P 0 8 0;2=23,4=1
P 0.04878002 0.21716998 2 P 0 8 0;2=23,4=1
P 0.08878002 0.21716998 2 P 0 8 0;2=23,4=1
P 2.76413002 4.33598002 2 P 0 8 0;2=23,4=1
P 2.72413002 4.33598002 2 P 0 8 0;2=23,4=1
P 2.68413002 4.33598002 2 P 0 8 0;2=23,4=1
P 2.64413002 4.33598002 2 P 0 8 0;2=23,4=1
P 2.60413002 4.33598002 2 P 0 8 0;2=23,4=1
P 0.55055 0.45073002 2 P 0 8 0;2=23,4=1
P 0.55558002 0.49041004 2 P 0 8 0;2=23,4=1
P 0.57858996 0.52313002 2 P 0 8 0;2=23,4=1
P 0.61463002 0.54048002 2 P 0 8 0;2=23,4=1
P 0.55055 0.29073002 2 P 0 8 0;2=23,4=1
P 0.55055 0.33073002 2 P 0 8 0;2=23,4=1
P 0.55055 0.37073002 2 P 0 8 0;2=23,4=1
P 0.55055 0.41073002 2 P 0 8 0;2=23,4=1
P 0.48878002 0.21716998 2 P 0 8 0;2=23,4=1
P 0.52878002 0.21716998 2 P 0 8 0;2=23,4=1
P 0.55055 0.25073002 2 P 0 8 0;2=23,4=1
P 0.44413002 4.33598002 2 P 0 8 0;2=23,4=1
P 0.40413002 4.33598002 2 P 0 8 0;2=23,4=1
P 0.36413002 4.33598002 2 P 0 8 0;2=23,4=1
P 0.32413002 4.33598002 2 P 0 8 0;2=23,4=1
P 0.28878002 0.21716998 2 P 0 8 0;2=23,4=1
P 0.32878002 0.21716998 2 P 0 8 0;2=23,4=1
P 0.36878002 0.21716998 2 P 0 8 0;2=23,4=1
P 0.40878002 0.21716998 2 P 0 8 0;2=23,4=1
P 0.44878002 0.21716998 2 P 0 8 0;2=23,4=1
P 0.28413002 4.33598002 2 P 0 8 0;2=23,4=1
P 0.24413002 4.33598002 2 P 0 8 0;2=23,4=1
P 0.20413002 4.33598002 2 P 0 8 0;2=23,4=1
P 0.16413002 4.33598002 2 P 0 8 0;2=23,4=1
P 0.12413002 4.33598002 2 P 0 8 0;2=23,4=1
P 0.889 0.67 3 P 0 8 0;2=6,4=1
P 0.9575 0.691 81 P 0 8 0;0,2=5,4=0
P 0.6546 0.54196998 2 P 0 8 0;2=23,4=1
P 0.6946 0.54196998 2 P 0 8 0;2=23,4=1
P 0.7346 0.54196998 2 P 0 8 0;2=23,4=1
P 0.7746 0.54196998 2 P 0 8 0;2=23,4=1
P 0.8146 0.54196998 2 P 0 8 0;2=23,4=1
P 0.64413002 4.33598002 2 P 0 8 0;2=23,4=1
P 0.60413002 4.33598002 2 P 0 8 0;2=23,4=1
P 0.56413002 4.33598002 2 P 0 8 0;2=23,4=1
P 0.52413002 4.33598002 2 P 0 8 0;2=23,4=1
P 0.48413002 4.33598002 2 P 0 8 0;2=23,4=1
P 0.8575 2.0275 3 P 0 8 0;2=6,4=1
P 0.86206998 2.091 74 P 0 8 0;0,2=78,4=0
P 1.195 0.57693996 3 P 0 8 0;2=6,4=1
P 1.2157 0.6136 60 P 0 8 0;0,2=2,4=0
P 0.8546 0.54196998 2 P 0 8 0;2=23,4=1
P 0.8946 0.54196998 2 P 0 8 0;2=23,4=1
P 0.9346 0.54196998 2 P 0 8 0;2=23,4=1
P 0.9746 0.54196998 2 P 0 8 0;2=23,4=1
P 0.80413002 4.33598002 2 P 0 8 0;2=23,4=1
P 0.76413002 4.33598002 2 P 0 8 0;2=23,4=1
P 0.72413002 4.33598002 2 P 0 8 0;2=23,4=1
P 0.68413002 4.33598002 2 P 0 8 0;2=23,4=1
P 0.66 4.19 3 P 0 8 0;2=6,4=1
P 0.67 2.831 2 P 0 8 0;2=23,4=1
P 0.79248002 2.661 2 P 0 8 0;2=23,4=1
P 0.81998996 2.661 42 P 0 8 0;0,2=43,4=0
P 0.80148002 2.53648002 3 P 0 8 0;2=6,4=1
P 0.715 2.478 3 P 0 8 0;2=6,4=1
P 0.715 2.444 55 P 0 8 0;0,2=2,4=0
P 0.714 2.217 3 P 0 8 0;2=6,4=1
P 0.714 2.252 55 P 0 8 0;0,2=2,4=0
P 0.74593002 2.02206998 3 P 0 8 0;2=6,4=1
P 0.74593002 2.091 74 P 0 8 0;0,2=78,4=0
P 1.0146 0.54196998 2 P 0 8 0;2=23,4=1
P 1.0546 0.54196998 2 P 0 8 0;2=23,4=1
P 1.0946 0.54196998 2 P 0 8 0;2=23,4=1
P 1.1346 0.54196998 2 P 0 8 0;2=23,4=1
P 1.1746 0.54196998 2 P 0 8 0;2=23,4=1
P 1.00413002 4.33598002 2 P 0 8 0;2=23,4=1
P 0.96413002 4.33598002 2 P 0 8 0;2=23,4=1
P 0.92413002 4.33598002 2 P 0 8 0;2=23,4=1
P 0.88413002 4.33598002 2 P 0 8 0;2=23,4=1
P 0.84413002 4.33598002 2 P 0 8 0;2=23,4=1
P 1.025 4.2 3 P 0 8 0;2=6,4=1
P 0.94 4.2 3 P 0 8 0;2=6,4=1
P 0.858 2.87451998 2 P 0 8 0;2=7,4=1
P 0.988 2.724 3 P 0 8 0;2=6,4=1
P 0.987 2.683 3 P 0 8 0;2=1,4=1
P 0.856 2.637 2 P 0 8 0;2=23,4=1
P 0.81998996 2.64131004 42 P 0 8 0;0,2=43,4=0
P 0.93031998 2.46476998 3 P 0 8 0;2=6,4=1
P 0.872 2.583 3 P 0 8 0;2=6,4=1
P 0.907 2.58048002 60 P 0 8 0;0,2=2,4=0
P 0.868 2.3 2 P 0 8 0;2=23,4=1
P 0.8594 2.2465 48 P 0 8 0;0,2=37,4=0
P 1.401 3.956 3 P 0 8 0;2=6,4=1
P 1.435 3.946 60 P 0 8 0;0,2=2,4=0
P 1.40123002 3.91603996 3 P 0 8 0;2=6,4=1
P 1.45056998 3.901 33 P 0 8 0;0,2=12,4=0
P 1.48 3.7 3 P 0 8 0;2=6,4=1
P 1.38163002 0.21716998 2 P 0 8 0;2=23,4=1
P 1.42163002 0.21716998 2 P 0 8 0;2=23,4=1
P 1.46163002 0.21716998 2 P 0 8 0;2=23,4=1
P 1.50163002 0.21716998 2 P 0 8 0;2=23,4=1
P 1.54163002 0.21716998 2 P 0 8 0;2=23,4=1
P 1.36413002 4.33598002 2 P 0 8 0;2=23,4=1
P 1.32413002 4.33598002 2 P 0 8 0;2=23,4=1
P 1.28413002 4.33598002 2 P 0 8 0;2=23,4=1
P 1.24413002 4.33598002 2 P 0 8 0;2=23,4=1
P 1.20413002 4.33598002 2 P 0 8 0;2=23,4=1
P 1.515 3.7 3 P 0 8 0;2=6,4=1
P 1.385 0.75 2 P 0 8 0;2=23,4=1
P 1.44 0.625 2 P 0 8 0;2=23,4=1
P 1.5184 0.79935 2 P 0 8 0;2=23,4=1
P 1.2146 0.54196998 2 P 0 8 0;2=23,4=1
P 1.2546 0.54196998 2 P 0 8 0;2=23,4=1
P 1.2945 0.53916998 2 P 0 8 0;2=23,4=1
P 1.3292 0.51926004 2 P 0 8 0;2=23,4=1
P 1.34976998 0.48496004 2 P 0 8 0;2=23,4=1
P 1.35298996 0.44508996 2 P 0 8 0;2=23,4=1
P 1.35298996 0.40508996 2 P 0 8 0;2=23,4=1
P 1.35298996 0.36508996 2 P 0 8 0;2=23,4=1
P 1.35298996 0.32508996 2 P 0 8 0;2=23,4=1
P 1.35298996 0.28508996 2 P 0 8 0;2=23,4=1
P 1.35298996 0.24508996 2 P 0 8 0;2=23,4=1
P 1.16413002 4.33598002 2 P 0 8 0;2=23,4=1
P 1.12413002 4.33598002 2 P 0 8 0;2=23,4=1
P 1.08413002 4.33598002 2 P 0 8 0;2=23,4=1
P 1.04413002 4.33598002 2 P 0 8 0;2=23,4=1
P 1.96413002 4.33598002 2 P 0 8 0;2=23,4=1
P 1.92413002 4.33598002 2 P 0 8 0;2=23,4=1
P 1.915 4.13 3 P 0 8 0;2=6,4=1
P 1.8832 0.74 93 P 0 8 0;0,2=54,4=0
P 1.88413002 4.33598002 2 P 0 8 0;2=23,4=1
P 1.84413002 4.33598002 2 P 0 8 0;2=23,4=1
P 1.80413002 4.33598002 2 P 0 8 0;2=23,4=1
P 1.76413002 4.33598002 2 P 0 8 0;2=23,4=1
P 1.746 4.061 3 P 0 8 0;2=6,4=1
P 1.746 4.106 3 P 0 8 0;2=1,4=1
P 1.751 3.871 3 P 0 8 0;2=6,4=1
P 1.746 4.016 3 P 0 8 0;2=6,4=1
P 1.751 3.826 3 P 0 8 0;2=1,4=1
P 1.786 3.746 3 P 0 8 0;2=6,4=1
P 1.786 3.786 3 P 0 8 0;2=6,4=1
P 2.0966 3.315 2 P 0 8 0;2=23,4=1
P 1.72413002 4.33598002 2 P 0 8 0;2=23,4=1
P 1.68413002 4.33598002 2 P 0 8 0;2=23,4=1
P 1.64413002 4.33598002 2 P 0 8 0;2=23,4=1
P 1.60413002 4.33598002 2 P 0 8 0;2=23,4=1
P 1.56413002 4.33598002 2 P 0 8 0;2=23,4=1
P 1.671 4.056 2 P 0 8 0;2=23,4=1
P 1.5086 0.674 3 P 0 8 0;2=1,4=1
P 1.548 0.6632 55 P 0 8 0;0,2=2,4=0
P 1.59111998 0.45653996 2 P 0 8 0;2=23,4=1
P 1.60736004 0.49308996 2 P 0 8 0;2=23,4=1
P 1.58795 0.29666998 2 P 0 8 0;2=23,4=1
P 1.58795 0.33666998 2 P 0 8 0;2=23,4=1
P 1.58795 0.37666998 2 P 0 8 0;2=23,4=1
P 1.58795 0.41666998 2 P 0 8 0;2=23,4=1
P 1.58163002 0.21716998 2 P 0 8 0;2=23,4=1
P 1.58795 0.25666998 2 P 0 8 0;2=23,4=1
P 1.52413002 4.33598002 2 P 0 8 0;2=23,4=1
P 1.48413002 4.33598002 2 P 0 8 0;2=23,4=1
P 1.44413002 4.33598002 2 P 0 8 0;2=23,4=1
P 1.40413002 4.33598002 2 P 0 8 0;2=23,4=1
P 2.56413002 4.33598002 2 P 0 8 0;2=23,4=1
P 2.52413002 4.33598002 2 P 0 8 0;2=23,4=1
P 2.48413002 4.33598002 2 P 0 8 0;2=23,4=1
P 2.44413002 4.33598002 2 P 0 8 0;2=23,4=1
P 2.40413002 4.33598002 2 P 0 8 0;2=23,4=1
P 2.36413002 4.33598002 2 P 0 8 0;2=23,4=1
P 2.32413002 4.33598002 2 P 0 8 0;2=23,4=1
P 2.28413002 4.33598002 2 P 0 8 0;2=23,4=1
P 2.295 4.15 3 P 0 8 0;2=6,4=1
P 2.285 3.825 3 P 0 8 0;2=1,4=1
P 2.24413002 4.33598002 2 P 0 8 0;2=23,4=1
P 2.20413002 4.33598002 2 P 0 8 0;2=23,4=1
P 2.16413002 4.33598002 2 P 0 8 0;2=23,4=1
P 2.12413002 4.33598002 2 P 0 8 0;2=23,4=1
P 2.176 4.151 3 P 0 8 0;2=6,4=1
P 2.256 4.151 3 P 0 8 0;2=6,4=1
P 2.215 4.15 3 P 0 8 0;2=6,4=1
P 2.18 3.811 3 P 0 8 0;2=6,4=1
P 2.218 2.895 2 P 0 8 0;2=23,4=1
P 2.218 2.931 55 P 0 8 0;0,2=2,4=0
P 2.173 2.895 2 P 0 8 0;2=23,4=1
P 2.083 2.895 2 P 0 8 0;2=23,4=1
P 2.08413002 4.33598002 2 P 0 8 0;2=23,4=1
P 2.04413002 4.33598002 2 P 0 8 0;2=23,4=1
P 2.00413002 4.33598002 2 P 0 8 0;2=23,4=1
P 0.22703996 3.79855 5 P 0 8 0;2=74,4=0
P 0.19878002 3.73031004 5 P 0 8 0;2=74,4=0
P 0.22703996 3.66206998 5 P 0 8 0;2=74,4=0
P 0.29528002 3.63381004 5 P 0 8 0;2=74,4=0
P 0.36351998 3.66206998 5 P 0 8 0;2=74,4=0
P 0.39178002 3.73031004 5 P 0 8 0;2=74,4=0
P 0.36351998 3.79855 5 P 0 8 0;2=74,4=0
P 0.29528002 3.82681004 5 P 0 8 0;2=74,4=0
P 6.19961004 2.21273996 2 P 0 8 0;2=23,4=1
P 6.19961004 2.30873996 2 P 0 8 0;2=23,4=1
P 4.3445 1.16598996 2 P 0 8 0;2=23,4=1
P 4.4405 1.16598996 2 P 0 8 0;2=23,4=1
P 3.45301004 1.96298996 2 P 0 8 0;2=23,4=1
P 3.65101004 1.94758996 2 P 0 8 0;2=23,4=1
P 4.44 2.63 3 P 0 8 0;2=6,4=1
P 4.395 2.665 3 P 0 8 0;2=6,4=1
P 4.455 2.672 85 P 0 8 0;0,2=18,4=0
P 4.39 2.699 55 P 0 8 0;0,2=2,4=0
P 4.6 2.895 3 P 0 8 0;2=6,4=1
P 4.6 2.845 3 P 0 8 0;2=6,4=1
P 5.76 2.087 85 P 0 8 0;0,2=18,4=0
P 3.42 3.76 3 P 0 8 0;2=6,4=1
P 3.385 3.76 3 P 0 8 0;2=6,4=1
P 3.315 3.76 3 P 0 8 0;2=6,4=1
P 3.26 3.74 3 P 0 8 0;2=6,4=1
P 3.48 3.718 85 P 0 8 0;0,2=18,4=0
P 3.4 3.718 85 P 0 8 0;0,2=18,4=0
P 3.255 3.706 55 P 0 8 0;0,2=2,4=0
P 3.32 3.718 85 P 0 8 0;0,2=18,4=0
P 6.56038996 1.81205 2 P 0 8 0;2=23,4=1
P 6.56038996 1.77205 2 P 0 8 0;2=23,4=1
P 6.56038996 1.73205 2 P 0 8 0;2=23,4=1
P 6.56038996 1.69205 2 P 0 8 0;2=23,4=1
P 6.56038996 1.65205 2 P 0 8 0;2=23,4=1
P 6.56038996 1.61205 2 P 0 8 0;2=23,4=1
P 6.56038996 1.57205 2 P 0 8 0;2=23,4=1
P 6.56038996 1.53205 2 P 0 8 0;2=23,4=1
P 6.56038996 1.49205 2 P 0 8 0;2=23,4=1
P 6.56038996 1.45205 2 P 0 8 0;2=23,4=1
P 6.56038996 1.05205 2 P 0 8 0;2=23,4=1
P 6.56038996 1.01205 2 P 0 8 0;2=23,4=1
P 6.56038996 0.97205 2 P 0 8 0;2=23,4=1
P 6.56038996 0.93205 2 P 0 8 0;2=23,4=1
P 6.56038996 0.89205 2 P 0 8 0;2=23,4=1
P 6.56038996 0.85205 2 P 0 8 0;2=23,4=1
P 6.56038996 0.81205 2 P 0 8 0;2=23,4=1
P 6.56038996 0.77205 2 P 0 8 0;2=23,4=1
P 6.56038996 0.73205 2 P 0 8 0;2=23,4=1
P 6.56038996 0.69205 2 P 0 8 0;2=23,4=1
P 6.56038996 0.65205 2 P 0 8 0;2=23,4=1
P 6.56038996 0.61205 2 P 0 8 0;2=23,4=1
P 6.56038996 0.57205 2 P 0 8 0;2=23,4=1
P 6.53401998 0.54196998 2 P 0 8 0;2=23,4=1
P 6.49401998 0.54196998 2 P 0 8 0;2=23,4=1
P 6.29401998 0.54196998 2 P 0 8 0;2=23,4=1
P 6.25401998 0.54196998 2 P 0 8 0;2=23,4=1
P 6.21401998 0.54196998 2 P 0 8 0;2=23,4=1
P 6.17401998 0.54196998 2 P 0 8 0;2=23,4=1
P 6.13401998 0.54196998 2 P 0 8 0;2=23,4=1
P 6.09401998 0.54196998 2 P 0 8 0;2=23,4=1
P 6.05401998 0.54196998 2 P 0 8 0;2=23,4=1
P 6.01401998 0.54196998 2 P 0 8 0;2=23,4=1
P 5.97401998 0.54196998 2 P 0 8 0;2=23,4=1
P 5.93401998 0.54196998 2 P 0 8 0;2=23,4=1
P 5.89401998 0.54196998 2 P 0 8 0;2=23,4=1
P 5.85401998 0.54196998 2 P 0 8 0;2=23,4=1
P 5.81401998 0.54196998 2 P 0 8 0;2=23,4=1
P 5.77401998 0.54196998 2 P 0 8 0;2=23,4=1
P 5.73401998 0.54196998 2 P 0 8 0;2=23,4=1
P 5.69401998 0.54196998 2 P 0 8 0;2=23,4=1
P 5.65401998 0.54196998 2 P 0 8 0;2=23,4=1
P 5.61401998 0.54196998 2 P 0 8 0;2=23,4=1
P 5.57401998 0.54196998 2 P 0 8 0;2=23,4=1
P 5.53401998 0.54196998 2 P 0 8 0;2=23,4=1
P 5.49401998 0.54196998 2 P 0 8 0;2=23,4=1
P 5.45401998 0.54196998 2 P 0 8 0;2=23,4=1
P 5.41401998 0.54196998 2 P 0 8 0;2=23,4=1
P 5.37401998 0.54196998 2 P 0 8 0;2=23,4=1
P 5.33401998 0.54196998 2 P 0 8 0;2=23,4=1
P 5.29401998 0.54196998 2 P 0 8 0;2=23,4=1
P 5.25401998 0.54196998 2 P 0 8 0;2=23,4=1
P 5.21401998 0.54196998 2 P 0 8 0;2=23,4=1
P 5.17401998 0.54196998 2 P 0 8 0;2=23,4=1
P 5.13401998 0.54196998 2 P 0 8 0;2=23,4=1
P 5.09401998 0.54196998 2 P 0 8 0;2=23,4=1
P 5.05401998 0.54196998 2 P 0 8 0;2=23,4=1
P 5.01401998 0.54196998 2 P 0 8 0;2=23,4=1
P 4.97401998 0.54196998 2 P 0 8 0;2=23,4=1
P 4.93401998 0.54196998 2 P 0 8 0;2=23,4=1
P 4.89401998 0.54196998 2 P 0 8 0;2=23,4=1
P 4.85401998 0.54196998 2 P 0 8 0;2=23,4=1
P 4.81401998 0.54196998 2 P 0 8 0;2=23,4=1
P 4.77401998 0.54196998 2 P 0 8 0;2=23,4=1
P 4.73401998 0.54196998 2 P 0 8 0;2=23,4=1
P 4.69401998 0.54196998 2 P 0 8 0;2=23,4=1
P 4.65401998 0.54196998 2 P 0 8 0;2=23,4=1
P 4.61401998 0.54196998 2 P 0 8 0;2=23,4=1
P 4.57401998 0.54196998 2 P 0 8 0;2=23,4=1
P 4.53401998 0.54196998 2 P 0 8 0;2=23,4=1
P 4.49401998 0.54196998 2 P 0 8 0;2=23,4=1
P 4.45401998 0.54196998 2 P 0 8 0;2=23,4=1
P 4.41401998 0.54196998 2 P 0 8 0;2=23,4=1
P 4.37401998 0.54196998 2 P 0 8 0;2=23,4=1
P 4.33401998 0.54196998 2 P 0 8 0;2=23,4=1
P 4.29401998 0.54196998 2 P 0 8 0;2=23,4=1
P 4.25401998 0.54196998 2 P 0 8 0;2=23,4=1
P 4.21401998 0.54196998 2 P 0 8 0;2=23,4=1
P 4.17401998 0.54196998 2 P 0 8 0;2=23,4=1
P 2.80413002 4.33598002 2 P 0 8 0;2=23,4=1
P 2.84413002 4.33598002 2 P 0 8 0;2=23,4=1
P 2.88413002 4.33598002 2 P 0 8 0;2=23,4=1
P 2.92413002 4.33598002 2 P 0 8 0;2=23,4=1
P 2.96413002 4.33598002 2 P 0 8 0;2=23,4=1
P 3.00413002 4.33598002 2 P 0 8 0;2=23,4=1
P 3.04413002 4.33598002 2 P 0 8 0;2=23,4=1
P 3.08413002 4.33598002 2 P 0 8 0;2=23,4=1
P 3.12413002 4.33598002 2 P 0 8 0;2=23,4=1
P 3.16413002 4.33598002 2 P 0 8 0;2=23,4=1
P 3.20413002 4.33598002 2 P 0 8 0;2=23,4=1
P 3.24413002 4.33598002 2 P 0 8 0;2=23,4=1
P 3.28413002 4.33598002 2 P 0 8 0;2=23,4=1
P 3.32413002 4.33598002 2 P 0 8 0;2=23,4=1
P 3.36413002 4.33598002 2 P 0 8 0;2=23,4=1
P 3.40413002 4.33598002 2 P 0 8 0;2=23,4=1
P 3.44413002 4.33598002 2 P 0 8 0;2=23,4=1
P 3.48413002 4.33598002 2 P 0 8 0;2=23,4=1
P 3.52413002 4.33598002 2 P 0 8 0;2=23,4=1
P 3.56413002 4.33598002 2 P 0 8 0;2=23,4=1
P 3.60413002 4.33598002 2 P 0 8 0;2=23,4=1
P 3.64413002 4.33598002 2 P 0 8 0;2=23,4=1
P 3.68413002 4.33598002 2 P 0 8 0;2=23,4=1
P 3.72413002 4.33598002 2 P 0 8 0;2=23,4=1
P 3.76413002 4.33598002 2 P 0 8 0;2=23,4=1
P 3.80413002 4.33598002 2 P 0 8 0;2=23,4=1
P 3.84413002 4.33598002 2 P 0 8 0;2=23,4=1
P 3.88413002 4.33598002 2 P 0 8 0;2=23,4=1
P 3.92413002 4.33598002 2 P 0 8 0;2=23,4=1
P 3.96413002 4.33598002 2 P 0 8 0;2=23,4=1
P 4.00413002 4.33598002 2 P 0 8 0;2=23,4=1
P 4.04413002 4.33598002 2 P 0 8 0;2=23,4=1
P 4.08413002 4.33598002 2 P 0 8 0;2=23,4=1
P 4.12413002 4.33598002 2 P 0 8 0;2=23,4=1
P 4.16413002 4.33598002 2 P 0 8 0;2=23,4=1
P 4.20413002 4.33598002 2 P 0 8 0;2=23,4=1
P 4.24413002 4.33598002 2 P 0 8 0;2=23,4=1
P 4.28413002 4.33598002 2 P 0 8 0;2=23,4=1
P 4.32413002 4.33598002 2 P 0 8 0;2=23,4=1
P 4.36413002 4.33598002 2 P 0 8 0;2=23,4=1
P 4.40413002 4.33598002 2 P 0 8 0;2=23,4=1
P 4.44413002 4.33598002 2 P 0 8 0;2=23,4=1
P 4.48413002 4.33598002 2 P 0 8 0;2=23,4=1
P 4.52413002 4.33598002 2 P 0 8 0;2=23,4=1
P 4.56413002 4.33598002 2 P 0 8 0;2=23,4=1
P 4.60413002 4.33598002 2 P 0 8 0;2=23,4=1
P 4.64413002 4.33598002 2 P 0 8 0;2=23,4=1
P 4.68413002 4.33598002 2 P 0 8 0;2=23,4=1
P 4.72413002 4.33598002 2 P 0 8 0;2=23,4=1
P 4.76413002 4.33598002 2 P 0 8 0;2=23,4=1
P 4.80413002 4.33598002 2 P 0 8 0;2=23,4=1
P 4.84413002 4.33598002 2 P 0 8 0;2=23,4=1
P 4.88413002 4.33598002 2 P 0 8 0;2=23,4=1
P 4.92413002 4.33598002 2 P 0 8 0;2=23,4=1
P 4.96413002 4.33598002 2 P 0 8 0;2=23,4=1
P 5.00413002 4.33598002 2 P 0 8 0;2=23,4=1
P 5.04413002 4.33598002 2 P 0 8 0;2=23,4=1
P 5.08413002 4.33598002 2 P 0 8 0;2=23,4=1
P 5.12413002 4.33598002 2 P 0 8 0;2=23,4=1
P 5.16413002 4.33598002 2 P 0 8 0;2=23,4=1
P 5.20413002 4.33598002 2 P 0 8 0;2=23,4=1
P 5.24413002 4.33598002 2 P 0 8 0;2=23,4=1
P 5.28413002 4.33598002 2 P 0 8 0;2=23,4=1
P 5.32413002 4.33598002 2 P 0 8 0;2=23,4=1
P 5.36413002 4.33598002 2 P 0 8 0;2=23,4=1
P 5.40413002 4.33598002 2 P 0 8 0;2=23,4=1
P 5.44413002 4.33598002 2 P 0 8 0;2=23,4=1
P 5.48413002 4.33598002 2 P 0 8 0;2=23,4=1
P 5.52413002 4.33598002 2 P 0 8 0;2=23,4=1
P 5.56413002 4.33598002 2 P 0 8 0;2=23,4=1
P 5.60413002 4.33598002 2 P 0 8 0;2=23,4=1
P 5.64413002 4.33598002 2 P 0 8 0;2=23,4=1
P 5.68413002 4.33598002 2 P 0 8 0;2=23,4=1
P 5.72413002 4.33598002 2 P 0 8 0;2=23,4=1
P 5.76413002 4.33598002 2 P 0 8 0;2=23,4=1
P 5.80413002 4.33598002 2 P 0 8 0;2=23,4=1
P 5.84413002 4.33598002 2 P 0 8 0;2=23,4=1
P 5.88413002 4.33598002 2 P 0 8 0;2=23,4=1
P 5.92413002 4.33598002 2 P 0 8 0;2=23,4=1
P 5.96413002 4.33598002 2 P 0 8 0;2=23,4=1
P 6.00413002 4.33598002 2 P 0 8 0;2=23,4=1
P 6.04413002 4.33598002 2 P 0 8 0;2=23,4=1
P 6.08413002 4.33598002 2 P 0 8 0;2=23,4=1
P 6.12413002 4.33598002 2 P 0 8 0;2=23,4=1
P 6.16413002 4.33598002 2 P 0 8 0;2=23,4=1
P 6.20413002 4.33598002 2 P 0 8 0;2=23,4=1
P 6.24413002 4.33598002 2 P 0 8 0;2=23,4=1
P 6.28413002 4.33598002 2 P 0 8 0;2=23,4=1
P 6.32413002 4.33598002 2 P 0 8 0;2=23,4=1
P 6.36413002 4.33598002 2 P 0 8 0;2=23,4=1
P 6.40413002 4.33598002 2 P 0 8 0;2=23,4=1
P 6.44413002 4.33598002 2 P 0 8 0;2=23,4=1
P 6.48413002 4.33598002 2 P 0 8 0;2=23,4=1
P 6.52413002 4.33598002 2 P 0 8 0;2=23,4=1
P 6.56038996 4.31908996 2 P 0 8 0;2=23,4=1
P 6.56038996 4.27908996 2 P 0 8 0;2=23,4=1
P 6.56038996 4.23908996 2 P 0 8 0;2=23,4=1
P 6.56038996 4.19908996 2 P 0 8 0;2=23,4=1
P 6.56038996 4.15908996 2 P 0 8 0;2=23,4=1
P 6.56038996 4.11908996 2 P 0 8 0;2=23,4=1
P 6.56038996 4.07908996 2 P 0 8 0;2=23,4=1
P 6.56038996 4.03908996 2 P 0 8 0;2=23,4=1
P 6.56038996 3.99908996 2 P 0 8 0;2=23,4=1
P 6.56038996 3.95908996 2 P 0 8 0;2=23,4=1
P 6.56038996 3.91908996 2 P 0 8 0;2=23,4=1
P 6.56038996 3.87908996 2 P 0 8 0;2=23,4=1
P 6.56038996 3.83908996 2 P 0 8 0;2=23,4=1
P 6.56038996 3.79908996 2 P 0 8 0;2=23,4=1
P 6.56038996 3.75908996 2 P 0 8 0;2=23,4=1
P 6.56038996 3.71908996 2 P 0 8 0;2=23,4=1
P 6.56038996 3.67908996 2 P 0 8 0;2=23,4=1
P 6.56038996 3.63908996 2 P 0 8 0;2=23,4=1
P 6.56038996 3.59908996 2 P 0 8 0;2=23,4=1
P 6.56038996 3.55908996 2 P 0 8 0;2=23,4=1
P 6.56038996 3.51908996 2 P 0 8 0;2=23,4=1
P 6.56038996 3.47908996 2 P 0 8 0;2=23,4=1
P 6.56038996 3.43908996 2 P 0 8 0;2=23,4=1
P 6.56038996 3.39908996 2 P 0 8 0;2=23,4=1
P 6.56038996 3.35908996 2 P 0 8 0;2=23,4=1
P 6.56038996 3.31908996 2 P 0 8 0;2=23,4=1
P 6.56038996 3.27908996 2 P 0 8 0;2=23,4=1
P 6.56038996 3.23908996 2 P 0 8 0;2=23,4=1
P 6.56038996 3.19908996 2 P 0 8 0;2=23,4=1
P 6.56038996 3.15908996 2 P 0 8 0;2=23,4=1
P 6.56038996 3.11908996 2 P 0 8 0;2=23,4=1
P 6.56038996 2.35585 2 P 0 8 0;2=23,4=1
P 5.119 2.762 3 P 0 8 0;2=6,4=1
P 5.63341004 0.62101998 3 P 0 8 0;2=6,4=1
P 5.59941004 0.6212 3 P 0 8 0;2=6,4=1
P 2.419 2.388 3 P 0 8 0;2=6,4=1
P 2.805 2.243 3 P 0 8 0;2=6,4=1
P 2.7526 2.23 3 P 0 8 0;2=6,4=1
P 4.56091004 1.72531998 4 P 0 8 0;0,2=4,4=0
P 4.278 1.003 3 P 0 8 0;2=6,4=1
P 3.08966998 2.04 3 P 0 8 0;2=6,4=1
P 2.41441004 2.15 3 P 0 8 0;2=6,4=1
P 2.69 2.15 3 P 0 8 0;2=6,4=1
P 5.83 1.92 3 P 0 8 0;2=6,4=1
P 5.805 1.945 3 P 0 8 0;2=6,4=1
P 5.089 3.775 60 P 0 8 0;0,2=2,4=0
P 5.045 3.76 3 P 0 8 0;2=6,4=1
P 5.05 3.795 3 P 0 8 0;2=6,4=1
P 5.05 3.837 85 P 0 8 0;0,2=18,4=0
P 4.588 3.927 69 P 0 8 0;0,2=18,4=0
P 4.53 3.891 55 P 0 8 0;0,2=2,4=0
P 4.54 3.97 3 P 0 8 0;2=6,4=1
P 4.54 3.935 3 P 0 8 0;2=6,4=1
P 4.62 2.5 3 P 0 8 0;2=6,4=1
P 3.23743996 2.865 28 P 0 8 0;0,2=32,4=0
P 3.305 2.915 3 P 0 8 0;2=6,4=1
P 3.23743996 2.765 28 P 0 8 0;0,2=32,4=0
P 3.145 2.765 3 P 0 8 0;2=6,4=1
P 3.95588002 2.88533002 106 P 0 8 0;0,2=27,4=0
P 6.071 2.225 60 P 0 8 0;0,2=2,4=0
P 6.071 2.27 60 P 0 8 0;0,2=2,4=0
P 6.105 2.27 3 P 0 8 0;2=6,4=1
P 6.141 2.278 55 P 0 8 0;0,2=2,4=0
P 6.141 2.241 3 P 0 8 0;2=6,4=1
P 2.54 2.135 3 P 0 8 0;2=6,4=1
P 2.59 2.23 3 P 0 8 0;2=6,4=1
P 5.859 0.796 3 P 0 8 0;2=6,4=1
P 5.78043002 0.609 33 P 0 8 0;0,2=12,4=0
P 5.80643002 0.609 3 P 0 8 0;2=6,4=1
P 5.772 0.658 55 P 0 8 0;0,2=2,4=0
P 5.805 0.658 3 P 0 8 0;2=6,4=1
P 5.37 0.69 3 P 0 8 0;2=6,4=1
P 5.43956998 0.635 33 P 0 8 0;0,2=12,4=0
P 5.43956998 0.60543002 3 P 0 8 0;2=6,4=1
P 5.56533002 0.63511998 104 P 0 8 0;0,2=27,4=0
P 5.575 0.932 85 P 0 8 0;0,2=18,4=0
P 6.335 1.96873996 3 P 0 8 0;2=6,4=1
P 5.59 0.888 3 P 0 8 0;2=6,4=1
P 4.933 1.215 3 P 0 8 0;2=6,4=1
P 4.933 1.264 69 P 0 8 0;0,2=18,4=0
P 4.894 1.263 3 P 0 8 0;2=6,4=1
P 4.79866998 1.38866998 3 P 0 8 0;2=6,4=1
P 5.001 1.43 60 P 0 8 0;0,2=2,4=0
P 5.0395 1.43 3 P 0 8 0;2=6,4=1
P 4.44 2.461 55 P 0 8 0;0,2=2,4=0
P 4.44 2.5 3 P 0 8 0;2=6,4=1
P 4.965 1.925 3 P 0 8 0;2=6,4=1
P 4.96 2.055 3 P 0 8 0;2=6,4=1
P 5.346 1.52 3 P 0 8 0;2=6,4=1
P 5.346 1.483 3 P 0 8 0;2=6,4=1
P 5.2975 1.595 76 P 0 8 0;0,2=52,4=0
P 5.2975 1.47 76 P 0 8 0;0,2=52,4=0
P 4.96 1.675 3 P 0 8 0;2=6,4=1
P 3.99 2.25 3 P 0 8 0;2=6,4=1
P 3.99 2.21406998 3 P 0 8 0;2=6,4=1
P 3.7206 2.13 3 P 0 8 0;2=6,4=1
P 3.6956 2.13 3 P 0 8 0;2=6,4=1
P 4.78 1.98 3 P 0 8 0;2=6,4=1
P 5.64 0.944 55 P 0 8 0;0,2=2,4=0
P 5.6065 0.7045 3 P 0 8 0;2=72,4=1
P 5.602 0.815 3 P 0 8 0;2=6,4=1
P 5.59 0.85 3 P 0 8 0;2=6,4=1
P 5.625 0.746 3 P 0 8 0;2=6,4=1
P 5.632 0.859 69 P 0 8 0;0,2=18,4=0
P 5.649 0.792 60 P 0 8 0;0,2=2,4=0
P 5.55 0.863 69 P 0 8 0;0,2=18,4=0
P 5.569 0.792 60 P 0 8 0;0,2=2,4=0
P 4.22 0.775 3 P 0 8 0;2=6,4=1
P 4.345 0.77 3 P 0 8 0;2=6,4=1
P 4.4843 0.8954 3 P 0 8 0;2=6,4=1
P 4.442 1.005 3 P 0 8 0;2=6,4=1
P 4.31 1.165 3 P 0 8 0;2=6,4=1
P 4.414 0.781 3 P 0 8 0;2=1,4=1
P 4.414 0.82366004 56 P 0 8 0;0,2=10,4=0
P 4.46 0.973 60 P 0 8 0;0,2=2,4=0
P 4.335 1.005 3 P 0 8 0;2=6,4=1
P 4.322 0.973 60 P 0 8 0;0,2=2,4=0
P 4.23 1.005 3 P 0 8 0;2=6,4=1
P 3.12 2.955 3 P 0 8 0;2=6,4=1
P 2.995 2.955 3 P 0 8 0;2=6,4=1
P 2.92 2.9472 3 P 0 8 0;2=6,4=1
P 2.88 2.93 3 P 0 8 0;2=6,4=1
P 3.01 3.12 3 P 0 8 0;2=6,4=1
P 5.121 2.447 3 P 0 8 0;2=6,4=1
P 5.121 2.407 3 P 0 8 0;2=6,4=1
P 5.298 2.23 3 P 0 8 0;2=6,4=1
P 5.332 2.2 3 P 0 8 0;2=1,4=1
P 5.369 2.015 3 P 0 8 0;2=6,4=1
P 5.435 2.05 3 P 0 8 0;2=6,4=1
P 5.409 2.015 3 P 0 8 0;2=6,4=1
P 5.071 2.407 3 P 0 8 0;2=6,4=1
P 4.71838996 1.64658002 4 P 0 8 0;0,2=4,4=0
P 4.815 1.82016004 3 P 0 8 0;2=6,4=1
P 2.76986004 1.79121004 94 P 0 8 0;0,2=70,4=0
P 2.76986004 1.85026004 94 P 0 8 0;0,2=70,4=0
P 4.44 2.26 3 P 0 8 0;2=6,4=1
P 3.67 2.41243002 3 P 0 8 0;2=6,4=1
P 3.63673002 2.41243002 44 P 0 8 0;0,2=12,4=0
P 3.67 2.32 3 P 0 8 0;2=1,4=1
P 3.63673002 2.32556998 44 P 0 8 0;0,2=12,4=0
P 3.54975 2.479 3 P 0 8 0;2=6,4=1
P 3.605 2.43 3 P 0 8 0;2=6,4=1
P 3.55 2.425 3 P 0 8 0;2=6,4=1
P 3.415 2.335 3 P 0 8 0;2=6,4=1
P 3.45151998 2.32383996 57 P 0 8 0;0,2=44,4=0
P 3.505 2.295 3 P 0 8 0;2=6,4=1
P 3.40953002 2.37 3 P 0 8 0;2=6,4=1
P 3.41953002 2.40503996 29 P 0 8 0;0,2=45,4=0
P 3.116 2.524 3 P 0 8 0;2=6,4=1
P 3.12 2.344 3 P 0 8 0;2=6,4=1
P 3.159 2.344 60 P 0 8 0;0,2=2,4=0
P 3.12 2.17 3 P 0 8 0;2=1,4=1
P 3.159 2.164 60 P 0 8 0;0,2=2,4=0
P 2.92733996 1.86995 94 P 0 8 0;0,2=70,4=0
P 3.512 1.966 3 P 0 8 0;2=6,4=1
P 3.50595 1.93911004 67 P 0 8 0;0,2=50,4=0
P 4.28531998 2.15838996 4 P 0 8 0;0,2=4,4=0
P 5.385 2.057 85 P 0 8 0;0,2=18,4=0
P 5.056 2.474 60 P 0 8 0;0,2=2,4=0
P 4.56091004 1.33161004 4 P 0 8 0;0,2=4,4=0
P 4.67901998 1.37098002 4 P 0 8 0;0,2=4,4=0
P 4.52153996 1.44973002 4 P 0 8 0;0,2=4,4=0
P 4.40343002 1.56783996 4 P 0 8 0;0,2=4,4=0
P 4.40343002 1.41035 4 P 0 8 0;0,2=4,4=0
P 4.36406004 1.60721004 4 P 0 8 0;0,2=4,4=0
P 4.36406004 1.52846998 4 P 0 8 0;0,2=4,4=0
P 4.36406004 1.64658002 4 P 0 8 0;0,2=4,4=0
P 4.32468996 1.56783996 4 P 0 8 0;0,2=4,4=0
P 4.32468996 1.68595 4 P 0 8 0;0,2=4,4=0
P 4.32468996 1.64658002 4 P 0 8 0;0,2=4,4=0
P 4.28531998 1.60721004 4 P 0 8 0;0,2=4,4=0
P 4.28531998 1.37098002 4 P 0 8 0;0,2=4,4=0
P 4.28531998 1.64658002 4 P 0 8 0;0,2=4,4=0
P 4.28531998 1.68595 4 P 0 8 0;0,2=4,4=0
P 4.24595 1.56783996 4 P 0 8 0;0,2=4,4=0
P 4.24595 1.4891 4 P 0 8 0;0,2=4,4=0
P 4.24595 1.64658002 4 P 0 8 0;0,2=4,4=0
P 4.20658002 1.60721004 4 P 0 8 0;0,2=4,4=0
P 4.16721004 1.56783996 4 P 0 8 0;0,2=4,4=0
P 4.16721004 1.33161004 4 P 0 8 0;0,2=4,4=0
P 4.12783996 1.56783996 4 P 0 8 0;0,2=4,4=0
P 4.12783996 1.52846998 4 P 0 8 0;0,2=4,4=0
P 4.12783996 1.4891 4 P 0 8 0;0,2=4,4=0
P 4.08846998 1.4891 4 P 0 8 0;0,2=4,4=0
P 4.0491 1.4891 4 P 0 8 0;0,2=4,4=0
P 4.0491 1.44973002 4 P 0 8 0;0,2=4,4=0
P 4.00973002 1.44973002 4 P 0 8 0;0,2=4,4=0
P 4.00973002 1.41035 4 P 0 8 0;0,2=4,4=0
P 3.97035 1.41035 4 P 0 8 0;0,2=4,4=0
P 3.89161004 2.15838996 4 P 0 8 0;0,2=4,4=0
P 3.93098002 2.04028002 4 P 0 8 0;0,2=4,4=0
P 3.97035 1.92216998 4 P 0 8 0;0,2=4,4=0
P 4.12783996 1.84343002 4 P 0 8 0;0,2=4,4=0
P 4.00973002 1.80406004 4 P 0 8 0;0,2=4,4=0
P 4.20658002 1.76468996 4 P 0 8 0;0,2=4,4=0
P 4.12783996 1.76468996 4 P 0 8 0;0,2=4,4=0
P 4.00973002 1.76468996 4 P 0 8 0;0,2=4,4=0
P 3.89161004 1.76468996 4 P 0 8 0;0,2=4,4=0
P 3.97035 1.76468996 4 P 0 8 0;0,2=4,4=0
P 3.93098002 1.76468996 4 P 0 8 0;0,2=4,4=0
P 4.24595 1.72531998 4 P 0 8 0;0,2=4,4=0
P 4.16721004 1.72531998 4 P 0 8 0;0,2=4,4=0
P 4.08846998 1.72531998 4 P 0 8 0;0,2=4,4=0
P 4.0491 1.72531998 4 P 0 8 0;0,2=4,4=0
P 3.89161004 1.72531998 4 P 0 8 0;0,2=4,4=0
P 4.20658002 1.68595 4 P 0 8 0;0,2=4,4=0
P 4.12783996 1.68595 4 P 0 8 0;0,2=4,4=0
P 3.97035 1.68595 4 P 0 8 0;0,2=4,4=0
P 3.89161004 1.64658002 4 P 0 8 0;0,2=4,4=0
P 4.16721004 1.64658002 4 P 0 8 0;0,2=4,4=0
P 4.12783996 1.64658002 4 P 0 8 0;0,2=4,4=0
P 4.0491 1.64658002 4 P 0 8 0;0,2=4,4=0
P 4.12783996 1.60721004 4 P 0 8 0;0,2=4,4=0
P 4.00973002 1.60721004 4 P 0 8 0;0,2=4,4=0
P 3.89161004 1.56783996 4 P 0 8 0;0,2=4,4=0
P 4.0491 1.56783996 4 P 0 8 0;0,2=4,4=0
P 3.97035 1.52846998 4 P 0 8 0;0,2=4,4=0
P 3.89161004 1.4891 4 P 0 8 0;0,2=4,4=0
P 3.89161004 1.41035 4 P 0 8 0;0,2=4,4=0
P 3.93098002 1.41035 4 P 0 8 0;0,2=4,4=0
P 3.89161004 1.37098002 4 P 0 8 0;0,2=4,4=0
P 4.67901998 2.15838996 4 P 0 8 0;0,2=4,4=0
P 4.56091004 2.11901998 4 P 0 8 0;0,2=4,4=0
P 4.48216998 1.96153996 4 P 0 8 0;0,2=4,4=0
P 4.4428 2.07965 4 P 0 8 0;0,2=4,4=0
P 4.36406004 1.92216998 4 P 0 8 0;0,2=4,4=0
P 4.32468996 2.04028002 4 P 0 8 0;0,2=4,4=0
P 4.24595 1.8828 4 P 0 8 0;0,2=4,4=0
P 4.20658002 2.00091004 4 P 0 8 0;0,2=4,4=0
P 4.16721004 2.11901998 4 P 0 8 0;0,2=4,4=0
P 4.08846998 1.96153996 4 P 0 8 0;0,2=4,4=0
P 4.0491 2.07965 4 P 0 8 0;0,2=4,4=0
P 4.71838996 2.04028002 4 P 0 8 0;0,2=4,4=0
P 4.60028002 2.00091004 4 P 0 8 0;0,2=4,4=0
P 4.63965 1.8828 4 P 0 8 0;0,2=4,4=0
P 4.52153996 1.84343002 4 P 0 8 0;0,2=4,4=0
P 4.40343002 1.80406004 4 P 0 8 0;0,2=4,4=0
P 4.67901998 1.76468996 4 P 0 8 0;0,2=4,4=0
P 4.4428 1.76468996 4 P 0 8 0;0,2=4,4=0
P 4.48216998 1.72531998 4 P 0 8 0;0,2=4,4=0
P 4.40343002 1.72531998 4 P 0 8 0;0,2=4,4=0
P 4.32468996 1.72531998 4 P 0 8 0;0,2=4,4=0
P 4.4428 1.68595 4 P 0 8 0;0,2=4,4=0
P 4.36406004 1.68595 4 P 0 8 0;0,2=4,4=0
P 4.48216998 1.64658002 4 P 0 8 0;0,2=4,4=0
P 4.40343002 1.64658002 4 P 0 8 0;0,2=4,4=0
P 4.60028002 1.60721004 4 P 0 8 0;0,2=4,4=0
P 4.4428 1.60721004 4 P 0 8 0;0,2=4,4=0
P 4.48216998 1.56783996 4 P 0 8 0;0,2=4,4=0
P 4.63965 1.4891 4 P 0 8 0;0,2=4,4=0
P 4.395 3.37891998 2 P 0 8 0;2=23,4=1
P 4.44 4.165 2 P 0 8 0;2=23,4=1
P 2.86151004 3.295 2 P 0 8 0;2=23,4=1
P 4.134 2.936 69 P 0 8 0;0,2=18,4=0
P 4.134 2.855 69 P 0 8 0;0,2=18,4=0
P 4.145 2.792 60 P 0 8 0;0,2=2,4=0
P 3.21898996 3.43 3 P 0 8 0;2=6,4=1
P 3.287 4.137 60 P 0 8 0;0,2=2,4=0
P 3.255 4.202 69 P 0 8 0;0,2=18,4=0
P 3.34118996 4.06613002 37 P 0 8 0;0,2=77,4=0
P 3.31953996 4.06613002 37 P 0 8 0;0,2=77,4=0
P 3.29788002 4.06613002 37 P 0 8 0;0,2=77,4=0
P 3.29788002 3.95786998 37 P 0 8 0;0,2=77,4=0
P 3.31953996 3.95786998 37 P 0 8 0;0,2=77,4=0
P 3.34118996 3.95786998 37 P 0 8 0;0,2=77,4=0
P 3.307 3.887 60 P 0 8 0;0,2=2,4=0
P 3.285 3.827 69 P 0 8 0;0,2=18,4=0
P 3.662 2.976 55 P 0 8 0;0,2=2,4=0
P 3.797 2.969 55 P 0 8 0;0,2=2,4=0
P 3.797 2.891 55 P 0 8 0;0,2=2,4=0
P 3.732 2.952 85 P 0 8 0;0,2=18,4=0
P 3.729 2.87 85 P 0 8 0;0,2=18,4=0
P 3.594 4.197 60 P 0 8 0;0,2=2,4=0
P 3.548 2.898 2 P 0 8 0;2=23,4=1
P 3.582 2.898 55 P 0 8 0;0,2=2,4=0
P 3.621 2.91 3 P 0 8 0;2=6,4=1
P 3.658 2.861 3 P 0 8 0;2=6,4=1
P 3.658 2.911 3 P 0 8 0;2=6,4=1
P 3.623 2.861 3 P 0 8 0;2=6,4=1
P 3.615 2.961 3 P 0 8 0;2=6,4=1
P 3.253 3.917 3 P 0 8 0;2=6,4=1
P 3.253 3.962 3 P 0 8 0;2=6,4=1
P 3.248 4.107 3 P 0 8 0;2=6,4=1
P 3.213 4.167 3 P 0 8 0;2=6,4=1
P 3.248 4.152 3 P 0 8 0;2=6,4=1
P 3.213 4.236 3 P 0 8 0;2=1,4=1
P 3.253 3.872 3 P 0 8 0;2=6,4=1
P 4.465 2.895 2 P 0 8 0;2=23,4=1
P 4.093 2.863 3 P 0 8 0;2=6,4=1
P 4.091 2.813 3 P 0 8 0;2=6,4=1
P 4.092 2.917 3 P 0 8 0;2=6,4=1
P 3.78 2.735 3 P 0 8 0;2=6,4=1
P 3.816 2.725 60 P 0 8 0;0,2=2,4=0
P 3.435 2.589 3 P 0 8 0;2=6,4=1
P 3.5485 2.761 2 P 0 8 0;2=23,4=1
P 3.582 2.761 55 P 0 8 0;0,2=2,4=0
P 3.285 2.589 3 P 0 8 0;2=1,4=1
P 4.775 2.59 3 P 0 8 0;2=6,4=1
P 4.71 2.592 3 P 0 8 0;2=1,4=1
P 4.918 2.777 3 P 0 8 0;2=6,4=1
P 4.95256998 2.777 33 P 0 8 0;0,2=12,4=0
P 4.925 2.722 3 P 0 8 0;2=6,4=1
P 4.961 2.728 55 P 0 8 0;0,2=2,4=0
P 3.106 3.305 2 P 0 8 0;2=23,4=1
P 3.222 3.25 2 P 0 8 0;2=23,4=1
P 3.975 3.129 3 P 0 8 0;2=6,4=1
P 3.982 3.10043002 44 P 0 8 0;0,2=12,4=0
P 3.998 2.784 3 P 0 8 0;2=6,4=1
P 3.96243002 2.774 33 P 0 8 0;0,2=12,4=0
P 3.83 2.932 3 P 0 8 0;2=6,4=1
P 3.78 2.932 3 P 0 8 0;2=6,4=1
P 3.703 2.911 3 P 0 8 0;2=6,4=1
P 3.748 2.911 3 P 0 8 0;2=6,4=1
P 3.933 3.125 3 P 0 8 0;2=6,4=1
P 3.933 3.092 60 P 0 8 0;0,2=2,4=0
P 3.564 4.032 60 P 0 8 0;0,2=2,4=0
P 3.6 4.024 3 P 0 8 0;2=6,4=1
P 3.631 4.228 3 P 0 8 0;2=6,4=1
P 3.60311004 4.0988 3 P 0 8 0;2=6,4=1
P 3.54743002 4.121 33 P 0 8 0;0,2=12,4=0
P 3.564 4.077 60 P 0 8 0;0,2=2,4=0
P 3.631 4.183 3 P 0 8 0;2=6,4=1
P 3.38 3.15 3 P 0 8 0;2=6,4=1
P 4.43 3.965 2 P 0 8 0;2=23,4=1
P 4.43 4.015 2 P 0 8 0;2=23,4=1
P 4.396 3.915 60 P 0 8 0;0,2=2,4=0
P 4.396 3.965 60 P 0 8 0;0,2=2,4=0
P 4.396 4.015 60 P 0 8 0;0,2=2,4=0
P 4.714 3.633 3 P 0 8 0;2=6,4=1
P 4.78656004 3.67205 99 P 0 8 0;0,2=17,4=0
P 4.71 3.47 3 P 0 8 0;2=6,4=1
P 3.159 2.569 60 P 0 8 0;0,2=2,4=0
P 4.94093996 4.12008002 16 P 0 8 0;2=79,4=0
P 4.94093996 3.09646004 16 P 0 8 0;2=79,4=0
P 3.8865 2.9265 3 P 0 8 0;2=72,4=1
P 2.55906004 4.12008002 16 P 0 8 0;2=79,4=0
P 2.55906004 3.09646004 16 P 0 8 0;2=79,4=0
P 5.815 2.67 3 P 0 8 0;2=6,4=1
P 5.517 2.563 3 P 0 8 0;2=6,4=1
P 5.50543996 2.621 28 P 0 8 0;0,2=32,4=0
P 5.49 2.675 3 P 0 8 0;2=6,4=1
P 5.328 2.611 55 P 0 8 0;0,2=2,4=0
P 5.3035 2.5748 3 P 0 8 0;2=6,4=1
P 5.122 2.587 3 P 0 8 0;2=6,4=1
P 5.123 2.544 3 P 0 8 0;2=6,4=1
P 5.121 2.495 3 P 0 8 0;2=6,4=1
P 5.121 2.625 3 P 0 8 0;2=6,4=1
P 5.41346004 3.03506998 3 P 0 8 0;2=6,4=1
P 5.50543996 3.021 28 P 0 8 0;0,2=32,4=0
P 5.814 2.9225 3 P 0 8 0;2=6,4=1
P 5.25176004 4.11925 3 P 0 8 0;2=6,4=1
P 5.283 4.15048996 19 P 0 8 0;0,2=31,4=0
P 5.88778996 3.34448996 11 P 0 8 0;2=66,4=0
P 5.88778996 3.50983996 11 P 0 8 0;2=66,4=0
P 5.88778996 3.67518996 11 P 0 8 0;2=66,4=0
P 5.162 2.592 60 P 0 8 0;0,2=2,4=0
P 5.084 2.597 60 P 0 8 0;0,2=2,4=0
P 5.08 2.534 69 P 0 8 0;0,2=18,4=0
P 5.331 2.238 55 P 0 8 0;0,2=2,4=0
P 5.52086998 2.14318996 77 P 0 8 0;0,2=77,4=0
P 5.52086998 2.12153996 77 P 0 8 0;0,2=77,4=0
P 5.52086998 2.09988002 77 P 0 8 0;0,2=77,4=0
P 5.45 2.089 55 P 0 8 0;0,2=2,4=0
P 5.7 2.109 55 P 0 8 0;0,2=2,4=0
P 5.62913002 2.09988002 77 P 0 8 0;0,2=77,4=0
P 5.62913002 2.12153996 77 P 0 8 0;0,2=77,4=0
P 5.62913002 2.14318996 77 P 0 8 0;0,2=77,4=0
P 6.51581998 2.07086998 98 P 0 8 0;0,2=80,4=0
P 6.51581998 2.14961004 98 P 0 8 0;0,2=80,4=0
P 6.289 1.97073996 55 P 0 8 0;0,2=2,4=0
P 6.225 1.97073996 85 P 0 8 0;0,2=18,4=0
P 5.51 2.35043002 44 P 0 8 0;0,2=12,4=0
P 5.555 2.366 55 P 0 8 0;0,2=2,4=0
P 5.538 2.402 3 P 0 8 0;2=6,4=1
P 5.666 2.129 2 P 0 8 0;2=23,4=1
P 5.647 2.044 3 P 0 8 0;2=6,4=1
P 5.687 2.043 3 P 0 8 0;2=6,4=1
P 5.732 2.043 3 P 0 8 0;2=6,4=1
P 5.865 2.3 3 P 0 8 0;2=6,4=1
P 5.89953002 2.28401998 60 P 0 8 0;0,2=2,4=0
P 6.36 2.16141998 3 P 0 8 0;2=6,4=1
P 5.162 2.521 69 P 0 8 0;0,2=18,4=0
P 6.51581998 2.23623002 96 P 0 8 0;2=81,4=0
P 6.51581998 1.98425 97 P 0 8 0;2=82,4=0
P 6.40951998 2.20866998 7 P 0 8 0;2=83,4=0
P 6.40951998 2.01181004 7 P 0 8 0;2=83,4=0
P 3.546 2.513 55 P 0 8 0;0,2=2,4=0
P 4.74 2.5415 23 P 0 8 0;0,2=52,4=0
P 3.285 2.553 55 P 0 8 0;0,2=2,4=0
P 3.38483996 2.553 55 P 0 8 0;0,2=2,4=0
P 3.435 2.553 55 P 0 8 0;0,2=2,4=0
P 0.06038996 1.38346004 9 P 0 8 0;2=84,4=0
P 0.26038996 1.38346004 9 P 0 8 0;2=84,4=0
P 0.06038996 1.18346004 9 P 0 8 0;2=84,4=0
P 0.26038996 1.18346004 9 P 0 8 0;2=84,4=0
P 0.06038996 0.8126 9 P 0 8 0;2=84,4=0
P 0.26038996 0.8126 9 P 0 8 0;2=84,4=0
P 0.06038996 0.6126 9 P 0 8 0;2=84,4=0
P 0.26038996 0.6126 9 P 0 8 0;2=84,4=0
P 0.06038996 2.5252 9 P 0 8 0;2=84,4=0
P 0.26038996 2.5252 9 P 0 8 0;2=84,4=0
P 0.06038996 2.3252 9 P 0 8 0;2=84,4=0
P 0.26038996 2.3252 9 P 0 8 0;2=84,4=0
P 0.06038996 1.95433002 9 P 0 8 0;2=84,4=0
P 0.26038996 1.95433002 9 P 0 8 0;2=84,4=0
P 0.06038996 1.75433002 9 P 0 8 0;2=84,4=0
P 0.26038996 1.75433002 9 P 0 8 0;2=84,4=0
P 1.26066998 1.84043002 10 P 0 8 0;2=69,4=0
P 3.2815 3.40456998 90 P 0 8 0;0,2=8,4=0
P 3.159 2.524 60 P 0 8 0;0,2=2,4=0
P 3.159 2.479 60 P 0 8 0;0,2=2,4=0
P 4.926 1.72 60 P 0 8 0;0,2=2,4=0
P 4.926 1.675 60 P 0 8 0;0,2=2,4=0
P 4.566 2.895 60 P 0 8 0;0,2=2,4=0
P 4.566 2.945 60 P 0 8 0;0,2=2,4=0
P 0.50356998 1 33 P 0 8 0;0,2=12,4=0
P 1.03441998 3.578 40 P 0 8 0;0,2=15,4=0
P 5.46443002 3.967 60 P 0 8 0;0,2=2,4=0
P 5.762 3.517 60 P 0 8 0;0,2=2,4=0
P 5.762 3.567 60 P 0 8 0;0,2=2,4=0
P 4.2391 3.992 82 P 0 8 0;0,2=0,4=0
P 5.96046998 2.04418002 36 P 0 8 0;0,2=19,4=0
P 5.91901998 2.003 2 P 0 8 0;2=21,4=1
P 5.91901998 1.95065 55 P 0 8 0;0,2=2,4=0
P 6.01953002 2.04418002 36 P 0 8 0;0,2=19,4=0
P 6.06901998 2.004 2 P 0 8 0;2=21,4=1
P 6.06901998 1.95065 55 P 0 8 0;0,2=2,4=0
P 3.119 1.895 60 P 0 8 0;0,2=2,4=0
P 2.92733996 1.929 94 P 0 8 0;0,2=70,4=0
P 3.119 1.85 60 P 0 8 0;0,2=2,4=0
P 2.92733996 1.90931998 94 P 0 8 0;0,2=70,4=0
P 3.49 0.825 2 P 0 8 0;2=21,4=1
P 2.65966998 0.93443002 10 P 0 8 0;2=69,4=0
P 6.095 2.545 3 P 0 8 0;2=1,4=1
P 4.926 1.975 60 P 0 8 0;0,2=2,4=0
P 5.07 1.885 3 P 0 8 0;2=6,4=1
P 5.33 0.995 2 P 0 8 0;2=23,4=1
P 3.54 0.825 3 P 0 8 0;2=6,4=1
P 6.04 2.545 3 P 0 8 0;2=1,4=1
P 4.926 2.025 60 P 0 8 0;0,2=2,4=0
P 5.07 1.925 3 P 0 8 0;2=6,4=1
P 5.33 0.95 2 P 0 8 0;2=23,4=1
P 2.53966998 0.93443002 10 P 0 8 0;2=69,4=0
P 3.123 1.8 60 P 0 8 0;0,2=2,4=0
P 2.76986004 1.77151998 94 P 0 8 0;0,2=70,4=0
P 3.123 1.75 60 P 0 8 0;0,2=2,4=0
P 2.76986004 1.75183996 94 P 0 8 0;0,2=70,4=0
P 2.802 1.987 2 P 0 8 0;2=23,4=1
P 3.168 2.11 60 P 0 8 0;0,2=2,4=0
P 2.76986004 1.929 94 P 0 8 0;0,2=70,4=0
P 2.834 1.987 2 P 0 8 0;2=23,4=1
P 3.168 2.06 60 P 0 8 0;0,2=2,4=0
P 2.76986004 1.90931998 94 P 0 8 0;0,2=70,4=0
P 2.845 1.875 2 P 0 8 0;2=23,4=1
P 2.76986004 1.88963002 94 P 0 8 0;0,2=70,4=0
P 3.168 2.015 60 P 0 8 0;0,2=2,4=0
P 2.845 1.843 2 P 0 8 0;2=23,4=1
P 2.76986004 1.86995 94 P 0 8 0;0,2=70,4=0
P 3.168 1.965 60 P 0 8 0;0,2=2,4=0
P 2.77866998 0.93443002 10 P 0 8 0;2=69,4=0
P 4.926 1.63 60 P 0 8 0;0,2=2,4=0
P 4.9806 1.855 3 P 0 8 0;2=1,4=1
P 1.26066998 1.04043002 10 P 0 8 0;2=69,4=0
P 0.724 2.646 3 P 0 8 0;2=1,4=1
P 0.68448002 2.664 60 P 0 8 0;0,2=2,4=0
P 0.75896998 2.661 42 P 0 8 0;0,2=43,4=0
P 0.758 2.743 2 P 0 8 0;2=7,4=1
P 0.714 2.79 60 P 0 8 0;0,2=2,4=0
P 0.77963996 2.69151004 32 P 0 8 0;0,2=47,4=0
P 3.275 2.32 2 P 0 8 0;2=7,4=1
P 3.201 2.389 60 P 0 8 0;0,2=2,4=0
P 3.201 2.299 60 P 0 8 0;0,2=2,4=0
P 3.201 2.344 60 P 0 8 0;0,2=2,4=0
P 3.32848002 2.30416004 57 P 0 8 0;0,2=44,4=0
P 3.24 2.275 3 P 0 8 0;2=1,4=1
P 3.201 2.254 60 P 0 8 0;0,2=2,4=0
P 3.32848002 2.2451 57 P 0 8 0;0,2=44,4=0
P 3.326 2.466 2 P 0 8 0;2=7,4=1
P 3.335 2.511 55 P 0 8 0;0,2=2,4=0
P 3.38016004 2.40503996 29 P 0 8 0;0,2=45,4=0
P 2.1481 0.7881 2 P 0 8 0;2=21,4=1
P 5.08 1.105 3 P 0 8 0;2=6,4=1
P 5.225 1.145 3 P 0 8 0;2=6,4=1
P 5.132 0.66 3 P 0 8 0;2=6,4=1
P 2.0816 0.7399 3 P 0 8 0;2=6,4=1
P 2.03 0.75 2 P 0 8 0;2=21,4=1
P 5.08 1.155 3 P 0 8 0;2=6,4=1
P 5.08 1.055 3 P 0 8 0;2=6,4=1
P 2.0788 0.7874 2 P 0 8 0;2=21,4=1
P 2.633 0.522 2 P 0 8 0;2=23,4=1
P 2.637 0.655 60 P 0 8 0;0,2=2,4=0
P 2.754 0.605 68 P 0 8 0;0,2=53,4=0
P 2.637 0.605 60 P 0 8 0;0,2=2,4=0
P 3.455 0.87 3 P 0 8 0;2=6,4=1
P 0.9225 0.9775 3 P 0 8 0;2=6,4=1
P 4.82 0.835 3 P 0 8 0;2=1,4=1
P 4.8855 0.8428 90 P 0 8 0;0,2=8,4=0
P 0.8825 1.7725 3 P 0 8 0;2=6,4=1
P 3.405 0.87 3 P 0 8 0;2=6,4=1
P 0.965 0.98 3 P 0 8 0;2=6,4=1
P 0.91 1.815 3 P 0 8 0;2=1,4=1
P 4.78 0.78 3 P 0 8 0;2=6,4=1
P 4.8855 0.76601998 90 P 0 8 0;0,2=8,4=0
P 4.40343002 1.84343002 4 P 0 8 0;0,2=4,4=0
P 3.58206998 1.89186998 67 P 0 8 0;0,2=50,4=0
P 3.65101004 1.88358996 2 P 0 8 0;2=33,4=1
P 4.4428 1.84343002 4 P 0 8 0;0,2=4,4=0
P 3.58206998 1.90761998 67 P 0 8 0;0,2=50,4=0
P 3.65101004 1.91558996 2 P 0 8 0;2=33,4=1
P 3.124 1.695 60 P 0 8 0;0,2=2,4=0
P 2.98283996 1.75183996 3 P 0 8 0;2=6,4=1
P 2.92733996 1.75183996 94 P 0 8 0;0,2=70,4=0
P 2.225 3.245 3 P 0 8 0;2=6,4=1
P 2.2628 3.245 55 P 0 8 0;0,2=2,4=0
P 3.2815 3.3022 90 P 0 8 0;0,2=8,4=0
P 4.595 2.62 3 P 0 8 0;2=6,4=1
P 4.025 3.08 3 P 0 8 0;2=6,4=1
P 0.62 3.07 3 P 0 8 0;2=6,4=1
P 5.865 1.125 3 P 0 8 0;2=1,4=1
P 5.914 1.125 60 P 0 8 0;0,2=2,4=0
P 5.914 1.08 60 P 0 8 0;0,2=2,4=0
P 6.0845 1.0578 89 P 0 8 0;0,2=37,4=0
P 5.865 1.07 3 P 0 8 0;2=1,4=1
P 2.1478 3.2655 48 P 0 8 0;0,2=37,4=0
P 2.265 3.34 3 P 0 8 0;2=6,4=1
P 3.2815 3.3278 90 P 0 8 0;0,2=8,4=0
P 4.57 2.585 3 P 0 8 0;2=6,4=1
P 4.02 3.03 3 P 0 8 0;2=6,4=1
P 0.645 2.9675 3 P 0 8 0;2=6,4=1
P 5.956 1.025 60 P 0 8 0;0,2=2,4=0
P 5.48828996 4.16328996 3 P 0 8 0;2=1,4=1
P 5.43503996 4.21653996 19 P 0 8 0;0,2=31,4=0
P 4.00973002 1.8828 4 P 0 8 0;0,2=4,4=0
P 5.55315 4.175 3 P 0 8 0;2=1,4=1
P 5.55315 4.21653996 19 P 0 8 0;0,2=31,4=0
P 4.00973002 1.84343002 4 P 0 8 0;0,2=4,4=0
P 5.67126004 4.175 3 P 0 8 0;2=1,4=1
P 5.67126004 4.21653996 19 P 0 8 0;0,2=31,4=0
P 3.97035 1.80406004 4 P 0 8 0;0,2=4,4=0
P 5.78936998 4.175 3 P 0 8 0;2=1,4=1
P 5.78936998 4.21653996 19 P 0 8 0;0,2=31,4=0
P 3.93098002 1.80406004 4 P 0 8 0;0,2=4,4=0
P 4.12783996 2.11901998 4 P 0 8 0;0,2=4,4=0
P 4.63965 1.64658002 4 P 0 8 0;0,2=4,4=0
P 4.12783996 2.15838996 4 P 0 8 0;0,2=4,4=0
P 4.0491 2.11901998 4 P 0 8 0;0,2=4,4=0
P 4.63965 1.56783996 4 P 0 8 0;0,2=4,4=0
P 4.00973002 2.11901998 4 P 0 8 0;0,2=4,4=0
P 4.67901998 1.60721004 4 P 0 8 0;0,2=4,4=0
P 4.0491 2.15838996 4 P 0 8 0;0,2=4,4=0
P 4.00973002 2.15838996 4 P 0 8 0;0,2=4,4=0
P 3.93098002 2.11901998 4 P 0 8 0;0,2=4,4=0
P 4.56091004 1.60721004 4 P 0 8 0;0,2=4,4=0
P 3.89161004 2.11901998 4 P 0 8 0;0,2=4,4=0
P 4.71838996 1.56783996 4 P 0 8 0;0,2=4,4=0
P 3.97035 2.15838996 4 P 0 8 0;0,2=4,4=0
P 4.71838996 1.52846998 4 P 0 8 0;0,2=4,4=0
P 3.93098002 2.15838996 4 P 0 8 0;0,2=4,4=0
P 0.8338 2.4275 48 P 0 8 0;0,2=37,4=0
P 0.846 2.489 2 P 0 8 0;2=7,4=1
P 3.28 3.065 3 P 0 8 0;2=6,4=1
P 3.0425 3.40456998 90 P 0 8 0;0,2=8,4=0
P 0.8082 2.4275 48 P 0 8 0;0,2=37,4=0
P 0.796 2.489 2 P 0 8 0;2=7,4=1
P 3.325 3.065 3 P 0 8 0;2=6,4=1
P 3.0425 3.37898002 90 P 0 8 0;0,2=8,4=0
P 4.985 3.546 55 P 0 8 0;0,2=2,4=0
P 5.03 3.546 2 P 0 8 0;2=7,4=1
P 4.91548996 3.82953002 99 P 0 8 0;0,2=17,4=0
P 4.935 3.546 55 P 0 8 0;0,2=2,4=0
P 4.885 3.546 55 P 0 8 0;0,2=2,4=0
P 4.935 3.59 2 P 0 8 0;2=7,4=1
P 4.91548996 3.75078996 99 P 0 8 0;0,2=17,4=0
P 4.785 3.546 55 P 0 8 0;0,2=2,4=0
P 4.735 3.546 55 P 0 8 0;0,2=2,4=0
P 4.78656004 3.82953002 99 P 0 8 0;0,2=17,4=0
P 4.885 3.59 2 P 0 8 0;2=21,4=1
P 4.91548996 3.67205 99 P 0 8 0;0,2=17,4=0
P 4.835 3.546 55 P 0 8 0;0,2=2,4=0
P 4.70461998 3.69461998 2 P 0 8 0;2=7,4=1
P 4.78656004 3.75078996 99 P 0 8 0;0,2=17,4=0
P 5.395 2.92 3 P 0 8 0;2=1,4=1
P 4.48216998 1.80406004 4 P 0 8 0;0,2=4,4=0
P 5.015 1.925 3 P 0 8 0;2=6,4=1
P 5.39976998 2.75123996 2 P 0 8 0;2=21,4=1
P 5.375 2.96606998 2 P 0 8 0;2=21,4=1
P 4.4428 1.80406004 4 P 0 8 0;0,2=4,4=0
P 5.4525 2.563 2 P 0 8 0;2=21,4=1
P 4.56091004 1.76468996 4 P 0 8 0;0,2=4,4=0
P 3.545 0.6092 3 P 0 8 0;2=6,4=1
P 5.1245 0.74043002 90 P 0 8 0;0,2=8,4=0
P 1.395 0.625 2 P 0 8 0;2=21,4=1
P 5.085 0.645 3 P 0 8 0;2=6,4=1
P 1.3505 0.613 60 P 0 8 0;0,2=2,4=0
P 3.495 0.61 3 P 0 8 0;2=6,4=1
P 5.1245 0.8172 90 P 0 8 0;0,2=8,4=0
P 5.04 0.645 3 P 0 8 0;2=6,4=1
P 1.485 0.625 2 P 0 8 0;2=21,4=1
P 1.3507 0.708 60 P 0 8 0;0,2=2,4=0
P 4.00973002 1.64658002 4 P 0 8 0;0,2=4,4=0
P 2.95835 0.385 2 P 0 8 0;2=33,4=1
P 2.8996 0.13781004 59 P 0 8 0;0,2=68,4=0
P 3.97035 1.64658002 4 P 0 8 0;0,2=4,4=0
P 2.95835 0.353 2 P 0 8 0;2=33,4=1
P 2.93896998 0.13781004 59 P 0 8 0;0,2=68,4=0
P 3.93098002 1.68595 4 P 0 8 0;0,2=4,4=0
P 2.80086998 0.385 2 P 0 8 0;2=33,4=1
P 2.74211998 0.13781004 59 P 0 8 0;0,2=68,4=0
P 3.89161004 1.68595 4 P 0 8 0;0,2=4,4=0
P 2.80086998 0.353 2 P 0 8 0;2=33,4=1
P 2.78148996 0.13781004 59 P 0 8 0;0,2=68,4=0
P 4.00973002 1.72531998 4 P 0 8 0;0,2=4,4=0
P 2.64338996 0.385 2 P 0 8 0;2=33,4=1
P 2.58463996 0.13781004 59 P 0 8 0;0,2=68,4=0
P 3.97035 1.72531998 4 P 0 8 0;0,2=4,4=0
P 2.64338996 0.353 2 P 0 8 0;2=33,4=1
P 2.62401004 0.13781004 59 P 0 8 0;0,2=68,4=0
P 3.93098002 1.60721004 4 P 0 8 0;0,2=4,4=0
P 2.95835 0.481 2 P 0 8 0;2=33,4=1
P 2.38778996 0.13781004 59 P 0 8 0;0,2=68,4=0
P 2.95835 0.449 2 P 0 8 0;2=33,4=1
P 3.89161004 1.60721004 4 P 0 8 0;0,2=4,4=0
P 2.42716004 0.13781004 59 P 0 8 0;0,2=68,4=0
P 3.125 0.875 2 P 0 8 0;2=33,4=1
P 4.00973002 1.56783996 4 P 0 8 0;0,2=4,4=0
P 3.14763002 0.85236998 2 P 0 8 0;2=33,4=1
P 3.97035 1.56783996 4 P 0 8 0;0,2=4,4=0
P 2.81855 0.763 2 P 0 8 0;2=33,4=1
P 3.93098002 1.52846998 4 P 0 8 0;0,2=4,4=0
P 2.85055 0.763 2 P 0 8 0;2=33,4=1
P 3.89161004 1.52846998 4 P 0 8 0;0,2=4,4=0
P 2.66706998 0.763 2 P 0 8 0;2=33,4=1
P 4.00973002 1.4891 4 P 0 8 0;0,2=4,4=0
P 2.69906998 0.763 2 P 0 8 0;2=33,4=1
P 3.97035 1.4891 4 P 0 8 0;0,2=4,4=0
P 2.47021998 0.763 2 P 0 8 0;2=33,4=1
P 3.93098002 1.44973002 4 P 0 8 0;0,2=4,4=0
P 2.50221998 0.763 2 P 0 8 0;2=33,4=1
P 3.89161004 1.44973002 4 P 0 8 0;0,2=4,4=0
P 1.889 0.5496 3 P 0 8 0;2=6,4=1
P 2.51121998 0.626 55 P 0 8 0;0,2=2,4=0
P 2.435 0.4865 2 P 0 8 0;2=7,4=1
P 3.56 3.023 3 P 0 8 0;2=1,4=1
P 3.0425 3.35338996 90 P 0 8 0;0,2=8,4=0
P 3.57 2.955 3 P 0 8 0;2=1,4=1
P 3.0425 3.3278 90 P 0 8 0;0,2=8,4=0
P 2.848 0.57941004 68 P 0 8 0;0,2=53,4=0
P 2.954 0.57441004 60 P 0 8 0;0,2=2,4=0
P 4.975 2.14 3 P 0 8 0;2=6,4=1
P 4.926 2.07 60 P 0 8 0;0,2=2,4=0
P 5.03005 0.99493996 3 P 0 8 0;2=1,4=1
P 6.4105 2.13583002 84 P 0 8 0;0,2=51,4=0
P 2.19093996 0.13781004 59 P 0 8 0;0,2=68,4=0
P 3.01771004 0.13781004 59 P 0 8 0;0,2=68,4=0
P 2.30905 0.13781004 59 P 0 8 0;0,2=68,4=0
P 2.1122 0.13781004 59 P 0 8 0;0,2=68,4=0
P 0.7574 3.3935 51 P 0 8 0;0,2=5,4=0
P 0.6826 3.3935 51 P 0 8 0;0,2=5,4=0
P 6.23248996 2.31483996 51 P 0 8 0;0,2=5,4=0
P 6.30728996 2.31483996 51 P 0 8 0;0,2=5,4=0
P 3.55188996 1.94555 26 P 0 8 0;0,2=62,4=0
P 3.53613996 1.94555 26 P 0 8 0;0,2=62,4=0
P 2.754 0.63058996 68 P 0 8 0;0,2=53,4=0
P 3.98 0.75216998 87 P 0 8 0;0,2=11,4=0
P 4.364 0.82366004 56 P 0 8 0;0,2=10,4=0
P 5.68466998 0.679 73 P 0 8 0;0,2=19,4=0
P 5.04833002 2.707 73 P 0 8 0;0,2=19,4=0
P 3.912 3.00466998 36 P 0 8 0;0,2=19,4=0
P 2.92733996 1.77151998 94 P 0 8 0;0,2=70,4=0
P 2.92733996 1.79121004 94 P 0 8 0;0,2=70,4=0
P 2.92733996 1.81088996 94 P 0 8 0;0,2=70,4=0
P 2.76986004 1.81088996 94 P 0 8 0;0,2=70,4=0
P 2.92733996 1.83058002 94 P 0 8 0;0,2=70,4=0
P 2.76986004 1.83058002 94 P 0 8 0;0,2=70,4=0
P 2.92733996 1.85026004 94 P 0 8 0;0,2=70,4=0
P 3.45151998 2.30416004 57 P 0 8 0;0,2=44,4=0
P 3.45151998 2.28446998 57 P 0 8 0;0,2=44,4=0
P 3.45151998 2.26478996 57 P 0 8 0;0,2=44,4=0
P 3.45151998 2.2451 57 P 0 8 0;0,2=44,4=0
P 3.32848002 2.26478996 57 P 0 8 0;0,2=44,4=0
P 3.32848002 2.28446998 57 P 0 8 0;0,2=44,4=0
P 3.32848002 2.36321004 57 P 0 8 0;0,2=44,4=0
P 3.32848002 2.3829 57 P 0 8 0;0,2=44,4=0
P 3.45151998 2.40258002 57 P 0 8 0;0,2=44,4=0
P 4.20306004 3.8954 38 P 0 8 0;0,2=42,4=0
P 4.18336998 3.8969 39 P 0 8 0;0,2=41,4=0
P 4.16368996 3.8969 39 P 0 8 0;0,2=41,4=0
P 4.20058996 3.4824 47 P 0 8 0;0,2=9,4=0
P 4.00558996 3.4804 47 P 0 8 0;0,2=9,4=0
P 1.73966998 3.015 73 P 0 8 0;0,2=19,4=0
P 1.03441998 3.12 40 P 0 8 0;0,2=15,4=0
P 1.352 3.4179 92 P 0 8 0;0,2=15,4=0
P 1.352 3.39821004 92 P 0 8 0;0,2=15,4=0
P 1.352 3.37853002 92 P 0 8 0;0,2=15,4=0
P 1.352 3.35883996 92 P 0 8 0;0,2=15,4=0
P 1.352 3.31946998 92 P 0 8 0;0,2=15,4=0
P 1.352 3.29978996 92 P 0 8 0;0,2=15,4=0
P 1.352 3.2801 92 P 0 8 0;0,2=15,4=0
P 1.23126998 3.12 40 P 0 8 0;0,2=15,4=0
P 1.21158002 3.12 40 P 0 8 0;0,2=15,4=0
P 1.1919 3.12 40 P 0 8 0;0,2=15,4=0
P 1.17221004 3.12 40 P 0 8 0;0,2=15,4=0
P 1.13283996 3.12 40 P 0 8 0;0,2=15,4=0
P 1.11316004 3.12 40 P 0 8 0;0,2=15,4=0
P 5.638 3.907 3 P 0 8 0;2=1,4=1
P 1.8317 0.5639 2 P 0 8 0;2=21,4=1
A 6.58071004 2.84646004 6.60038996 2.86613996 6.58071004 2.86613996 6 P 0 N
L 6.60038996 2.86613996 6.60038996 4.33661004 6 P 0 
A 6.60038996 4.33661004 6.56101998 4.37598002 6.56101998 4.33661004 6 P 0 N
L 6.56101998 4.37598002 0.03936998 4.37598002 6 P 0 
A 0.03936998 4.37598002 0 4.33661004 0.03936998 4.33661004 6 P 0 N
L 0 4.33661004 0 0.21653996 6 P 0 
A 0 0.21653996 0.03936998 0.17716998 0.03936998 0.21653996 6 P 0 N
L 0.03936998 0.17716998 0.55118002 0.17716998 6 P 0 
A 0.55118002 0.17716998 0.59055 0.21653996 0.55118002 0.21653996 6 P 0 N
L 0.59055 0.21653996 0.59055 0.4626 6 P 0 
A 0.59055 0.4626 0.62991998 0.50196998 0.62991998 0.4626 6 P 0 Y
L 0.62991998 0.50196998 1.27361998 0.50196998 6 P 0 
A 1.27361998 0.50196998 1.31298996 0.4626 1.27361998 0.4626 6 P 0 Y
L 1.31298996 0.4626 1.31298996 0.21653996 6 P 0 
A 1.31298996 0.21653996 1.35236004 0.17716998 1.35235994 0.21653996 6 P 0 N
L 1.35236004 0.17716998 1.58858002 0.17716998 6 P 0 
A 1.58858002 0.17716998 1.62795 0.21653996 1.58858002 0.21653996 6 P 0 N
L 1.62795 0.21653996 1.62795 0.43011998 6 P 0 
A 1.62795 0.43011998 1.77165 0.43011998 1.6998 0.43011998 6 P 0 Y
L 1.77165 0.43011998 1.77165 0.01968996 6 P 0 
L 1.77165 0.01968996 1.79133996 0 6 P 8191 
L 1.79133996 0 2.19291004 0 6 P 0 
L 2.19291004 0 2.2126 0.01968996 6 P 8191 
L 2.2126 0.01968996 2.2126 0.29331004 6 P 0 
A 2.2126 0.29331004 2.2874 0.29331004 2.25 0.29331004 6 P 0 Y
L 2.2874 0.29331004 2.2874 0.01968996 6 P 0 
L 2.2874 0.01968996 2.30708996 0 6 P 8191 
L 2.30708996 0 3.10236004 0 6 P 0 
L 3.10236004 0 3.12205 0.01968996 6 P 8191 
L 3.12205 0.01968996 3.12205 0.4626 6 P 0 
A 3.12205 0.4626 3.16141998 0.50196998 3.16141998 0.4626 6 P 0 Y
L 3.16141998 0.50196998 6.56101998 0.50196998 6 P 0 
A 6.56101998 0.50196998 6.60038996 0.54133996 6.56101998 0.54133996 6 P 0 N
L 6.60038996 0.54133996 6.60038996 2.375 6 P 0 
A 6.60038996 2.375 6.58071004 2.39468996 6.58070502 2.37500502 6 P 0 N
L 6.58071004 2.39468996 6.57211004 2.39468996 6 P 8191 
A 6.57211004 2.39468996 6.55243002 2.41436998 6.57211004 2.41436998 6 P 0 Y
L 6.55243002 2.41436998 6.55243002 2.82676998 6 P 0 
A 6.55243002 2.82676998 6.57211004 2.84646004 6.57211496 2.826775 6 P 0 Y
L 6.57211004 2.84646004 6.58071004 2.84646004 6 P 8191 
S P 0
OB 1.82478996063 2.875 I
OS 1.82978996063 2.87
OS 2.01 2.87
OS 3.045 2.87
OS 3.09 2.825
OS 3.09 2.13
OS 3.065 2.105
OS 2.715 2.105
OS 2.68 2.07
OS 2.68 1.63
OS 2.68 1.61
OS 2.705 1.585
OS 3.05 1.585
OS 3.085 1.55
OS 3.085 0.835
OS 3.05 0.8
OS 2.32 0.8
OS 2.25 0.87
OS 1.81 0.87
OS 1.74 0.8
OS 1.06 0.8
OS 1.02 0.84
OS 1.02 2.835
OS 1.06 2.875
OS 1.82478996063 2.875
OE
SE
S P 0
OB 0.560430019685 0.528069980315 I
OS 0.560430019685 0.2166
OS 0.55126003937 0.207430019685
OS 0.071380019685 0.207430019685
OS 0.038269980315 0.207430019685
OS 0.030330019685 0.215369980315
OS 0.030330019685 0.528069980315
OS 0.030330019685 0.5353
OS 0.34908996063 0.5353
OS 0.560430019685 0.5353
OS 0.560430019685 0.528069980315
OE
SE
S P 0
OB 6.205 0.54133996063 I
OS 6.20551003937 0.54133996063
OS 6.20551003937 0.901569980315
OS 6.569880019685 0.901569980315
OS 6.569880019685 0.54058996063
OS 6.561769980315 0.532480019685
OS 6.205 0.532480019685
OS 6.205 0.54133996063
OE
SE
S P 0
OB 6.20551003937 3.9252 I
OS 6.20551003937 4.33661003937
OS 6.20551003937 4.3456
OS 6.562719980315 4.3456
OS 6.57018996063 4.338130019685
OS 6.57018996063 3.9252
OS 6.20551003937 3.9252
OE
SE
S P 0
OB 0.5 4.33661003937 I
OS 0.5 3.5315
OS 0.039369980315 3.5315
OS 0.030119980315 3.5315
OS 0.030119980315 3.9179
OS 0.030119980315 4.337469980315
OS 0.03853996063 4.34588996063
OS 0.5 4.34588996063
OS 0.5 4.33661003937
OE
SE
P 5.78 1.165 13 P 0 8 0;0,2=85,4=0
P 0.95 0.845 13 P 0 8 0;0,2=85,4=0
P 1.105 4.145 13 P 0 8 0;0,2=85,4=0
P 2.68566998 1.12143002 12 P 0 8 0;2=86,4=0
P 2.68566998 2.55943002 12 P 0 8 0;2=86,4=0
P 1.46066998 2.68043002 12 P 0 8 0;2=86,4=0
P 1.43566998 1.06043002 12 P 0 8 0;2=86,4=0
P 6.40038996 0.65353996 15 P 0 8 0;2=87,4=0
P 0.29528002 3.73031004 15 P 0 8 0;2=87,4=0
P 0.29528002 0.36811004 15 P 0 8 0;2=87,4=0
P 6.40038996 4.17835 15 P 0 8 0;2=87,4=0
P 6.34055 3.34448996 14 P 0 8 0;2=88,4=0
P 6.34055 3.67518996 14 P 0 8 0;2=88,4=0
L 3.16 -0.655 3.16 -1.58 1 P 0 
L 1.36 -0.655 1.36 -1.58 1 P 0 
L 1.36 -1.58 5.06 -1.58 1 P 0 
L 5.06 -1.58 5.06 -0.655 1 P 0 
L 5.06 -0.655 1.36 -0.655 1 P 0 
A 1.559 -1.33655 1.559 -1.33655 1.55268002 -1.33655 6 P 0 N
A 1.54775 -1.205 1.54775 -1.205 1.53883002 -1.205 6 P 0 N
A 1.54763996 -0.99775 1.54763996 -0.99775 1.53871998 -0.99775 6 P 0 N
A 1.54063996 -1.10118002 1.54063996 -1.10118002 1.52603996 -1.10118002 6 P 0 N
A 1.49695 -1.10118002 1.49695 -1.10118002 1.48656998 -1.10118002 6 P 0 N
A 1.45963996 -1.10118002 1.45963996 -1.10118002 1.4533 -1.10118002 6 P 0 N
A 1.52135 -0.98681004 1.52135 -0.98681004 1.51503002 -0.98681004 6 P 0 N
A 1.79433002 -1.43586998 1.79433002 -1.43586998 1.78798996 -1.43586998 6 P 0 N
A 1.79841004 -1.40261004 1.79841004 -1.40261004 1.78798996 -1.40261004 6 P 0 N
A 1.80255 -1.36311004 1.80255 -1.36311004 1.78798996 -1.36311004 6 P 0 N
A 1.80668996 -1.31528002 1.80668996 -1.31528002 1.78798996 -1.31528002 6 P 0 N
A 1.68013002 -1.37456004 1.68013002 -1.37456004 1.67378996 -1.37456004 6 P 0 N
A 1.69321998 -1.35033002 1.69321998 -1.35033002 1.6843 -1.35033002 6 P 0 N
A 1.7108 -1.31738996 1.7108 -1.31738996 1.69798002 -1.31738996 6 P 0 N
A 1.89666998 -1.31511004 1.89666998 -1.31511004 1.88383996 -1.31511004 6 P 0 N
A 1.88198996 -1.16876004 1.88198996 -1.16876004 1.85558996 -1.16876004 6 P 0 N
A 1.87928002 -1.27801998 1.87928002 -1.27801998 1.86343996 -1.27801998 6 P 0 N
A 1.86176998 -1.23075 1.86176998 -1.23075 1.84206004 -1.23075 6 P 0 N
A 1.80978996 -1.25916998 1.80978996 -1.25916998 1.78798996 -1.25916998 6 P 0 N
A 1.74681004 -1.16876004 1.74681004 -1.16876004 1.72041004 -1.16876004 6 P 0 N
A 1.67813002 -1.15513002 1.67813002 -1.15513002 1.65841998 -1.15513002 6 P 0 N
A 1.73018002 -1.27816004 1.73018002 -1.27816004 1.71433996 -1.27816004 6 P 0 N
A 1.75373002 -1.23081004 1.75373002 -1.23081004 1.73405 -1.23081004 6 P 0 N
A 1.65531004 -1.25255 1.65531004 -1.25255 1.63661998 -1.25255 6 P 0 N
A 1.69808996 -1.21291998 1.69808996 -1.21291998 1.67628996 -1.21291998 6 P 0 N
A 1.81438996 -1.1968 1.81438996 -1.1968 1.78798996 -1.1968 6 P 0 N
A 1.6269 -1.1749 1.6269 -1.1749 1.61106004 -1.1749 6 P 0 N
A 1.58461004 -1.19126004 1.58461004 -1.19126004 1.57178002 -1.19126004 6 P 0 N
A 1.5853 -1.31428002 1.5853 -1.31428002 1.57488996 -1.31428002 6 P 0 N
A 1.61735 -1.28638996 1.61735 -1.28638996 1.60276998 -1.28638996 6 P 0 N
A 1.88198996 -1.03361004 1.88198996 -1.03361004 1.85558996 -1.03361004 6 P 0 N
A 1.71881004 -1.10118002 1.71881004 -1.10118002 1.69238996 -1.10118002 6 P 0 N
A 1.65183002 -1.10118002 1.65183002 -1.10118002 1.63003002 -1.10118002 6 P 0 N
A 1.67801998 -1.04738996 1.67801998 -1.04738996 1.65831004 -1.04738996 6 P 0 N
A 1.74681004 -1.03361004 1.74681004 -1.03361004 1.72041004 -1.03361004 6 P 0 N
A 1.69811998 -0.98951004 1.69811998 -0.98951004 1.67631998 -0.98951004 6 P 0 N
A 1.81438996 -1.00556004 1.81438996 -1.00556004 1.78798996 -1.00556004 6 P 0 N
A 1.59258002 -1.10118002 1.59258002 -1.10118002 1.5739 -1.10118002 6 P 0 N
A 1.58451004 -1.01148996 1.58451004 -1.01148996 1.57168002 -1.01148996 6 P 0 N
A 1.62681004 -1.02773996 1.62681004 -1.02773996 1.61096998 -1.02773996 6 P 0 N
A 1.92148002 -1.21285 1.92148002 -1.21285 1.89968002 -1.21285 6 P 0 N
A 1.92148002 -0.98951004 1.92148002 -0.98951004 1.89968002 -0.98951004 6 P 0 N
A 1.80978996 -0.9432 1.80978996 -0.9432 1.78798996 -0.9432 6 P 0 N
A 1.80668996 -0.88708002 1.80668996 -0.88708002 1.78798996 -0.88708002 6 P 0 N
A 1.80255 -0.83923996 1.80255 -0.83923996 1.78798996 -0.83923996 6 P 0 N
A 1.8919 -0.88538002 1.8919 -0.88538002 1.87906998 -0.88538002 6 P 0 N
A 1.87838996 -0.92456998 1.87838996 -0.92456998 1.86255 -0.92456998 6 P 0 N
A 1.65531004 -0.94981004 1.65531004 -0.94981004 1.63661998 -0.94981004 6 P 0 N
A 1.73123002 -0.92378002 1.73123002 -0.92378002 1.71538996 -0.92378002 6 P 0 N
A 1.71216998 -0.88443996 1.71216998 -0.88443996 1.69935 -0.88443996 6 P 0 N
A 1.86225 -0.97178002 1.86225 -0.97178002 1.84253996 -0.97178002 6 P 0 N
A 1.75451998 -0.97123996 1.75451998 -0.97123996 1.73483996 -0.97123996 6 P 0 N
A 1.61741998 -0.91601004 1.61741998 -0.91601004 1.60283996 -0.91601004 6 P 0 N
A 1.5853 -0.88808996 1.5853 -0.88808996 1.57488996 -0.88808996 6 P 0 N
A 1.79841004 -0.79975 1.79841004 -0.79975 1.78798996 -0.79975 6 P 0 N
A 1.79433002 -0.76648002 1.79433002 -0.76648002 1.78798996 -0.76648002 6 P 0 N
A 1.92135 -1.36781004 1.92135 -1.36781004 1.91503996 -1.36781004 6 P 0 N
A 1.91096004 -1.34658002 1.91096004 -1.34658002 1.90203996 -1.34658002 6 P 0 N
A 2.19078996 -1.1806 2.26591004 -1.16473002 2.21741014 -1.12088169 6 P 0 N
A 2.15903002 -1.1402 2.19078996 -1.18061004 2.22093406 -1.12423278 6 P 0 N
A 2.05721004 -1.16178996 2.08853002 -1.16658996 2.08281614 -1.09929134 6 P 0 N
A 2.00546998 -1.13951998 2.03345 -1.17196004 2.07793927 -1.10530069 6 P 0 N
A 2.03346004 -1.17195 2.0847 -1.18461004 2.07891181 -1.09801299 6 P 0 N
A 2.0847 -1.18461998 2.14261004 -1.15663002 2.07348435 -1.08751378 6 P 0 N
A 2.08853996 -1.16658002 2.13313002 -1.14451998 2.06368967 -1.06025512 6 P 0 N
A 1.95808002 -1.25255 1.95808002 -1.25255 1.93938996 -1.25255 6 P 0 N
A 1.98775 -1.28635 1.98775 -1.28635 1.97316998 -1.28635 6 P 0 N
A 2.27411998 -1.11835 2.15906004 -1.11835 2.21658996 -1.11611998 6 P 0 N
L 2.25188002 -1.11418002 2.1807 -1.11418002 6 P 0 
L 2.1807 -1.11418002 2.1807 -1.11398996 6 P 8191 
A 2.25188996 -1.11398996 2.18071004 -1.11398996 2.2163 -1.1124 6 P 0 N
A 2.08028996 -1.03428996 2.02048996 -1.08258996 2.0798126 -1.09486801 6 P 0 N
A 2.13151998 -1.05146004 2.0803 -1.0343 2.0802999 -1.11932195 6 P 0 N
A 2.1315 -1.05146998 2.14175 -1.03951004 2.1356003 -1.04461171 6 P 0 N
A 2.14175 -1.03951004 2.08283002 -1.01613002 2.07772461 -1.11492805 6 P 0 N
A 2.08283996 -1.01611998 2.00698002 -1.05835 2.08064724 -1.10143169 6 P 0 N
L 2.27413002 -1.12868996 2.18073996 -1.12868996 6 P 0 
A 2.18075 -1.12868996 2.19083002 -1.15751998 2.22417795 -1.12968307 6 P 0 N
A 2.19083002 -1.15753002 2.25311004 -1.15211004 2.21927195 -1.12381791 6 P 0 N
L 2.15903996 -1.1402 2.15903996 -1.11835 6 P 8191 
A 2.02048996 -1.0826 2.05721998 -1.16181004 2.09087933 -1.0980811 6 P 0 N
A 2.00698996 -1.05836004 2.00546998 -1.13953002 2.09672953 -1.10063967 6 P 0 N
A 2.14258996 -1.15661004 2.13313996 -1.14453002 2.13544892 -1.15246004 6 P 0 N
A 1.95808002 -0.94981004 1.95808002 -0.94981004 1.93938996 -0.94981004 6 P 0 N
A 1.90183996 -0.8525 1.90183996 -0.8525 1.89291004 -0.8525 6 P 0 N
A 1.91108002 -0.82726998 1.91108002 -0.82726998 1.90473996 -0.82726998 6 P 0 N
L 2.32081004 -1.02041004 2.32081004 -1.17625 6 P 0 
A 2.49568002 -1.15528996 2.47898002 -1.16443002 2.4882003 -1.1614502 6 P 0 N
A 2.47896998 -1.16443996 2.50283002 -1.18086004 2.51649242 -1.13546152 6 P 0 N
A 2.50281998 -1.18086998 2.54318002 -1.1834 2.52887392 -1.08843022 6 P 0 N
A 2.52306998 -1.16761004 2.52848996 -1.16771998 2.52673258 -1.12070098 6 P 0 N
A 2.49566004 -1.15528996 2.52306998 -1.1676 2.5255122 -1.12549094 6 P 0 N
A 2.37851998 -1.15753002 2.4408 -1.15211004 2.40696191 -1.12381791 6 P 0 N
A 2.45358002 -1.16471998 2.44078996 -1.1521 2.44541191 -1.16020689 6 P 0 N
A 2.37848002 -1.1806 2.4536 -1.16473002 2.4051001 -1.12088169 6 P 0 N
A 2.34673002 -1.1402 2.37848996 -1.18061004 2.40863406 -1.12423278 6 P 0 N
A 2.2659 -1.16471998 2.25311004 -1.1521 2.25773199 -1.16020689 6 P 0 N
A 2.3006 -1.17626004 2.3208 -1.17626004 2.3107 -1.17386841 6 P 0 N
L 2.30058996 -1.17625 2.30058996 -1.02033996 6 P 0 
A 2.50836998 -1.10106004 2.54306004 -1.11513002 2.56106673 -1.02093386 6 P 0 N
A 2.51081004 -1.07948002 2.50836998 -1.10103996 2.51886093 -1.09130915 6 P 0 N
A 2.53611004 -1.07688996 2.5108 -1.07948996 2.52742205 -1.11680827 6 P 0 N
A 2.56883996 -1.07368002 2.50178002 -1.06358996 2.5273123 -1.12178858 6 P 0 N
A 2.50178996 -1.06358996 2.48536998 -1.08248996 2.52926211 -1.10403986 6 P 0 N
L 2.48536998 -1.0825 2.48536998 -1.09748002 6 P 8191 
A 2.48536998 -1.09748002 2.49956004 -1.12031004 2.51189104 -1.09682067 6 P 0 N
A 2.46181004 -1.11835 2.34675 -1.11835 2.40428002 -1.11611998 6 P 0 N
L 2.43956998 -1.11418002 2.36841004 -1.11418002 6 P 0 
L 2.36841004 -1.11418002 2.36841004 -1.11398996 6 P 8191 
A 2.43958002 -1.11398996 2.3684 -1.11398996 2.40398996 -1.1124 6 P 0 N
L 2.43956998 -1.11398996 2.43956998 -1.11418002 6 P 8191 
A 2.49955 -1.1203 2.52723002 -1.12985 2.58163209 -0.92727982 6 P 0 N
A 2.55001998 -1.14328002 2.52723002 -1.12986004 2.51462185 -1.17733228 6 P 0 N
L 2.46181004 -1.12868996 2.36843996 -1.12868996 6 P 0 
A 2.36843996 -1.12868996 2.37851998 -1.15751998 2.41186801 -1.12968307 6 P 0 N
L 2.34675 -1.1402 2.34675 -1.11835 6 P 8191 
L 2.46181004 -1.11835 2.46181004 -1.12868996 6 P 8191 
L 2.25188002 -1.11398996 2.25188002 -1.11418002 6 P 8191 
A 2.3208 -1.02041004 2.3006 -1.02033996 2.31069163 -1.02276978 6 P 0 N
L 2.27413002 -1.11835 2.27413002 -1.12868996 6 P 8191 
A 2.52848996 -1.16771004 2.54891998 -1.15895 2.52774557 -1.13777087 6 P 0 N
A 2.55608002 -1.08618002 2.53611998 -1.07688996 2.5249185 -1.12704419 6 P 0 N
L 2.71926004 -1.06796998 2.71926004 -1.17483996 6 P 0 
A 2.78888996 -1.16296998 2.81508002 -1.16676998 2.8083499 -1.12100167 6 P 0 N
A 2.8151 -1.16675 2.83966004 -1.15211998 2.80521398 -1.12222392 6 P 0 N
A 2.85201004 -1.16508002 2.83966004 -1.15211004 2.84505768 -1.15933514 6 P 0 N
L 2.85201004 -1.16508002 2.84523996 -1.17161004 6 P 8191 
A 2.81425 -1.1835 2.84525 -1.17161004 2.81425 -1.13714291 6 P 0 N
L 2.81425 -1.1835 2.79571004 -1.1835 6 P 8191 
A 2.75886998 -1.16443002 2.79571998 -1.18351998 2.80278976 -1.12476142 6 P 0 N
A 2.74528996 -1.13568002 2.75888002 -1.16443002 2.80246565 -1.12624016 6 P 0 N
A 2.54316998 -1.1834 2.56906004 -1.1647 2.5305814 -1.13869892 6 P 0 N
A 2.56906004 -1.1647 2.57053996 -1.13728002 2.53763041 -1.14925374 6 P 0 N
A 2.65463996 -1.18351998 2.66863996 -1.17373996 2.65440246 -1.16826969 6 P 0 N
L 2.65463002 -1.1835 2.64165 -1.1835 6 P 8191 
A 2.60955 -1.16043002 2.64163996 -1.18351004 2.63911063 -1.15317815 6 P 0 N
A 2.62978002 -1.15461998 2.66001998 -1.16328996 2.6502374 -1.14033868 6 P 0 N
A 2.66863996 -1.17375 2.66001998 -1.16328996 2.66100344 -1.17126132 6 P 0 N
A 2.6962 -1.17483996 2.71926004 -1.17483996 2.70773002 -1.17286427 6 P 0 N
L 2.69618996 -1.17483996 2.69618996 -1.06796998 6 P 0 
A 2.83833002 -1.09275 2.82661998 -1.08201998 2.74555758 -1.18224094 6 P 0 N
A 2.82661998 -1.08198996 2.80036998 -1.07538996 2.80348839 -1.11848878 6 P 0 N
A 2.80036004 -1.07541998 2.76848996 -1.09933002 2.80700217 -1.1174685 6 P 0 N
A 2.76848996 -1.09931998 2.76446004 -1.12066004 2.82315728 -1.120694 6 P 0 N
A 2.74998002 -1.09273996 2.74528996 -1.11838996 2.8498563 -1.12425591 6 P 0 N
A 2.7954 -1.05776998 2.74998996 -1.09273996 2.80799961 -1.12109961 6 P 0 N
L 2.79541004 -1.05776998 2.80918996 -1.05776998 6 P 8191 
A 2.85401998 -1.08106004 2.80918996 -1.05776998 2.80626024 -1.1181998 6 P 0 N
A 2.83833002 -1.09273996 2.85403002 -1.08106004 2.84418386 -1.08421683 6 P 0 N
L 2.76445 -1.12066004 2.76445 -1.12943002 6 P 8191 
A 2.76446004 -1.12943002 2.76836998 -1.14305 2.80607844 -1.12485364 6 P 0 N
A 2.76836998 -1.14305 2.78891004 -1.16296998 2.80906152 -1.12164144 6 P 0 N
L 2.74528996 -1.13566004 2.74528996 -1.11838996 6 P 8191 
A 2.55606004 -1.0862 2.56885 -1.07366998 2.56205354 -1.0795252 6 P 0 N
L 2.60953996 -1.07953996 2.59981998 -1.07953996 6 P 8191 
A 2.5993 -1.05931998 2.59981004 -1.07955 2.6022813 -1.06936624 6 P 0 N
L 2.5993 -1.05931998 2.60953996 -1.05931998 6 P 8191 
L 2.60953996 -1.05931998 2.60953996 -1.03491998 6 P 8191 
A 2.62971998 -1.03418002 2.60953996 -1.03491004 2.61966791 -1.03559478 6 P 0 N
L 2.62971004 -1.03418996 2.62978002 -1.05931998 6 P 8191 
L 2.62978002 -1.05931998 2.66008002 -1.05931998 6 P 8191 
A 2.66003996 -1.07955 2.66008002 -1.05931998 2.65827421 -1.0694314 6 P 0 N
L 2.66003002 -1.07953996 2.62978002 -1.07953996 6 P 8191 
A 2.71926004 -1.06796998 2.6962 -1.06796998 2.70773002 -1.0720561 6 P 0 N
A 2.71968996 -1.02341998 2.71968996 -1.02341998 2.70775 -1.02341998 6 P 0 N
A 2.57053996 -1.13728996 2.54306998 -1.11513002 2.53584449 -1.15219301 6 P 0 N
A 2.54891998 -1.15895 2.55001004 -1.14328002 2.54127923 -1.15054557 6 P 0 N
L 2.60953996 -1.16041004 2.60953996 -1.07953996 6 P 0 
L 2.62978002 -1.07953996 2.62978002 -1.15463002 6 P 0 
L 2.98495 -1.09393996 2.98495 -1.17625 6 P 0 
A 2.96473996 -1.17626998 2.98493996 -1.17626998 2.97483996 -1.17442303 6 P 0 N
L 2.96473002 -1.17625 2.96473002 -1.17226004 6 P 8191 
A 2.94165 -1.1835 2.96471004 -1.17226004 2.93076516 -1.1318935 6 P 0 N
L 2.94165 -1.1835 2.90701004 -1.1835 6 P 8191 
A 2.90671004 -1.10841998 2.90703002 -1.18351004 2.9153065 -1.14592904 6 P 0 N
A 2.91853002 -1.12288996 2.91853002 -1.16618996 2.92048209 -1.14453996 6 P 0 N
L 2.91853002 -1.1662 2.94456004 -1.1662 6 P 8191 
A 2.94456998 -1.16618996 2.94456998 -1.12288996 2.94406004 -1.14453996 6 P 0 N
A 2.96473002 -1.09686004 2.94741998 -1.07955 2.94874833 -1.09553169 6 P 0 N
L 2.9474 -1.07953996 2.90986998 -1.07953996 6 P 8191 
A 2.90986998 -1.07953996 2.89821004 -1.0852 2.92433445 -1.12417766 6 P 0 N
A 2.89111998 -1.07086004 2.8982 -1.0852 2.8969689 -1.07688996 6 P 0 N
A 2.91561998 -1.05931998 2.89111998 -1.07085 2.92146033 -1.103525 6 P 0 N
L 2.91563002 -1.05931998 2.95031004 -1.05931998 6 P 8191 
A 2.98496004 -1.09393996 2.95031004 -1.05933002 2.9453438 -1.09895197 6 P 0 N
A 2.92878996 -1.10535 2.9067 -1.10841998 2.93158484 -1.20646998 6 P 0 N
A 2.96471998 -1.10841004 2.92878002 -1.10536004 2.93215738 -1.27883829 6 P 0 N
L 2.96473002 -1.10841004 2.96473002 -1.09686004 6 P 8191 
L 2.94456004 -1.12288002 2.91853002 -1.12288002 6 P 8191 
L 3.04731004 -1.06001004 3.04191998 -1.07631998 6 P 8191 
L 3.04191998 -1.07631998 3.03648002 -1.06001004 6 P 8191 
L 3.03648002 -1.06001004 3.03243002 -1.06001004 6 P 8191 
L 3.03243002 -1.06001004 3.02698002 -1.08543996 6 P 8191 
L 3.02698002 -1.08543996 3.03226004 -1.08543996 6 P 8191 
L 3.03226004 -1.08543996 3.03501004 -1.06886998 6 P 8191 
L 3.03501004 -1.06886998 3.04086004 -1.08543996 6 P 8191 
L 3.04086004 -1.08543996 3.04308996 -1.08543996 6 P 8191 
L 3.04308996 -1.08543996 3.04888996 -1.06871004 6 P 8191 
L 3.04888996 -1.06871004 3.05171004 -1.08543996 6 P 8191 
L 3.05171004 -1.08543996 3.05713002 -1.08543996 6 P 8191 
L 3.05713002 -1.08543996 3.05163996 -1.06001004 6 P 8191 
L 3.05163996 -1.06001004 3.04731004 -1.06001004 6 P 8191 
L 3.01066998 -1.06508002 3.00223002 -1.06508002 6 P 8191 
L 3.00223002 -1.06508002 3.00223002 -1.06001004 6 P 8191 
L 3.00223002 -1.06001004 3.02461004 -1.06001004 6 P 8191 
L 3.02461004 -1.06001004 3.02461004 -1.06508002 6 P 8191 
L 3.02461004 -1.06508002 3.01615 -1.06508002 6 P 8191 
L 3.01615 -1.06508002 3.01615 -1.08533996 6 P 8191 
L 3.01615 -1.08533996 3.01066998 -1.08533996 6 P 8191 
L 3.01066998 -1.08533996 3.01066998 -1.06508002 6 P 8191 
L 3.8433999 -1.32000217 3.85086663 -1.32625089 0 P 0 ;1,3=89,5=0.000000
L 3.85086663 -1.32625089 3.85926654 -1.33 0 P 0 ;1,3=89,5=0.000000
L 3.85926654 -1.33 3.86673337 -1.33 0 P 0 ;1,3=89,5=0.000000
L 3.86673337 -1.33 3.8742001 -1.32625089 0 P 0 ;1,3=89,5=0.000000
L 3.8742001 -1.32625089 3.87980059 -1.32000217 0 P 0 ;1,3=89,5=0.000000
L 3.87980059 -1.32000217 3.8826 -1.31124951 0 P 0 ;1,3=89,5=0.000000
L 3.8826 -1.31124951 3.88073376 -1.30250138 0 P 0 ;1,3=89,5=0.000000
L 3.88073376 -1.30250138 3.87606644 -1.29500069 0 P 0 ;1,3=89,5=0.000000
L 3.87606644 -1.29500069 3.86766644 -1.28999941 0 P 0 ;1,3=89,5=0.000000
L 3.86766644 -1.28999941 3.85646713 -1.2875 0 P 0 ;1,3=89,5=0.000000
L 3.85646713 -1.2875 3.84993346 -1.28250108 0 P 0 ;1,3=89,5=0.000000
L 3.84993346 -1.28250108 3.84713238 -1.27375059 0 P 0 ;1,3=89,5=0.000000
L 3.84713238 -1.27375059 3.84900039 -1.2650002 0 P 0 ;1,3=89,5=0.000000
L 3.84900039 -1.2650002 3.85366604 -1.25875157 0 P 0 ;1,3=89,5=0.000000
L 3.85366604 -1.25875157 3.8601997 -1.255 0 P 0 ;1,3=89,5=0.000000
L 3.8601997 -1.255 3.86673337 -1.255 0 P 0 ;1,3=89,5=0.000000
L 3.86673337 -1.255 3.87326703 -1.25749951 0 P 0 ;1,3=89,5=0.000000
L 3.87326703 -1.25749951 3.87886752 -1.26375049 0 P 0 ;1,3=89,5=0.000000
L 3.93799911 -1.33 3.93053228 -1.3287503 0 P 0 ;1,3=89,5=0.000000
L 3.93053228 -1.3287503 3.92400039 -1.32375138 0 P 0 ;1,3=89,5=0.000000
L 3.92400039 -1.32375138 3.9183999 -1.31625069 0 P 0 ;1,3=89,5=0.000000
L 3.9183999 -1.31625069 3.91466565 -1.3075003 0 P 0 ;1,3=89,5=0.000000
L 3.91466565 -1.3075003 3.91279931 -1.2975001 0 P 0 ;1,3=89,5=0.000000
L 3.91279931 -1.2975001 3.91279931 -1.2875 0 P 0 ;1,3=89,5=0.000000
L 3.91279931 -1.2875 3.91466565 -1.2774998 0 P 0 ;1,3=89,5=0.000000
L 3.91466565 -1.2774998 3.9183999 -1.26874941 0 P 0 ;1,3=89,5=0.000000
L 3.9183999 -1.26874941 3.92400039 -1.26125098 0 P 0 ;1,3=89,5=0.000000
L 3.92400039 -1.26125098 3.93053228 -1.2562498 0 P 0 ;1,3=89,5=0.000000
L 3.93053228 -1.2562498 3.93799911 -1.255 0 P 0 ;1,3=89,5=0.000000
L 3.93799911 -1.255 3.94546585 -1.2562498 0 P 0 ;1,3=89,5=0.000000
L 3.94546585 -1.2562498 3.95199951 -1.26125098 0 P 0 ;1,3=89,5=0.000000
L 3.95199951 -1.26125098 3.9576 -1.26874941 0 P 0 ;1,3=89,5=0.000000
L 3.9576 -1.26874941 3.96133425 -1.2774998 0 P 0 ;1,3=89,5=0.000000
L 3.96133425 -1.2774998 3.96320059 -1.2875 0 P 0 ;1,3=89,5=0.000000
L 3.96320059 -1.2875 3.96320059 -1.2975001 0 P 0 ;1,3=89,5=0.000000
L 3.96320059 -1.2975001 3.96133425 -1.3075003 0 P 0 ;1,3=89,5=0.000000
L 3.96133425 -1.3075003 3.9576 -1.31625069 0 P 0 ;1,3=89,5=0.000000
L 3.9576 -1.31625069 3.95199951 -1.32375138 0 P 0 ;1,3=89,5=0.000000
L 3.95199951 -1.32375138 3.94546585 -1.3287503 0 P 0 ;1,3=89,5=0.000000
L 3.94546585 -1.3287503 3.93799911 -1.33 0 P 0 ;1,3=89,5=0.000000
L 3.99433297 -1.255 3.99433297 -1.33 0 P 0 ;1,3=89,5=0.000000
L 3.99433297 -1.33 4.03166693 -1.33 0 P 0 ;1,3=89,5=0.000000
L 4.06746673 -1.33 4.06746673 -1.255 0 P 0 ;1,3=89,5=0.000000
L 4.06746673 -1.255 4.08613287 -1.255 0 P 0 ;1,3=89,5=0.000000
L 4.08613287 -1.255 4.09359961 -1.25875157 0 P 0 ;1,3=89,5=0.000000
L 4.09359961 -1.25875157 4.0992001 -1.26375049 0 P 0 ;1,3=89,5=0.000000
L 4.0992001 -1.26375049 4.10386752 -1.27124882 0 P 0 ;1,3=89,5=0.000000
L 4.10386752 -1.27124882 4.1076 -1.28000157 0 P 0 ;1,3=89,5=0.000000
L 4.1076 -1.28000157 4.10853317 -1.29250118 0 P 0 ;1,3=89,5=0.000000
L 4.10853317 -1.29250118 4.1076 -1.30500079 0 P 0 ;1,3=89,5=0.000000
L 4.1076 -1.30500079 4.10386752 -1.31375128 0 P 0 ;1,3=89,5=0.000000
L 4.10386752 -1.31375128 4.0992001 -1.32125187 0 P 0 ;1,3=89,5=0.000000
L 4.0992001 -1.32125187 4.09359961 -1.32625089 0 P 0 ;1,3=89,5=0.000000
L 4.09359961 -1.32625089 4.08613287 -1.33 0 P 0 ;1,3=89,5=0.000000
L 4.08613287 -1.33 4.06746673 -1.33 0 P 0 ;1,3=89,5=0.000000
L 4.18166693 -1.33 4.14433297 -1.33 0 P 0 ;1,3=89,5=0.000000
L 4.14433297 -1.33 4.14433297 -1.255 0 P 0 ;1,3=89,5=0.000000
L 4.14433297 -1.255 4.18166693 -1.255 0 P 0 ;1,3=89,5=0.000000
L 4.16673337 -1.29124921 4.14433297 -1.29124921 0 P 0 ;1,3=89,5=0.000000
L 4.21933297 -1.33 4.21933297 -1.255 0 P 0 ;1,3=89,5=0.000000
L 4.21933297 -1.255 4.24266644 -1.255 0 P 0 ;1,3=89,5=0.000000
L 4.24266644 -1.255 4.25013327 -1.25875157 0 P 0 ;1,3=89,5=0.000000
L 4.25013327 -1.25875157 4.25480059 -1.26375049 0 P 0 ;1,3=89,5=0.000000
L 4.25480059 -1.26375049 4.25666693 -1.27375059 0 P 0 ;1,3=89,5=0.000000
L 4.25666693 -1.27375059 4.25480059 -1.28375079 0 P 0 ;1,3=89,5=0.000000
L 4.25480059 -1.28375079 4.2492001 -1.28999941 0 P 0 ;1,3=89,5=0.000000
L 4.2492001 -1.28999941 4.24266644 -1.29375089 0 P 0 ;1,3=89,5=0.000000
L 4.24266644 -1.29375089 4.21933297 -1.29375089 0 P 0 ;1,3=89,5=0.000000
L 4.24266644 -1.29375089 4.25666693 -1.33 0 P 0 ;1,3=89,5=0.000000
L 4.28873248 -1.33 4.28873248 -1.255 0 P 0 ;1,3=89,5=0.000000
L 4.28873248 -1.255 4.31299911 -1.31750039 0 P 0 ;1,3=89,5=0.000000
L 4.31299911 -1.31750039 4.33726742 -1.255 0 P 0 ;1,3=89,5=0.000000
L 4.33726742 -1.255 4.33726742 -1.33 0 P 0 ;1,3=89,5=0.000000
L 4.36466565 -1.33 4.38799911 -1.255 0 P 0 ;1,3=89,5=0.000000
L 4.38799911 -1.255 4.41133425 -1.33 0 P 0 ;1,3=89,5=0.000000
L 4.40293268 -1.30375108 4.37306555 -1.30375108 0 P 0 ;1,3=89,5=0.000000
L 4.4433999 -1.32000217 4.45086663 -1.32625089 0 P 0 ;1,3=89,5=0.000000
L 4.45086663 -1.32625089 4.45926654 -1.33 0 P 0 ;1,3=89,5=0.000000
L 4.45926654 -1.33 4.46673337 -1.33 0 P 0 ;1,3=89,5=0.000000
L 4.46673337 -1.33 4.4742001 -1.32625089 0 P 0 ;1,3=89,5=0.000000
L 4.4742001 -1.32625089 4.47980059 -1.32000217 0 P 0 ;1,3=89,5=0.000000
L 4.47980059 -1.32000217 4.4826 -1.31124951 0 P 0 ;1,3=89,5=0.000000
L 4.4826 -1.31124951 4.48073376 -1.30250138 0 P 0 ;1,3=89,5=0.000000
L 4.48073376 -1.30250138 4.47606644 -1.29500069 0 P 0 ;1,3=89,5=0.000000
L 4.47606644 -1.29500069 4.46766644 -1.28999941 0 P 0 ;1,3=89,5=0.000000
L 4.46766644 -1.28999941 4.45646713 -1.2875 0 P 0 ;1,3=89,5=0.000000
L 4.45646713 -1.2875 4.44993346 -1.28250108 0 P 0 ;1,3=89,5=0.000000
L 4.44993346 -1.28250108 4.44713238 -1.27375059 0 P 0 ;1,3=89,5=0.000000
L 4.44713238 -1.27375059 4.44900039 -1.2650002 0 P 0 ;1,3=89,5=0.000000
L 4.44900039 -1.2650002 4.45366604 -1.25875157 0 P 0 ;1,3=89,5=0.000000
L 4.45366604 -1.25875157 4.4601997 -1.255 0 P 0 ;1,3=89,5=0.000000
L 4.4601997 -1.255 4.46673337 -1.255 0 P 0 ;1,3=89,5=0.000000
L 4.46673337 -1.255 4.47326703 -1.25749951 0 P 0 ;1,3=89,5=0.000000
L 4.47326703 -1.25749951 4.47886752 -1.26375049 0 P 0 ;1,3=89,5=0.000000
L 4.51746673 -1.33 4.51746673 -1.255 0 P 0 ;1,3=89,5=0.000000
L 4.55293268 -1.255 4.51746673 -1.30125157 0 P 0 ;1,3=89,5=0.000000
L 4.55853317 -1.33 4.53333346 -1.28000157 0 P 0 ;1,3=89,5=0.000000
L 4.68799911 -1.255 4.68799911 -1.33 0 P 0 ;1,3=89,5=0.000000
L 4.66653356 -1.255 4.70946634 -1.255 0 P 0 ;1,3=89,5=0.000000
L 4.76299911 -1.33 4.75553228 -1.3287503 0 P 0 ;1,3=89,5=0.000000
L 4.75553228 -1.3287503 4.74900039 -1.32375138 0 P 0 ;1,3=89,5=0.000000
L 4.74900039 -1.32375138 4.7433999 -1.31625069 0 P 0 ;1,3=89,5=0.000000
L 4.7433999 -1.31625069 4.73966565 -1.3075003 0 P 0 ;1,3=89,5=0.000000
L 4.73966565 -1.3075003 4.73779931 -1.2975001 0 P 0 ;1,3=89,5=0.000000
L 4.73779931 -1.2975001 4.73779931 -1.2875 0 P 0 ;1,3=89,5=0.000000
L 4.73779931 -1.2875 4.73966565 -1.2774998 0 P 0 ;1,3=89,5=0.000000
L 4.73966565 -1.2774998 4.7433999 -1.26874941 0 P 0 ;1,3=89,5=0.000000
L 4.7433999 -1.26874941 4.74900039 -1.26125098 0 P 0 ;1,3=89,5=0.000000
L 4.74900039 -1.26125098 4.75553228 -1.2562498 0 P 0 ;1,3=89,5=0.000000
L 4.75553228 -1.2562498 4.76299911 -1.255 0 P 0 ;1,3=89,5=0.000000
L 4.76299911 -1.255 4.77046585 -1.2562498 0 P 0 ;1,3=89,5=0.000000
L 4.77046585 -1.2562498 4.77699951 -1.26125098 0 P 0 ;1,3=89,5=0.000000
L 4.77699951 -1.26125098 4.7826 -1.26874941 0 P 0 ;1,3=89,5=0.000000
L 4.7826 -1.26874941 4.78633425 -1.2774998 0 P 0 ;1,3=89,5=0.000000
L 4.78633425 -1.2774998 4.78820059 -1.2875 0 P 0 ;1,3=89,5=0.000000
L 4.78820059 -1.2875 4.78820059 -1.2975001 0 P 0 ;1,3=89,5=0.000000
L 4.78820059 -1.2975001 4.78633425 -1.3075003 0 P 0 ;1,3=89,5=0.000000
L 4.78633425 -1.3075003 4.7826 -1.31625069 0 P 0 ;1,3=89,5=0.000000
L 4.7826 -1.31625069 4.77699951 -1.32375138 0 P 0 ;1,3=89,5=0.000000
L 4.77699951 -1.32375138 4.77046585 -1.3287503 0 P 0 ;1,3=89,5=0.000000
L 4.77046585 -1.3287503 4.76299911 -1.33 0 P 0 ;1,3=89,5=0.000000
L 4.81933297 -1.33 4.81933297 -1.255 0 P 0 ;1,3=89,5=0.000000
L 4.81933297 -1.255 4.84173337 -1.255 0 P 0 ;1,3=89,5=0.000000
L 4.84173337 -1.255 4.8492001 -1.25875157 0 P 0 ;1,3=89,5=0.000000
L 4.8492001 -1.25875157 4.85480059 -1.2674997 0 P 0 ;1,3=89,5=0.000000
L 4.85480059 -1.2674997 4.85666693 -1.2774998 0 P 0 ;1,3=89,5=0.000000
L 4.85666693 -1.2774998 4.85480059 -1.2875 0 P 0 ;1,3=89,5=0.000000
L 4.85480059 -1.2875 4.85013327 -1.29500069 0 P 0 ;1,3=89,5=0.000000
L 4.85013327 -1.29500069 4.84173337 -1.29875217 0 P 0 ;1,3=89,5=0.000000
L 4.84173337 -1.29875217 4.81933297 -1.29875217 0 P 0 ;1,3=89,5=0.000000
L 3.36933297 -0.955 3.36933297 -0.88 0 P 0 ;1,3=90,5=0.000000
L 3.36933297 -0.88 3.39173337 -0.88 0 P 0 ;1,3=90,5=0.000000
L 3.39173337 -0.88 3.3992001 -0.88375157 0 P 0 ;1,3=90,5=0.000000
L 3.3992001 -0.88375157 3.40480059 -0.8924997 0 P 0 ;1,3=90,5=0.000000
L 3.40480059 -0.8924997 3.40666693 -0.9024998 0 P 0 ;1,3=90,5=0.000000
L 3.40666693 -0.9024998 3.40480059 -0.9125 0 P 0 ;1,3=90,5=0.000000
L 3.40480059 -0.9125 3.40013327 -0.92000069 0 P 0 ;1,3=90,5=0.000000
L 3.40013327 -0.92000069 3.39173337 -0.92375217 0 P 0 ;1,3=90,5=0.000000
L 3.39173337 -0.92375217 3.36933297 -0.92375217 0 P 0 ;1,3=90,5=0.000000
L 3.44619931 -0.95749941 3.47980059 -0.88 0 P 0 ;1,3=90,5=0.000000
L 3.51653356 -0.955 3.51653356 -0.88 0 P 0 ;1,3=90,5=0.000000
L 3.51653356 -0.88 3.55946634 -0.955 0 P 0 ;1,3=90,5=0.000000
L 3.55946634 -0.955 3.55946634 -0.88 0 P 0 ;1,3=90,5=0.000000
L 3.68799911 -0.95749941 3.68613287 -0.9562497 0 P 0 ;1,3=90,5=0.000000
L 3.68613287 -0.9562497 3.68613287 -0.9537503 0 P 0 ;1,3=90,5=0.000000
L 3.68613287 -0.9537503 3.68799911 -0.95250059 0 P 0 ;1,3=90,5=0.000000
L 3.68799911 -0.95250059 3.68986703 -0.9537503 0 P 0 ;1,3=90,5=0.000000
L 3.68986703 -0.9537503 3.68986703 -0.9562497 0 P 0 ;1,3=90,5=0.000000
L 3.68986703 -0.9562497 3.68799911 -0.95749941 0 P 0 ;1,3=90,5=0.000000
L 3.68799911 -0.92375217 3.68613287 -0.9225001 0 P 0 ;1,3=90,5=0.000000
L 3.68613287 -0.9225001 3.68613287 -0.92000069 0 P 0 ;1,3=90,5=0.000000
L 3.68613287 -0.92000069 3.68799911 -0.91875089 0 P 0 ;1,3=90,5=0.000000
L 3.68799911 -0.91875089 3.68986703 -0.92000069 0 P 0 ;1,3=90,5=0.000000
L 3.68986703 -0.92000069 3.68986703 -0.9225001 0 P 0 ;1,3=90,5=0.000000
L 3.68986703 -0.9225001 3.68799911 -0.92375217 0 P 0 ;1,3=90,5=0.000000
L 3.81933297 -0.955 3.81933297 -0.88 0 P 0 ;1,3=90,5=0.000000
L 3.81933297 -0.88 3.84266644 -0.88 0 P 0 ;1,3=90,5=0.000000
L 3.84266644 -0.88 3.85013327 -0.88375157 0 P 0 ;1,3=90,5=0.000000
L 3.85013327 -0.88375157 3.85480059 -0.88875049 0 P 0 ;1,3=90,5=0.000000
L 3.85480059 -0.88875049 3.85666693 -0.89875059 0 P 0 ;1,3=90,5=0.000000
L 3.85666693 -0.89875059 3.85480059 -0.90875079 0 P 0 ;1,3=90,5=0.000000
L 3.85480059 -0.90875079 3.8492001 -0.91499941 0 P 0 ;1,3=90,5=0.000000
L 3.8492001 -0.91499941 3.84266644 -0.91875089 0 P 0 ;1,3=90,5=0.000000
L 3.84266644 -0.91875089 3.81933297 -0.91875089 0 P 0 ;1,3=90,5=0.000000
L 3.84266644 -0.91875089 3.85666693 -0.955 0 P 0 ;1,3=90,5=0.000000
L 3.9242001 -0.955 3.9242001 -0.88 0 P 0 ;1,3=90,5=0.000000
L 3.9242001 -0.88 3.88966565 -0.93375 0 P 0 ;1,3=90,5=0.000000
L 3.88966565 -0.93375 3.93633425 -0.93375 0 P 0 ;1,3=90,5=0.000000
L 3.98799911 -0.88 3.98053228 -0.88249951 0 P 0 ;1,3=90,5=0.000000
L 3.98053228 -0.88249951 3.97493346 -0.88875049 0 P 0 ;1,3=90,5=0.000000
L 3.97493346 -0.88875049 3.97119931 -0.89624882 0 P 0 ;1,3=90,5=0.000000
L 3.97119931 -0.89624882 3.9683999 -0.90625128 0 P 0 ;1,3=90,5=0.000000
L 3.9683999 -0.90625128 3.96746673 -0.91750118 0 P 0 ;1,3=90,5=0.000000
L 3.96746673 -0.91750118 3.9683999 -0.92875108 0 P 0 ;1,3=90,5=0.000000
L 3.9683999 -0.92875108 3.97119931 -0.93875128 0 P 0 ;1,3=90,5=0.000000
L 3.97119931 -0.93875128 3.97493346 -0.94625187 0 P 0 ;1,3=90,5=0.000000
L 3.97493346 -0.94625187 3.98053228 -0.95250059 0 P 0 ;1,3=90,5=0.000000
L 3.98053228 -0.95250059 3.98799911 -0.955 0 P 0 ;1,3=90,5=0.000000
L 3.98799911 -0.955 3.99546585 -0.95250059 0 P 0 ;1,3=90,5=0.000000
L 3.99546585 -0.95250059 4.00106644 -0.94625187 0 P 0 ;1,3=90,5=0.000000
L 4.00106644 -0.94625187 4.00480059 -0.93875128 0 P 0 ;1,3=90,5=0.000000
L 4.00480059 -0.93875128 4.0076 -0.92875108 0 P 0 ;1,3=90,5=0.000000
L 4.0076 -0.92875108 4.00853317 -0.91750118 0 P 0 ;1,3=90,5=0.000000
L 4.00853317 -0.91750118 4.0076 -0.90625128 0 P 0 ;1,3=90,5=0.000000
L 4.0076 -0.90625128 4.00480059 -0.89624882 0 P 0 ;1,3=90,5=0.000000
L 4.00480059 -0.89624882 4.00106644 -0.88875049 0 P 0 ;1,3=90,5=0.000000
L 4.00106644 -0.88875049 3.99546585 -0.88249951 0 P 0 ;1,3=90,5=0.000000
L 3.99546585 -0.88249951 3.98799911 -0.88 0 P 0 ;1,3=90,5=0.000000
L 4.06299911 -0.88 4.05553228 -0.88249951 0 P 0 ;1,3=90,5=0.000000
L 4.05553228 -0.88249951 4.04993346 -0.88875049 0 P 0 ;1,3=90,5=0.000000
L 4.04993346 -0.88875049 4.04619931 -0.89624882 0 P 0 ;1,3=90,5=0.000000
L 4.04619931 -0.89624882 4.0433999 -0.90625128 0 P 0 ;1,3=90,5=0.000000
L 4.0433999 -0.90625128 4.04246673 -0.91750118 0 P 0 ;1,3=90,5=0.000000
L 4.04246673 -0.91750118 4.0433999 -0.92875108 0 P 0 ;1,3=90,5=0.000000
L 4.0433999 -0.92875108 4.04619931 -0.93875128 0 P 0 ;1,3=90,5=0.000000
L 4.04619931 -0.93875128 4.04993346 -0.94625187 0 P 0 ;1,3=90,5=0.000000
L 4.04993346 -0.94625187 4.05553228 -0.95250059 0 P 0 ;1,3=90,5=0.000000
L 4.05553228 -0.95250059 4.06299911 -0.955 0 P 0 ;1,3=90,5=0.000000
L 4.06299911 -0.955 4.07046585 -0.95250059 0 P 0 ;1,3=90,5=0.000000
L 4.07046585 -0.95250059 4.07606644 -0.94625187 0 P 0 ;1,3=90,5=0.000000
L 4.07606644 -0.94625187 4.07980059 -0.93875128 0 P 0 ;1,3=90,5=0.000000
L 4.07980059 -0.93875128 4.0826 -0.92875108 0 P 0 ;1,3=90,5=0.000000
L 4.0826 -0.92875108 4.08353317 -0.91750118 0 P 0 ;1,3=90,5=0.000000
L 4.08353317 -0.91750118 4.0826 -0.90625128 0 P 0 ;1,3=90,5=0.000000
L 4.0826 -0.90625128 4.07980059 -0.89624882 0 P 0 ;1,3=90,5=0.000000
L 4.07980059 -0.89624882 4.07606644 -0.88875049 0 P 0 ;1,3=90,5=0.000000
L 4.07606644 -0.88875049 4.07046585 -0.88249951 0 P 0 ;1,3=90,5=0.000000
L 4.07046585 -0.88249951 4.06299911 -0.88 0 P 0 ;1,3=90,5=0.000000
L 4.12026614 -0.92375217 4.1267998 -0.91499941 0 P 0 ;1,3=90,5=0.000000
L 4.1267998 -0.91499941 4.1324003 -0.91000049 0 P 0 ;1,3=90,5=0.000000
L 4.1324003 -0.91000049 4.13986703 -0.90750108 0 P 0 ;1,3=90,5=0.000000
L 4.13986703 -0.90750108 4.14640069 -0.91000049 0 P 0 ;1,3=90,5=0.000000
L 4.14640069 -0.91000049 4.15106644 -0.91499941 0 P 0 ;1,3=90,5=0.000000
L 4.15106644 -0.91499941 4.15480059 -0.9225001 0 P 0 ;1,3=90,5=0.000000
L 4.15480059 -0.9225001 4.15573376 -0.93125059 0 P 0 ;1,3=90,5=0.000000
L 4.15573376 -0.93125059 4.15480059 -0.93875128 0 P 0 ;1,3=90,5=0.000000
L 4.15480059 -0.93875128 4.15106644 -0.94625187 0 P 0 ;1,3=90,5=0.000000
L 4.15106644 -0.94625187 4.14546585 -0.95250059 0 P 0 ;1,3=90,5=0.000000
L 4.14546585 -0.95250059 4.13893396 -0.955 0 P 0 ;1,3=90,5=0.000000
L 4.13893396 -0.955 4.13146713 -0.95250059 0 P 0 ;1,3=90,5=0.000000
L 4.13146713 -0.95250059 4.12493346 -0.94500217 0 P 0 ;1,3=90,5=0.000000
L 4.12493346 -0.94500217 4.12119931 -0.93375 0 P 0 ;1,3=90,5=0.000000
L 4.12119931 -0.93375 4.12026614 -0.92125039 0 P 0 ;1,3=90,5=0.000000
L 4.12026614 -0.92125039 4.12213238 -0.90500157 0 P 0 ;1,3=90,5=0.000000
L 4.12213238 -0.90500157 4.12493346 -0.89624882 0 P 0 ;1,3=90,5=0.000000
L 4.12493346 -0.89624882 4.12959921 -0.88750069 0 P 0 ;1,3=90,5=0.000000
L 4.12959921 -0.88750069 4.13613287 -0.8812498 0 P 0 ;1,3=90,5=0.000000
L 4.13613287 -0.8812498 4.14266644 -0.88 0 P 0 ;1,3=90,5=0.000000
L 4.14266644 -0.88 4.1492001 -0.88249951 0 P 0 ;1,3=90,5=0.000000
L 4.1492001 -0.88249951 4.15386752 -0.88875049 0 P 0 ;1,3=90,5=0.000000
L 4.20086663 -0.93000079 4.22513327 -0.93000079 0 P 0 ;1,3=90,5=0.000000
L 4.29546585 -0.91499941 4.2992001 -0.9112502 0 P 0 ;1,3=90,5=0.000000
L 4.2992001 -0.9112502 4.30199951 -0.90500157 0 P 0 ;1,3=90,5=0.000000
L 4.30199951 -0.90500157 4.30386752 -0.89624882 0 P 0 ;1,3=90,5=0.000000
L 4.30386752 -0.89624882 4.30199951 -0.88875049 0 P 0 ;1,3=90,5=0.000000
L 4.30199951 -0.88875049 4.29826703 -0.88375157 0 P 0 ;1,3=90,5=0.000000
L 4.29826703 -0.88375157 4.29173337 -0.88 0 P 0 ;1,3=90,5=0.000000
L 4.29173337 -0.88 4.26653356 -0.88 0 P 0 ;1,3=90,5=0.000000
L 4.26653356 -0.88 4.26653356 -0.955 0 P 0 ;1,3=90,5=0.000000
L 4.26653356 -0.955 4.29733386 -0.955 0 P 0 ;1,3=90,5=0.000000
L 4.29733386 -0.955 4.30386752 -0.95000108 0 P 0 ;1,3=90,5=0.000000
L 4.30386752 -0.95000108 4.3076 -0.94250039 0 P 0 ;1,3=90,5=0.000000
L 4.3076 -0.94250039 4.30946634 -0.93375 0 P 0 ;1,3=90,5=0.000000
L 4.30946634 -0.93375 4.3076 -0.92500187 0 P 0 ;1,3=90,5=0.000000
L 4.3076 -0.92500187 4.30199951 -0.91750118 0 P 0 ;1,3=90,5=0.000000
L 4.30199951 -0.91750118 4.29546585 -0.91499941 0 P 0 ;1,3=90,5=0.000000
L 4.29546585 -0.91499941 4.26653356 -0.91499941 0 P 0 ;1,3=90,5=0.000000
L 4.36299911 -0.88 4.35553228 -0.88249951 0 P 0 ;1,3=90,5=0.000000
L 4.35553228 -0.88249951 4.34993346 -0.88875049 0 P 0 ;1,3=90,5=0.000000
L 4.34993346 -0.88875049 4.34619931 -0.89624882 0 P 0 ;1,3=90,5=0.000000
L 4.34619931 -0.89624882 4.3433999 -0.90625128 0 P 0 ;1,3=90,5=0.000000
L 4.3433999 -0.90625128 4.34246673 -0.91750118 0 P 0 ;1,3=90,5=0.000000
L 4.34246673 -0.91750118 4.3433999 -0.92875108 0 P 0 ;1,3=90,5=0.000000
L 4.3433999 -0.92875108 4.34619931 -0.93875128 0 P 0 ;1,3=90,5=0.000000
L 4.34619931 -0.93875128 4.34993346 -0.94625187 0 P 0 ;1,3=90,5=0.000000
L 4.34993346 -0.94625187 4.35553228 -0.95250059 0 P 0 ;1,3=90,5=0.000000
L 4.35553228 -0.95250059 4.36299911 -0.955 0 P 0 ;1,3=90,5=0.000000
L 4.36299911 -0.955 4.37046585 -0.95250059 0 P 0 ;1,3=90,5=0.000000
L 4.37046585 -0.95250059 4.37606644 -0.94625187 0 P 0 ;1,3=90,5=0.000000
L 4.37606644 -0.94625187 4.37980059 -0.93875128 0 P 0 ;1,3=90,5=0.000000
L 4.37980059 -0.93875128 4.3826 -0.92875108 0 P 0 ;1,3=90,5=0.000000
L 4.3826 -0.92875108 4.38353317 -0.91750118 0 P 0 ;1,3=90,5=0.000000
L 4.38353317 -0.91750118 4.3826 -0.90625128 0 P 0 ;1,3=90,5=0.000000
L 4.3826 -0.90625128 4.37980059 -0.89624882 0 P 0 ;1,3=90,5=0.000000
L 4.37980059 -0.89624882 4.37606644 -0.88875049 0 P 0 ;1,3=90,5=0.000000
L 4.37606644 -0.88875049 4.37046585 -0.88249951 0 P 0 ;1,3=90,5=0.000000
L 4.37046585 -0.88249951 4.36299911 -0.88 0 P 0 ;1,3=90,5=0.000000
L 4.43799911 -0.88 4.43053228 -0.88249951 0 P 0 ;1,3=90,5=0.000000
L 4.43053228 -0.88249951 4.42493346 -0.88875049 0 P 0 ;1,3=90,5=0.000000
L 4.42493346 -0.88875049 4.42119931 -0.89624882 0 P 0 ;1,3=90,5=0.000000
L 4.42119931 -0.89624882 4.4183999 -0.90625128 0 P 0 ;1,3=90,5=0.000000
L 4.4183999 -0.90625128 4.41746673 -0.91750118 0 P 0 ;1,3=90,5=0.000000
L 4.41746673 -0.91750118 4.4183999 -0.92875108 0 P 0 ;1,3=90,5=0.000000
L 4.4183999 -0.92875108 4.42119931 -0.93875128 0 P 0 ;1,3=90,5=0.000000
L 4.42119931 -0.93875128 4.42493346 -0.94625187 0 P 0 ;1,3=90,5=0.000000
L 4.42493346 -0.94625187 4.43053228 -0.95250059 0 P 0 ;1,3=90,5=0.000000
L 4.43053228 -0.95250059 4.43799911 -0.955 0 P 0 ;1,3=90,5=0.000000
L 4.43799911 -0.955 4.44546585 -0.95250059 0 P 0 ;1,3=90,5=0.000000
L 4.44546585 -0.95250059 4.45106644 -0.94625187 0 P 0 ;1,3=90,5=0.000000
L 4.45106644 -0.94625187 4.45480059 -0.93875128 0 P 0 ;1,3=90,5=0.000000
L 4.45480059 -0.93875128 4.4576 -0.92875108 0 P 0 ;1,3=90,5=0.000000
L 4.4576 -0.92875108 4.45853317 -0.91750118 0 P 0 ;1,3=90,5=0.000000
L 4.45853317 -0.91750118 4.4576 -0.90625128 0 P 0 ;1,3=90,5=0.000000
L 4.4576 -0.90625128 4.45480059 -0.89624882 0 P 0 ;1,3=90,5=0.000000
L 4.45480059 -0.89624882 4.45106644 -0.88875049 0 P 0 ;1,3=90,5=0.000000
L 4.45106644 -0.88875049 4.44546585 -0.88249951 0 P 0 ;1,3=90,5=0.000000
L 4.44546585 -0.88249951 4.43799911 -0.88 0 P 0 ;1,3=90,5=0.000000
L 4.51299911 -0.88 4.50553228 -0.88249951 0 P 0 ;1,3=90,5=0.000000
L 4.50553228 -0.88249951 4.49993346 -0.88875049 0 P 0 ;1,3=90,5=0.000000
L 4.49993346 -0.88875049 4.49619931 -0.89624882 0 P 0 ;1,3=90,5=0.000000
L 4.49619931 -0.89624882 4.4933999 -0.90625128 0 P 0 ;1,3=90,5=0.000000
L 4.4933999 -0.90625128 4.49246673 -0.91750118 0 P 0 ;1,3=90,5=0.000000
L 4.49246673 -0.91750118 4.4933999 -0.92875108 0 P 0 ;1,3=90,5=0.000000
L 4.4933999 -0.92875108 4.49619931 -0.93875128 0 P 0 ;1,3=90,5=0.000000
L 4.49619931 -0.93875128 4.49993346 -0.94625187 0 P 0 ;1,3=90,5=0.000000
L 4.49993346 -0.94625187 4.50553228 -0.95250059 0 P 0 ;1,3=90,5=0.000000
L 4.50553228 -0.95250059 4.51299911 -0.955 0 P 0 ;1,3=90,5=0.000000
L 4.51299911 -0.955 4.52046585 -0.95250059 0 P 0 ;1,3=90,5=0.000000
L 4.52046585 -0.95250059 4.52606644 -0.94625187 0 P 0 ;1,3=90,5=0.000000
L 4.52606644 -0.94625187 4.52980059 -0.93875128 0 P 0 ;1,3=90,5=0.000000
L 4.52980059 -0.93875128 4.5326 -0.92875108 0 P 0 ;1,3=90,5=0.000000
L 4.5326 -0.92875108 4.53353317 -0.91750118 0 P 0 ;1,3=90,5=0.000000
L 4.53353317 -0.91750118 4.5326 -0.90625128 0 P 0 ;1,3=90,5=0.000000
L 4.5326 -0.90625128 4.52980059 -0.89624882 0 P 0 ;1,3=90,5=0.000000
L 4.52980059 -0.89624882 4.52606644 -0.88875049 0 P 0 ;1,3=90,5=0.000000
L 4.52606644 -0.88875049 4.52046585 -0.88249951 0 P 0 ;1,3=90,5=0.000000
L 4.52046585 -0.88249951 4.51299911 -0.88 0 P 0 ;1,3=90,5=0.000000
L 4.58799911 -0.955 4.58799911 -0.88 0 P 0 ;1,3=90,5=0.000000
L 4.58799911 -0.88 4.5767998 -0.89499911 0 P 0 ;1,3=90,5=0.000000
L 4.5767998 -0.955 4.59919843 -0.955 0 P 0 ;1,3=90,5=0.000000
L 4.65086663 -0.93000079 4.67513327 -0.93000079 0 P 0 ;1,3=90,5=0.000000
L 4.73799911 -0.88 4.73053228 -0.88249951 0 P 0 ;1,3=90,5=0.000000
L 4.73053228 -0.88249951 4.72493346 -0.88875049 0 P 0 ;1,3=90,5=0.000000
L 4.72493346 -0.88875049 4.72119931 -0.89624882 0 P 0 ;1,3=90,5=0.000000
L 4.72119931 -0.89624882 4.7183999 -0.90625128 0 P 0 ;1,3=90,5=0.000000
L 4.7183999 -0.90625128 4.71746673 -0.91750118 0 P 0 ;1,3=90,5=0.000000
L 4.71746673 -0.91750118 4.7183999 -0.92875108 0 P 0 ;1,3=90,5=0.000000
L 4.7183999 -0.92875108 4.72119931 -0.93875128 0 P 0 ;1,3=90,5=0.000000
L 4.72119931 -0.93875128 4.72493346 -0.94625187 0 P 0 ;1,3=90,5=0.000000
L 4.72493346 -0.94625187 4.73053228 -0.95250059 0 P 0 ;1,3=90,5=0.000000
L 4.73053228 -0.95250059 4.73799911 -0.955 0 P 0 ;1,3=90,5=0.000000
L 4.73799911 -0.955 4.74546585 -0.95250059 0 P 0 ;1,3=90,5=0.000000
L 4.74546585 -0.95250059 4.75106644 -0.94625187 0 P 0 ;1,3=90,5=0.000000
L 4.75106644 -0.94625187 4.75480059 -0.93875128 0 P 0 ;1,3=90,5=0.000000
L 4.75480059 -0.93875128 4.7576 -0.92875108 0 P 0 ;1,3=90,5=0.000000
L 4.7576 -0.92875108 4.75853317 -0.91750118 0 P 0 ;1,3=90,5=0.000000
L 4.75853317 -0.91750118 4.7576 -0.90625128 0 P 0 ;1,3=90,5=0.000000
L 4.7576 -0.90625128 4.75480059 -0.89624882 0 P 0 ;1,3=90,5=0.000000
L 4.75480059 -0.89624882 4.75106644 -0.88875049 0 P 0 ;1,3=90,5=0.000000
L 4.75106644 -0.88875049 4.74546585 -0.88249951 0 P 0 ;1,3=90,5=0.000000
L 4.74546585 -0.88249951 4.73799911 -0.88 0 P 0 ;1,3=90,5=0.000000
L 4.79526614 -0.8924997 4.80086663 -0.88500128 0 P 0 ;1,3=90,5=0.000000
L 4.80086663 -0.88500128 4.8074003 -0.8812498 0 P 0 ;1,3=90,5=0.000000
L 4.8074003 -0.8812498 4.81486703 -0.88 0 P 0 ;1,3=90,5=0.000000
L 4.81486703 -0.88 4.8242001 -0.88249951 0 P 0 ;1,3=90,5=0.000000
L 4.8242001 -0.88249951 4.83073376 -0.88875049 0 P 0 ;1,3=90,5=0.000000
L 4.83073376 -0.88875049 4.8326 -0.89624882 0 P 0 ;1,3=90,5=0.000000
L 4.8326 -0.89624882 4.83166693 -0.90375187 0 P 0 ;1,3=90,5=0.000000
L 4.83166693 -0.90375187 4.82793268 -0.91000049 0 P 0 ;1,3=90,5=0.000000
L 4.82793268 -0.91000049 4.80926654 -0.9225001 0 P 0 ;1,3=90,5=0.000000
L 4.80926654 -0.9225001 4.80086663 -0.93125059 0 P 0 ;1,3=90,5=0.000000
L 4.80086663 -0.93125059 4.79526614 -0.94375246 0 P 0 ;1,3=90,5=0.000000
L 4.79526614 -0.94375246 4.7933999 -0.955 0 P 0 ;1,3=90,5=0.000000
L 4.7933999 -0.955 4.8326 -0.955 0 P 0 ;1,3=90,5=0.000000
L 3.36746673 -1.205 3.36746673 -1.13 0 P 0 ;1,3=91,5=0.000000
L 3.36746673 -1.13 3.38613287 -1.13 0 P 0 ;1,3=91,5=0.000000
L 3.38613287 -1.13 3.39359961 -1.13375157 0 P 0 ;1,3=91,5=0.000000
L 3.39359961 -1.13375157 3.3992001 -1.13875049 0 P 0 ;1,3=91,5=0.000000
L 3.3992001 -1.13875049 3.40386752 -1.14624882 0 P 0 ;1,3=91,5=0.000000
L 3.40386752 -1.14624882 3.4076 -1.15500157 0 P 0 ;1,3=91,5=0.000000
L 3.4076 -1.15500157 3.40853317 -1.16750118 0 P 0 ;1,3=91,5=0.000000
L 3.40853317 -1.16750118 3.4076 -1.18000079 0 P 0 ;1,3=91,5=0.000000
L 3.4076 -1.18000079 3.40386752 -1.18875128 0 P 0 ;1,3=91,5=0.000000
L 3.40386752 -1.18875128 3.3992001 -1.19625187 0 P 0 ;1,3=91,5=0.000000
L 3.3992001 -1.19625187 3.39359961 -1.20125089 0 P 0 ;1,3=91,5=0.000000
L 3.39359961 -1.20125089 3.38613287 -1.205 0 P 0 ;1,3=91,5=0.000000
L 3.38613287 -1.205 3.36746673 -1.205 0 P 0 ;1,3=91,5=0.000000
L 3.47980059 -1.205 3.47980059 -1.15500157 0 P 0 ;1,3=91,5=0.000000
L 3.47980059 -1.1637497 3.47606644 -1.15875079 0 P 0 ;1,3=91,5=0.000000
L 3.47606644 -1.15875079 3.47046585 -1.15625128 0 P 0 ;1,3=91,5=0.000000
L 3.47046585 -1.15625128 3.46393396 -1.15500157 0 P 0 ;1,3=91,5=0.000000
L 3.46393396 -1.15500157 3.4574003 -1.15750108 0 P 0 ;1,3=91,5=0.000000
L 3.4574003 -1.15750108 3.4517998 -1.1625 0 P 0 ;1,3=91,5=0.000000
L 3.4517998 -1.1625 3.44806555 -1.17000069 0 P 0 ;1,3=91,5=0.000000
L 3.44806555 -1.17000069 3.44619931 -1.18000079 0 P 0 ;1,3=91,5=0.000000
L 3.44619931 -1.18000079 3.44806555 -1.19000098 0 P 0 ;1,3=91,5=0.000000
L 3.44806555 -1.19000098 3.4517998 -1.19750167 0 P 0 ;1,3=91,5=0.000000
L 3.4517998 -1.19750167 3.4574003 -1.20250059 0 P 0 ;1,3=91,5=0.000000
L 3.4574003 -1.20250059 3.46393396 -1.205 0 P 0 ;1,3=91,5=0.000000
L 3.46393396 -1.205 3.47046585 -1.2037503 0 P 0 ;1,3=91,5=0.000000
L 3.47046585 -1.2037503 3.47606644 -1.20000108 0 P 0 ;1,3=91,5=0.000000
L 3.47606644 -1.20000108 3.47980059 -1.19500217 0 P 0 ;1,3=91,5=0.000000
L 3.53799911 -1.13 3.53799911 -1.205 0 P 0 ;1,3=91,5=0.000000
L 3.52493346 -1.15500157 3.55106644 -1.15500157 0 P 0 ;1,3=91,5=0.000000
L 3.59900039 -1.17125039 3.62886752 -1.17125039 0 P 0 ;1,3=91,5=0.000000
L 3.62886752 -1.17125039 3.62606644 -1.1625 0 P 0 ;1,3=91,5=0.000000
L 3.62606644 -1.1625 3.62140069 -1.15750108 0 P 0 ;1,3=91,5=0.000000
L 3.62140069 -1.15750108 3.61486703 -1.15500157 0 P 0 ;1,3=91,5=0.000000
L 3.61486703 -1.15500157 3.60833346 -1.15625128 0 P 0 ;1,3=91,5=0.000000
L 3.60833346 -1.15625128 3.60273287 -1.16000049 0 P 0 ;1,3=91,5=0.000000
L 3.60273287 -1.16000049 3.59900039 -1.16875089 0 P 0 ;1,3=91,5=0.000000
L 3.59900039 -1.16875089 3.59713238 -1.17625157 0 P 0 ;1,3=91,5=0.000000
L 3.59713238 -1.17625157 3.59713238 -1.18375 0 P 0 ;1,3=91,5=0.000000
L 3.59713238 -1.18375 3.59900039 -1.19125069 0 P 0 ;1,3=91,5=0.000000
L 3.59900039 -1.19125069 3.60366604 -1.19875138 0 P 0 ;1,3=91,5=0.000000
L 3.60366604 -1.19875138 3.60926654 -1.2037503 0 P 0 ;1,3=91,5=0.000000
L 3.60926654 -1.2037503 3.6158002 -1.205 0 P 0 ;1,3=91,5=0.000000
L 3.6158002 -1.205 3.62233386 -1.20250059 0 P 0 ;1,3=91,5=0.000000
L 3.62233386 -1.20250059 3.62886752 -1.19500217 0 P 0 ;1,3=91,5=0.000000
L 3.68799911 -1.20749941 3.68613287 -1.2062497 0 P 0 ;1,3=91,5=0.000000
L 3.68613287 -1.2062497 3.68613287 -1.2037503 0 P 0 ;1,3=91,5=0.000000
L 3.68613287 -1.2037503 3.68799911 -1.20250059 0 P 0 ;1,3=91,5=0.000000
L 3.68799911 -1.20250059 3.68986703 -1.2037503 0 P 0 ;1,3=91,5=0.000000
L 3.68986703 -1.2037503 3.68986703 -1.2062497 0 P 0 ;1,3=91,5=0.000000
L 3.68986703 -1.2062497 3.68799911 -1.20749941 0 P 0 ;1,3=91,5=0.000000
L 3.68799911 -1.17375217 3.68613287 -1.1725001 0 P 0 ;1,3=91,5=0.000000
L 3.68613287 -1.1725001 3.68613287 -1.17000069 0 P 0 ;1,3=91,5=0.000000
L 3.68613287 -1.17000069 3.68799911 -1.16875089 0 P 0 ;1,3=91,5=0.000000
L 3.68799911 -1.16875089 3.68986703 -1.17000069 0 P 0 ;1,3=91,5=0.000000
L 3.68986703 -1.17000069 3.68986703 -1.1725001 0 P 0 ;1,3=91,5=0.000000
L 3.68986703 -1.1725001 3.68799911 -1.17375217 0 P 0 ;1,3=91,5=0.000000
L 3.82026614 -1.1424997 3.82586663 -1.13500128 0 P 0 ;1,3=91,5=0.000000
L 3.82586663 -1.13500128 3.8324003 -1.1312498 0 P 0 ;1,3=91,5=0.000000
L 3.8324003 -1.1312498 3.83986703 -1.13 0 P 0 ;1,3=91,5=0.000000
L 3.83986703 -1.13 3.8492001 -1.13249951 0 P 0 ;1,3=91,5=0.000000
L 3.8492001 -1.13249951 3.85573376 -1.13875049 0 P 0 ;1,3=91,5=0.000000
L 3.85573376 -1.13875049 3.8576 -1.14624882 0 P 0 ;1,3=91,5=0.000000
L 3.8576 -1.14624882 3.85666693 -1.15375187 0 P 0 ;1,3=91,5=0.000000
L 3.85666693 -1.15375187 3.85293268 -1.16000049 0 P 0 ;1,3=91,5=0.000000
L 3.85293268 -1.16000049 3.83426654 -1.1725001 0 P 0 ;1,3=91,5=0.000000
L 3.83426654 -1.1725001 3.82586663 -1.18125059 0 P 0 ;1,3=91,5=0.000000
L 3.82586663 -1.18125059 3.82026614 -1.19375246 0 P 0 ;1,3=91,5=0.000000
L 3.82026614 -1.19375246 3.8183999 -1.205 0 P 0 ;1,3=91,5=0.000000
L 3.8183999 -1.205 3.8576 -1.205 0 P 0 ;1,3=91,5=0.000000
L 3.91299911 -1.13 3.90553228 -1.13249951 0 P 0 ;1,3=91,5=0.000000
L 3.90553228 -1.13249951 3.89993346 -1.13875049 0 P 0 ;1,3=91,5=0.000000
L 3.89993346 -1.13875049 3.89619931 -1.14624882 0 P 0 ;1,3=91,5=0.000000
L 3.89619931 -1.14624882 3.8933999 -1.15625128 0 P 0 ;1,3=91,5=0.000000
L 3.8933999 -1.15625128 3.89246673 -1.16750118 0 P 0 ;1,3=91,5=0.000000
L 3.89246673 -1.16750118 3.8933999 -1.17875108 0 P 0 ;1,3=91,5=0.000000
L 3.8933999 -1.17875108 3.89619931 -1.18875128 0 P 0 ;1,3=91,5=0.000000
L 3.89619931 -1.18875128 3.89993346 -1.19625187 0 P 0 ;1,3=91,5=0.000000
L 3.89993346 -1.19625187 3.90553228 -1.20250059 0 P 0 ;1,3=91,5=0.000000
L 3.90553228 -1.20250059 3.91299911 -1.205 0 P 0 ;1,3=91,5=0.000000
L 3.91299911 -1.205 3.92046585 -1.20250059 0 P 0 ;1,3=91,5=0.000000
L 3.92046585 -1.20250059 3.92606644 -1.19625187 0 P 0 ;1,3=91,5=0.000000
L 3.92606644 -1.19625187 3.92980059 -1.18875128 0 P 0 ;1,3=91,5=0.000000
L 3.92980059 -1.18875128 3.9326 -1.17875108 0 P 0 ;1,3=91,5=0.000000
L 3.9326 -1.17875108 3.93353317 -1.16750118 0 P 0 ;1,3=91,5=0.000000
L 3.93353317 -1.16750118 3.9326 -1.15625128 0 P 0 ;1,3=91,5=0.000000
L 3.9326 -1.15625128 3.92980059 -1.14624882 0 P 0 ;1,3=91,5=0.000000
L 3.92980059 -1.14624882 3.92606644 -1.13875049 0 P 0 ;1,3=91,5=0.000000
L 3.92606644 -1.13875049 3.92046585 -1.13249951 0 P 0 ;1,3=91,5=0.000000
L 3.92046585 -1.13249951 3.91299911 -1.13 0 P 0 ;1,3=91,5=0.000000
L 3.97026614 -1.1424997 3.97586663 -1.13500128 0 P 0 ;1,3=91,5=0.000000
L 3.97586663 -1.13500128 3.9824003 -1.1312498 0 P 0 ;1,3=91,5=0.000000
L 3.9824003 -1.1312498 3.98986703 -1.13 0 P 0 ;1,3=91,5=0.000000
L 3.98986703 -1.13 3.9992001 -1.13249951 0 P 0 ;1,3=91,5=0.000000
L 3.9992001 -1.13249951 4.00573376 -1.13875049 0 P 0 ;1,3=91,5=0.000000
L 4.00573376 -1.13875049 4.0076 -1.14624882 0 P 0 ;1,3=91,5=0.000000
L 4.0076 -1.14624882 4.00666693 -1.15375187 0 P 0 ;1,3=91,5=0.000000
L 4.00666693 -1.15375187 4.00293268 -1.16000049 0 P 0 ;1,3=91,5=0.000000
L 4.00293268 -1.16000049 3.98426654 -1.1725001 0 P 0 ;1,3=91,5=0.000000
L 3.98426654 -1.1725001 3.97586663 -1.18125059 0 P 0 ;1,3=91,5=0.000000
L 3.97586663 -1.18125059 3.97026614 -1.19375246 0 P 0 ;1,3=91,5=0.000000
L 3.97026614 -1.19375246 3.9683999 -1.205 0 P 0 ;1,3=91,5=0.000000
L 3.9683999 -1.205 4.0076 -1.205 0 P 0 ;1,3=91,5=0.000000
L 4.04526614 -1.1424997 4.05086663 -1.13500128 0 P 0 ;1,3=91,5=0.000000
L 4.05086663 -1.13500128 4.0574003 -1.1312498 0 P 0 ;1,3=91,5=0.000000
L 4.0574003 -1.1312498 4.06486703 -1.13 0 P 0 ;1,3=91,5=0.000000
L 4.06486703 -1.13 4.0742001 -1.13249951 0 P 0 ;1,3=91,5=0.000000
L 4.0742001 -1.13249951 4.08073376 -1.13875049 0 P 0 ;1,3=91,5=0.000000
L 4.08073376 -1.13875049 4.0826 -1.14624882 0 P 0 ;1,3=91,5=0.000000
L 4.0826 -1.14624882 4.08166693 -1.15375187 0 P 0 ;1,3=91,5=0.000000
L 4.08166693 -1.15375187 4.07793268 -1.16000049 0 P 0 ;1,3=91,5=0.000000
L 4.07793268 -1.16000049 4.05926654 -1.1725001 0 P 0 ;1,3=91,5=0.000000
L 4.05926654 -1.1725001 4.05086663 -1.18125059 0 P 0 ;1,3=91,5=0.000000
L 4.05086663 -1.18125059 4.04526614 -1.19375246 0 P 0 ;1,3=91,5=0.000000
L 4.04526614 -1.19375246 4.0433999 -1.205 0 P 0 ;1,3=91,5=0.000000
L 4.0433999 -1.205 4.0826 -1.205 0 P 0 ;1,3=91,5=0.000000
L 4.12586663 -1.18000079 4.15013327 -1.18000079 0 P 0 ;1,3=91,5=0.000000
L 4.21299911 -1.13 4.20553228 -1.13249951 0 P 0 ;1,3=91,5=0.000000
L 4.20553228 -1.13249951 4.19993346 -1.13875049 0 P 0 ;1,3=91,5=0.000000
L 4.19993346 -1.13875049 4.19619931 -1.14624882 0 P 0 ;1,3=91,5=0.000000
L 4.19619931 -1.14624882 4.1933999 -1.15625128 0 P 0 ;1,3=91,5=0.000000
L 4.1933999 -1.15625128 4.19246673 -1.16750118 0 P 0 ;1,3=91,5=0.000000
L 4.19246673 -1.16750118 4.1933999 -1.17875108 0 P 0 ;1,3=91,5=0.000000
L 4.1933999 -1.17875108 4.19619931 -1.18875128 0 P 0 ;1,3=91,5=0.000000
L 4.19619931 -1.18875128 4.19993346 -1.19625187 0 P 0 ;1,3=91,5=0.000000
L 4.19993346 -1.19625187 4.20553228 -1.20250059 0 P 0 ;1,3=91,5=0.000000
L 4.20553228 -1.20250059 4.21299911 -1.205 0 P 0 ;1,3=91,5=0.000000
L 4.21299911 -1.205 4.22046585 -1.20250059 0 P 0 ;1,3=91,5=0.000000
L 4.22046585 -1.20250059 4.22606644 -1.19625187 0 P 0 ;1,3=91,5=0.000000
L 4.22606644 -1.19625187 4.22980059 -1.18875128 0 P 0 ;1,3=91,5=0.000000
L 4.22980059 -1.18875128 4.2326 -1.17875108 0 P 0 ;1,3=91,5=0.000000
L 4.2326 -1.17875108 4.23353317 -1.16750118 0 P 0 ;1,3=91,5=0.000000
L 4.23353317 -1.16750118 4.2326 -1.15625128 0 P 0 ;1,3=91,5=0.000000
L 4.2326 -1.15625128 4.22980059 -1.14624882 0 P 0 ;1,3=91,5=0.000000
L 4.22980059 -1.14624882 4.22606644 -1.13875049 0 P 0 ;1,3=91,5=0.000000
L 4.22606644 -1.13875049 4.22046585 -1.13249951 0 P 0 ;1,3=91,5=0.000000
L 4.22046585 -1.13249951 4.21299911 -1.13 0 P 0 ;1,3=91,5=0.000000
L 4.27026614 -1.1424997 4.27586663 -1.13500128 0 P 0 ;1,3=91,5=0.000000
L 4.27586663 -1.13500128 4.2824003 -1.1312498 0 P 0 ;1,3=91,5=0.000000
L 4.2824003 -1.1312498 4.28986703 -1.13 0 P 0 ;1,3=91,5=0.000000
L 4.28986703 -1.13 4.2992001 -1.13249951 0 P 0 ;1,3=91,5=0.000000
L 4.2992001 -1.13249951 4.30573376 -1.13875049 0 P 0 ;1,3=91,5=0.000000
L 4.30573376 -1.13875049 4.3076 -1.14624882 0 P 0 ;1,3=91,5=0.000000
L 4.3076 -1.14624882 4.30666693 -1.15375187 0 P 0 ;1,3=91,5=0.000000
L 4.30666693 -1.15375187 4.30293268 -1.16000049 0 P 0 ;1,3=91,5=0.000000
L 4.30293268 -1.16000049 4.28426654 -1.1725001 0 P 0 ;1,3=91,5=0.000000
L 4.28426654 -1.1725001 4.27586663 -1.18125059 0 P 0 ;1,3=91,5=0.000000
L 4.27586663 -1.18125059 4.27026614 -1.19375246 0 P 0 ;1,3=91,5=0.000000
L 4.27026614 -1.19375246 4.2683999 -1.205 0 P 0 ;1,3=91,5=0.000000
L 4.2683999 -1.205 4.3076 -1.205 0 P 0 ;1,3=91,5=0.000000
L 4.35086663 -1.18000079 4.37513327 -1.18000079 0 P 0 ;1,3=91,5=0.000000
L 4.42026614 -1.1424997 4.42586663 -1.13500128 0 P 0 ;1,3=91,5=0.000000
L 4.42586663 -1.13500128 4.4324003 -1.1312498 0 P 0 ;1,3=91,5=0.000000
L 4.4324003 -1.1312498 4.43986703 -1.13 0 P 0 ;1,3=91,5=0.000000
L 4.43986703 -1.13 4.4492001 -1.13249951 0 P 0 ;1,3=91,5=0.000000
L 4.4492001 -1.13249951 4.45573376 -1.13875049 0 P 0 ;1,3=91,5=0.000000
L 4.45573376 -1.13875049 4.4576 -1.14624882 0 P 0 ;1,3=91,5=0.000000
L 4.4576 -1.14624882 4.45666693 -1.15375187 0 P 0 ;1,3=91,5=0.000000
L 4.45666693 -1.15375187 4.45293268 -1.16000049 0 P 0 ;1,3=91,5=0.000000
L 4.45293268 -1.16000049 4.43426654 -1.1725001 0 P 0 ;1,3=91,5=0.000000
L 4.43426654 -1.1725001 4.42586663 -1.18125059 0 P 0 ;1,3=91,5=0.000000
L 4.42586663 -1.18125059 4.42026614 -1.19375246 0 P 0 ;1,3=91,5=0.000000
L 4.42026614 -1.19375246 4.4183999 -1.205 0 P 0 ;1,3=91,5=0.000000
L 4.4183999 -1.205 4.4576 -1.205 0 P 0 ;1,3=91,5=0.000000
L 4.49246673 -1.19375246 4.49806555 -1.20000108 0 P 0 ;1,3=91,5=0.000000
L 4.49806555 -1.20000108 4.50459921 -1.2037503 0 P 0 ;1,3=91,5=0.000000
L 4.50459921 -1.2037503 4.51299911 -1.205 0 P 0 ;1,3=91,5=0.000000
L 4.51299911 -1.205 4.52140069 -1.20250059 0 P 0 ;1,3=91,5=0.000000
L 4.52140069 -1.20250059 4.52793268 -1.19750167 0 P 0 ;1,3=91,5=0.000000
L 4.52793268 -1.19750167 4.5326 -1.18875128 0 P 0 ;1,3=91,5=0.000000
L 4.5326 -1.18875128 4.53353317 -1.17875108 0 P 0 ;1,3=91,5=0.000000
L 4.53353317 -1.17875108 4.53166693 -1.16875089 0 P 0 ;1,3=91,5=0.000000
L 4.53166693 -1.16875089 4.52699951 -1.1625 0 P 0 ;1,3=91,5=0.000000
L 4.52699951 -1.1625 4.52046585 -1.15750108 0 P 0 ;1,3=91,5=0.000000
L 4.52046585 -1.15750108 4.51393396 -1.15625128 0 P 0 ;1,3=91,5=0.000000
L 4.51393396 -1.15625128 4.5074003 -1.15750108 0 P 0 ;1,3=91,5=0.000000
L 4.5074003 -1.15750108 4.49900039 -1.1625 0 P 0 ;1,3=91,5=0.000000
L 4.49900039 -1.1625 4.5017998 -1.13 0 P 0 ;1,3=91,5=0.000000
L 4.5017998 -1.13 4.52699951 -1.13 0 P 0 ;1,3=91,5=0.000000
L 3.29433297 -1.255 3.29433297 -1.33 0 P 0 ;1,3=92,5=0.000000
L 3.29433297 -1.33 3.33166693 -1.33 0 P 0 ;1,3=92,5=0.000000
L 3.40480059 -1.33 3.40480059 -1.28000157 0 P 0 ;1,3=92,5=0.000000
L 3.40480059 -1.2887497 3.40106644 -1.28375079 0 P 0 ;1,3=92,5=0.000000
L 3.40106644 -1.28375079 3.39546585 -1.28125128 0 P 0 ;1,3=92,5=0.000000
L 3.39546585 -1.28125128 3.38893396 -1.28000157 0 P 0 ;1,3=92,5=0.000000
L 3.38893396 -1.28000157 3.3824003 -1.28250108 0 P 0 ;1,3=92,5=0.000000
L 3.3824003 -1.28250108 3.3767998 -1.2875 0 P 0 ;1,3=92,5=0.000000
L 3.3767998 -1.2875 3.37306555 -1.29500069 0 P 0 ;1,3=92,5=0.000000
L 3.37306555 -1.29500069 3.37119931 -1.30500079 0 P 0 ;1,3=92,5=0.000000
L 3.37119931 -1.30500079 3.37306555 -1.31500098 0 P 0 ;1,3=92,5=0.000000
L 3.37306555 -1.31500098 3.3767998 -1.32250167 0 P 0 ;1,3=92,5=0.000000
L 3.3767998 -1.32250167 3.3824003 -1.32750059 0 P 0 ;1,3=92,5=0.000000
L 3.3824003 -1.32750059 3.38893396 -1.33 0 P 0 ;1,3=92,5=0.000000
L 3.38893396 -1.33 3.39546585 -1.3287503 0 P 0 ;1,3=92,5=0.000000
L 3.39546585 -1.3287503 3.40106644 -1.32500108 0 P 0 ;1,3=92,5=0.000000
L 3.40106644 -1.32500108 3.40480059 -1.32000217 0 P 0 ;1,3=92,5=0.000000
L 3.4433999 -1.3524997 3.44900039 -1.35499921 0 P 0 ;1,3=92,5=0.000000
L 3.44900039 -1.35499921 3.45646713 -1.3524997 0 P 0 ;1,3=92,5=0.000000
L 3.45646713 -1.3524997 3.46113287 -1.34750079 0 P 0 ;1,3=92,5=0.000000
L 3.46113287 -1.34750079 3.46486703 -1.3412498 0 P 0 ;1,3=92,5=0.000000
L 3.46486703 -1.3412498 3.47046585 -1.32125187 0 P 0 ;1,3=92,5=0.000000
L 3.47046585 -1.32125187 3.4826 -1.28000157 0 P 0 ;1,3=92,5=0.000000
L 3.45273287 -1.28000157 3.47046585 -1.32125187 0 P 0 ;1,3=92,5=0.000000
L 3.52400039 -1.29625039 3.55386752 -1.29625039 0 P 0 ;1,3=92,5=0.000000
L 3.55386752 -1.29625039 3.55106644 -1.2875 0 P 0 ;1,3=92,5=0.000000
L 3.55106644 -1.2875 3.54640069 -1.28250108 0 P 0 ;1,3=92,5=0.000000
L 3.54640069 -1.28250108 3.53986703 -1.28000157 0 P 0 ;1,3=92,5=0.000000
L 3.53986703 -1.28000157 3.53333346 -1.28125128 0 P 0 ;1,3=92,5=0.000000
L 3.53333346 -1.28125128 3.52773287 -1.28500049 0 P 0 ;1,3=92,5=0.000000
L 3.52773287 -1.28500049 3.52400039 -1.29375089 0 P 0 ;1,3=92,5=0.000000
L 3.52400039 -1.29375089 3.52213238 -1.30125157 0 P 0 ;1,3=92,5=0.000000
L 3.52213238 -1.30125157 3.52213238 -1.30875 0 P 0 ;1,3=92,5=0.000000
L 3.52213238 -1.30875 3.52400039 -1.31625069 0 P 0 ;1,3=92,5=0.000000
L 3.52400039 -1.31625069 3.52866604 -1.32375138 0 P 0 ;1,3=92,5=0.000000
L 3.52866604 -1.32375138 3.53426654 -1.3287503 0 P 0 ;1,3=92,5=0.000000
L 3.53426654 -1.3287503 3.5408002 -1.33 0 P 0 ;1,3=92,5=0.000000
L 3.5408002 -1.33 3.54733386 -1.32750059 0 P 0 ;1,3=92,5=0.000000
L 3.54733386 -1.32750059 3.55386752 -1.32000217 0 P 0 ;1,3=92,5=0.000000
L 3.59993346 -1.33 3.59993346 -1.28000157 0 P 0 ;1,3=92,5=0.000000
L 3.59993346 -1.28999941 3.60459921 -1.28500049 0 P 0 ;1,3=92,5=0.000000
L 3.60459921 -1.28500049 3.60926654 -1.28125128 0 P 0 ;1,3=92,5=0.000000
L 3.60926654 -1.28125128 3.6158002 -1.28000157 0 P 0 ;1,3=92,5=0.000000
L 3.6158002 -1.28000157 3.62046585 -1.28125128 0 P 0 ;1,3=92,5=0.000000
L 3.62046585 -1.28125128 3.62606644 -1.28500049 0 P 0 ;1,3=92,5=0.000000
L 3.68799911 -1.33249941 3.68613287 -1.3312497 0 P 0 ;1,3=92,5=0.000000
L 3.68613287 -1.3312497 3.68613287 -1.3287503 0 P 0 ;1,3=92,5=0.000000
L 3.68613287 -1.3287503 3.68799911 -1.32750059 0 P 0 ;1,3=92,5=0.000000
L 3.68799911 -1.32750059 3.68986703 -1.3287503 0 P 0 ;1,3=92,5=0.000000
L 3.68986703 -1.3287503 3.68986703 -1.3312497 0 P 0 ;1,3=92,5=0.000000
L 3.68986703 -1.3312497 3.68799911 -1.33249941 0 P 0 ;1,3=92,5=0.000000
L 3.68799911 -1.29875217 3.68613287 -1.2975001 0 P 0 ;1,3=92,5=0.000000
L 3.68613287 -1.2975001 3.68613287 -1.29500069 0 P 0 ;1,3=92,5=0.000000
L 3.68613287 -1.29500069 3.68799911 -1.29375089 0 P 0 ;1,3=92,5=0.000000
L 3.68799911 -1.29375089 3.68986703 -1.29500069 0 P 0 ;1,3=92,5=0.000000
L 3.68986703 -1.29500069 3.68986703 -1.2975001 0 P 0 ;1,3=92,5=0.000000
L 3.68986703 -1.2975001 3.68799911 -1.29875217 0 P 0 ;1,3=92,5=0.000000
L 3.36933297 -1.08 3.36933297 -1.005 0 P 0 ;1,3=93,5=0.000000
L 3.36933297 -1.005 3.39266644 -1.005 0 P 0 ;1,3=93,5=0.000000
L 3.39266644 -1.005 3.40013327 -1.00875157 0 P 0 ;1,3=93,5=0.000000
L 3.40013327 -1.00875157 3.40480059 -1.01375049 0 P 0 ;1,3=93,5=0.000000
L 3.40480059 -1.01375049 3.40666693 -1.02375059 0 P 0 ;1,3=93,5=0.000000
L 3.40666693 -1.02375059 3.40480059 -1.03375079 0 P 0 ;1,3=93,5=0.000000
L 3.40480059 -1.03375079 3.3992001 -1.03999941 0 P 0 ;1,3=93,5=0.000000
L 3.3992001 -1.03999941 3.39266644 -1.04375089 0 P 0 ;1,3=93,5=0.000000
L 3.39266644 -1.04375089 3.36933297 -1.04375089 0 P 0 ;1,3=93,5=0.000000
L 3.39266644 -1.04375089 3.40666693 -1.08 0 P 0 ;1,3=93,5=0.000000
L 3.44900039 -1.04625039 3.47886752 -1.04625039 0 P 0 ;1,3=93,5=0.000000
L 3.47886752 -1.04625039 3.47606644 -1.0375 0 P 0 ;1,3=93,5=0.000000
L 3.47606644 -1.0375 3.47140069 -1.03250108 0 P 0 ;1,3=93,5=0.000000
L 3.47140069 -1.03250108 3.46486703 -1.03000157 0 P 0 ;1,3=93,5=0.000000
L 3.46486703 -1.03000157 3.45833346 -1.03125128 0 P 0 ;1,3=93,5=0.000000
L 3.45833346 -1.03125128 3.45273287 -1.03500049 0 P 0 ;1,3=93,5=0.000000
L 3.45273287 -1.03500049 3.44900039 -1.04375089 0 P 0 ;1,3=93,5=0.000000
L 3.44900039 -1.04375089 3.44713238 -1.05125157 0 P 0 ;1,3=93,5=0.000000
L 3.44713238 -1.05125157 3.44713238 -1.05875 0 P 0 ;1,3=93,5=0.000000
L 3.44713238 -1.05875 3.44900039 -1.06625069 0 P 0 ;1,3=93,5=0.000000
L 3.44900039 -1.06625069 3.45366604 -1.07375138 0 P 0 ;1,3=93,5=0.000000
L 3.45366604 -1.07375138 3.45926654 -1.0787503 0 P 0 ;1,3=93,5=0.000000
L 3.45926654 -1.0787503 3.4658002 -1.08 0 P 0 ;1,3=93,5=0.000000
L 3.4658002 -1.08 3.47233386 -1.07750059 0 P 0 ;1,3=93,5=0.000000
L 3.47233386 -1.07750059 3.47886752 -1.07000217 0 P 0 ;1,3=93,5=0.000000
L 3.52119931 -1.03000157 3.53799911 -1.08 0 P 0 ;1,3=93,5=0.000000
L 3.53799911 -1.08 3.55480059 -1.03000157 0 P 0 ;1,3=93,5=0.000000
L 3.68799911 -1.08249941 3.68613287 -1.0812497 0 P 0 ;1,3=93,5=0.000000
L 3.68613287 -1.0812497 3.68613287 -1.0787503 0 P 0 ;1,3=93,5=0.000000
L 3.68613287 -1.0787503 3.68799911 -1.07750059 0 P 0 ;1,3=93,5=0.000000
L 3.68799911 -1.07750059 3.68986703 -1.0787503 0 P 0 ;1,3=93,5=0.000000
L 3.68986703 -1.0787503 3.68986703 -1.0812497 0 P 0 ;1,3=93,5=0.000000
L 3.68986703 -1.0812497 3.68799911 -1.08249941 0 P 0 ;1,3=93,5=0.000000
L 3.68799911 -1.04875217 3.68613287 -1.0475001 0 P 0 ;1,3=93,5=0.000000
L 3.68613287 -1.0475001 3.68613287 -1.04500069 0 P 0 ;1,3=93,5=0.000000
L 3.68613287 -1.04500069 3.68799911 -1.04375089 0 P 0 ;1,3=93,5=0.000000
L 3.68799911 -1.04375089 3.68986703 -1.04500069 0 P 0 ;1,3=93,5=0.000000
L 3.68986703 -1.04500069 3.68986703 -1.0475001 0 P 0 ;1,3=93,5=0.000000
L 3.68986703 -1.0475001 3.68799911 -1.04875217 0 P 0 ;1,3=93,5=0.000000
L 3.83799911 -1.005 3.83053228 -1.00749951 0 P 0 ;1,3=93,5=0.000000
L 3.83053228 -1.00749951 3.82493346 -1.01375049 0 P 0 ;1,3=93,5=0.000000
L 3.82493346 -1.01375049 3.82119931 -1.02124882 0 P 0 ;1,3=93,5=0.000000
L 3.82119931 -1.02124882 3.8183999 -1.03125128 0 P 0 ;1,3=93,5=0.000000
L 3.8183999 -1.03125128 3.81746673 -1.04250118 0 P 0 ;1,3=93,5=0.000000
L 3.81746673 -1.04250118 3.8183999 -1.05375108 0 P 0 ;1,3=93,5=0.000000
L 3.8183999 -1.05375108 3.82119931 -1.06375128 0 P 0 ;1,3=93,5=0.000000
L 3.82119931 -1.06375128 3.82493346 -1.07125187 0 P 0 ;1,3=93,5=0.000000
L 3.82493346 -1.07125187 3.83053228 -1.07750059 0 P 0 ;1,3=93,5=0.000000
L 3.83053228 -1.07750059 3.83799911 -1.08 0 P 0 ;1,3=93,5=0.000000
L 3.83799911 -1.08 3.84546585 -1.07750059 0 P 0 ;1,3=93,5=0.000000
L 3.84546585 -1.07750059 3.85106644 -1.07125187 0 P 0 ;1,3=93,5=0.000000
L 3.85106644 -1.07125187 3.85480059 -1.06375128 0 P 0 ;1,3=93,5=0.000000
L 3.85480059 -1.06375128 3.8576 -1.05375108 0 P 0 ;1,3=93,5=0.000000
L 3.8576 -1.05375108 3.85853317 -1.04250118 0 P 0 ;1,3=93,5=0.000000
L 3.85853317 -1.04250118 3.8576 -1.03125128 0 P 0 ;1,3=93,5=0.000000
L 3.8576 -1.03125128 3.85480059 -1.02124882 0 P 0 ;1,3=93,5=0.000000
L 3.85480059 -1.02124882 3.85106644 -1.01375049 0 P 0 ;1,3=93,5=0.000000
L 3.85106644 -1.01375049 3.84546585 -1.00749951 0 P 0 ;1,3=93,5=0.000000
L 3.84546585 -1.00749951 3.83799911 -1.005 0 P 0 ;1,3=93,5=0.000000
L 3.91299911 -1.08 3.91299911 -1.005 0 P 0 ;1,3=93,5=0.000000
L 3.91299911 -1.005 3.9017998 -1.01999911 0 P 0 ;1,3=93,5=0.000000
L 3.9017998 -1.08 3.92419843 -1.08 0 P 0 ;1,3=93,5=0.000000
S P 0
OB 1.6515 3.011 I
OS 1.7085 3.011
OS 1.7085 2.9898
OC 1.6985 2.9995 1.6985 2.989495374016 N
OC 1.6885 2.9895 1.6985 2.9895 N
OC 1.6977 2.979530019685 1.69850226378 2.989500098425 N
OS 1.6977 2.9795
OS 1.6515 2.9795
OS 1.6515 3.011
OE
SE
S P 0
OB 1.6515 3.019 I
OS 1.6515 3.0405
OC 1.6615 3.0505 1.6615 3.0405 N
OS 1.7085 3.0505
OS 1.7085 3.019
OS 1.6515 3.019
OE
SE
S P 0
OB 5.0901 2.7425 I
OS 5.1365 2.7425
OS 5.1365 2.711
OS 5.0795 2.711
OS 5.0795 2.7324
OC 5.0895 2.7225 5.0895 2.732500492126 N
OC 5.0995 2.7325 5.0895 2.7325 N
OC 5.0901 2.742480019685 5.089502066929 2.7325 N
OS 5.0901 2.7425
OE
SE
S P 0
OB 5.1365 2.703 I
OS 5.1365 2.6815
OC 5.1265 2.6715 5.1265 2.6815 N
OS 5.0795 2.6715
OS 5.0795 2.703
OS 5.1365 2.703
OE
SE
S P 0
OB 5.5965 0.675 I
OS 5.6535 0.675
OS 5.6535 0.6537
OC 5.6435 0.6635 5.6435 0.653497933071 N
OC 5.6335 0.6535 5.6435 0.6535 N
OC 5.6431 0.64351003937 5.643497933071 0.653500098425 N
OS 5.6431 0.6435
OS 5.5965 0.6435
OS 5.5965 0.675
OE
SE
S P 0
OB 5.5965 0.683 I
OS 5.5965 0.7045
OC 5.6065 0.7145 5.6065 0.7045 N
OS 5.6535 0.7145
OS 5.6535 0.683
OS 5.5965 0.683
OE
SE
S P 0
OB 3.9475 2.9165 I
OS 3.916 2.9165
OS 3.916 2.9735
OS 3.9475 2.9735
OS 3.9475 2.9165
OE
SE
S P 0
OB 3.908 2.9165 I
OS 3.8865 2.9165
OC 3.8765 2.9265 3.8865 2.9265 N
OS 3.8765 2.9735
OS 3.908 2.9735
OS 3.908 2.9165
OE
SE
S P 0
OB 4.3915 2.924 I
OS 4.3915 2.88
OS 4.36 2.88
OS 4.36 2.924
OS 4.3915 2.924
OE
SE
S P 0
OB 4.352 2.872 I
OS 4.352 2.828
OS 4.3205 2.828
OS 4.3205 2.872
OS 4.352 2.872
OE
SE
S P 0
OB 4.3915 2.872 I
OS 4.3915 2.838
OC 4.3815 2.828 4.3815 2.838 N
OS 4.36 2.828
OS 4.36 2.872
OS 4.3915 2.872
OE
SE
S P 0
OB 4.3205 2.88 I
OS 4.3205 2.914
OC 4.3305 2.924 4.3305 2.914 N
OS 4.352 2.924
OS 4.352 2.88
OS 4.3205 2.88
OE
SE
S P 0
OB 4.1275 4.0495 I
OS 4.1605 4.0495
OS 4.1605 4.021669980315
OC 4.155330019685 4.0165 4.1645 4.0125 N
OS 4.132669980315 4.0165
OC 4.1275 4.021669980315 4.1235 4.0125 N
OS 4.1275 4.0495
OE
SE
S P 0
OB 4.132669980315 3.9675 I
OS 4.155330019685 3.9675
OC 4.1605 3.962330019685 4.1645 3.9715 N
OS 4.1605 3.9345
OS 4.1275 3.9345
OS 4.1275 3.962330019685
OC 4.132669980315 3.9675 4.1235 3.9715 N
OE
SE
S P 0
OB 4.132669980315 4.0085 I
OS 4.155330019685 4.0085
OC 4.1605 4.003330019685 4.1645 4.0125 N
OS 4.1605 3.980669980315
OC 4.155330019685 3.9755 4.1645 3.9715 N
OS 4.132669980315 3.9755
OC 4.1275 3.980669980315 4.1235 3.9715 N
OS 4.1275 4.003330019685
OC 4.132669980315 4.0085 4.1235 4.0125 N
OE
SE
S P 0
OB 4.173669980315 4.0085 I
OS 4.2015 4.0085
OS 4.2015 3.9755
OS 4.173669980315 3.9755
OC 4.1685 3.980669980315 4.1645 3.9715 N
OS 4.1685 4.003330019685
OC 4.173669980315 4.0085 4.1645 4.0125 N
OE
SE
S P 0
OB 4.0865 4.0085 I
OS 4.114330019685 4.0085
OC 4.1195 4.003330019685 4.1235 4.0125 N
OS 4.1195 3.980669980315
OC 4.114330019685 3.9755 4.1235 3.9715 N
OS 4.0865 3.9755
OS 4.0865 4.0085
OE
SE
S P 0
OB 4.0865 3.9675 I
OS 4.114330019685 3.9675
OC 4.1195 3.962330019685 4.1235 3.9715 N
OS 4.1195 3.9345
OS 4.0968 3.9345
OC 4.1065 3.9445 4.096495374016 3.9445 N
OC 4.0965 3.9545 4.0965 3.9445 N
OC 4.08651003937 3.94498996063 4.0965 3.944497933071 N
OS 4.0865 3.945
OS 4.0865 3.9675
OE
SE
S P 0
OB 4.173669980315 3.9675 I
OS 4.2015 3.9675
OS 4.2015 3.9448
OC 4.1915 3.9545 4.1915 3.944495374016 N
OC 4.1815 3.9445 4.1915 3.9445 N
OC 4.1914 3.9345 4.191500492126 3.9445 N
OS 4.1685 3.9345
OS 4.1685 3.962330019685
OC 4.173669980315 3.9675 4.1645 3.9715 N
OE
SE
S P 0
OB 4.1685 4.0495 I
OS 4.191 4.0495
OS 4.191 4.04948996063
OC 4.1815 4.0395 4.19150265748 4.039499901575 N
OC 4.1915 4.0295 4.1915 4.0395 N
OC 4.201469980315 4.0387 4.191499901575 4.03950226378 N
OS 4.2015 4.0387
OS 4.2015 4.0165
OS 4.173669980315 4.0165
OC 4.1685 4.021669980315 4.1645 4.0125 N
OS 4.1685 4.0495
OE
SE
S P 0
OB 4.0972 4.0495 I
OS 4.1195 4.0495
OS 4.1195 4.021669980315
OC 4.114330019685 4.0165 4.1235 4.0125 N
OS 4.0865 4.0165
OS 4.0865 4.0394
OC 4.0965 4.0295 4.0965 4.039500492126 N
OC 4.1065 4.0395 4.0965 4.0395 N
OC 4.097180019685 4.049480019685 4.096496653543 4.0395 N
OS 4.0972 4.0495
OE
SE
S P 0
OB 2.807669980315 1.121430019685 I
OC 2.807669980315 1.121430019685 2.685669980315 1.121430019685 Y
OE
SE
S P 0
OB 2.807669980315 2.559430019685 I
OC 2.807669980315 2.559430019685 2.685669980315 2.559430019685 Y
OE
SE
S P 0
OB 1.582669980315 2.680430019685 I
OC 1.582669980315 2.680430019685 1.460669980315 2.680430019685 Y
OE
SE
S P 0
OB 1.557669980315 1.060430019685 I
OC 1.557669980315 1.060430019685 1.435669980315 1.060430019685 Y
OE
SE
S P 0
OB 6.52038996063 0.65353996063 I
OC 6.52038996063 0.65353996063 6.40038996063 0.65353996063 Y
OE
SE
S P 0
OB 0.415280019685 3.73031003937 I
OC 0.415280019685 3.73031003937 0.295280019685 3.73031003937 Y
OE
SE
S P 0
OB 0.415280019685 0.36811003937 I
OC 0.415280019685 0.36811003937 0.295280019685 0.36811003937 Y
OE
SE
S P 0
OB 6.52038996063 4.17835 I
OC 6.52038996063 4.17835 6.40038996063 4.17835 Y
OE
SE
S P 0
OB 5.994 2.1135 I
OS 6.0255 2.1135
OS 6.0255 2.0847
OC 6.0155 2.0945 6.0155 2.084497933071 N
OC 6.0055 2.0845 6.0155 2.0845 N
OC 6.015 2.07451003937 6.01550265748 2.084500098425 N
OS 6.015 2.0745
OS 5.994 2.0745
OS 5.994 2.1135
OE
SE
S P 0
OB 5.9649 2.1135 I
OS 5.986 2.1135
OS 5.986 2.0745
OS 5.9545 2.0745
OS 5.9545 2.1033
OC 5.9645 2.0935 5.9645 2.103502066929 N
OC 5.9745 2.1035 5.9645 2.1035 N
OC 5.9649 2.11348996063 5.964502066929 2.103499901575 N
OS 5.9649 2.1135
OE
SE
S P 0
OB 0.669 4.14 I
OS 0.7082 4.14
OS 0.7082 4.100769980315
OC 0.704719980315 4.0976 0.713003346457 4.092001673228 N
OS 0.669 4.0976
OS 0.669 4.14
OE
SE
S P 0
OB 0.7162 4.14 I
OS 0.7554 4.14
OS 0.7554 4.100880019685
OC 0.751719980315 4.0976 0.760007677165 4.092006003937 N
OS 0.721280019685 4.0976
OC 0.7162 4.101469980315 0.712999114173 4.091999015748 N
OS 0.7162 4.14
OE
SE
S P 0
OB 0.72271003937 4.0896 I
OS 0.75028996063 4.0896
OC 0.7554 4.083119980315 0.759998425197 4.092001082677 N
OS 0.7554 4.050880019685
OC 0.75146003937 4.0472 0.760003051181 4.04200265748 N
OS 0.72153996063 4.0472
OC 0.7162 4.051469980315 0.71300226378 4.041996948819 N
OS 0.7162 4.082530019685
OC 0.72271003937 4.0896 0.713004133858 4.092005019685 N
OE
SE
S P 0
OB 0.669 4.0896 I
OS 0.70328996063 4.0896
OC 0.7082 4.083230019685 0.712996555118 4.092004625984 N
OS 0.7082 4.050769980315
OC 0.70446003937 4.0472 0.712999114173 4.041998326772 N
OS 0.669 4.0472
OS 0.669 4.0896
OE
SE
S P 0
OB 0.7634 4.14 I
OS 0.8026 4.14
OS 0.8026 4.100980019685
OC 0.798719980315 4.0976 0.807006496063 4.092004724409 N
OS 0.768280019685 4.0976
OC 0.7634 4.1014 0.759999015748 4.091998917323 N
OS 0.7634 4.14
OE
SE
S P 0
OB 0.76971003937 4.0896 I
OS 0.79728996063 4.0896
OC 0.8026 4.083019980315 0.806998031496 4.092001771654 N
OS 0.8026 4.050980019685
OC 0.79846003937 4.0472 0.807002165354 4.042001574803 N
OS 0.76853996063 4.0472
OC 0.7634 4.0514 0.76000226378 4.041996751969 N
OS 0.7634 4.0826
OC 0.76971003937 4.0896 0.760004133858 4.092005216535 N
OE
SE
S P 0
OB 0.8106 4.14 I
OS 0.8498 4.14
OS 0.8498 4.101080019685
OC 0.845719980315 4.0976 0.854011909449 4.092010137795 N
OS 0.815280019685 4.0976
OC 0.8106 4.101330019685 0.806993700787 4.092004232283 N
OS 0.8106 4.14
OE
SE
S P 0
OB 0.81671003937 4.0896 I
OS 0.84428996063 4.0896
OC 0.8498 4.082919980315 0.854000590551 4.09199734252 N
OS 0.8498 4.051080019685
OC 0.84546003937 4.0472 0.854007086614 4.042006988189 N
OS 0.81553996063 4.0472
OC 0.8106 4.051330019685 0.806997637795 4.042001771654 N
OS 0.8106 4.082669980315
OC 0.81671003937 4.0896 0.807001673228 4.092001082677 N
OE
SE
S P 0
OB 0.8578 4.14 I
OS 0.897 4.14
OS 0.897 4.0976
OS 0.862280019685 4.0976
OC 0.8578 4.10125 0.853993897638 4.092004035433 N
OS 0.8578 4.14
OE
SE
S P 0
OB 0.86371003937 4.0896 I
OS 0.897 4.0896
OS 0.897 4.0472
OS 0.86253996063 4.0472
OC 0.8578 4.05125 0.853997933071 4.042001476378 N
OS 0.8578 4.08275
OC 0.86371003937 4.0896 0.854001870079 4.092001476378 N
OE
SE
S P 0
OB 0.669 4.0392 I
OS 0.7034 4.0392
OC 0.7082 4.033230019685 0.712998425197 4.042002755906 N
OS 0.7082 4.000769980315
OC 0.704230019685 3.9968 0.713 3.992 N
OS 0.669 3.9968
OS 0.669 4.0392
OE
SE
S P 0
OB 0.7226 4.0392 I
OS 0.7504 4.0392
OC 0.7554 4.033119980315 0.760000492126 4.041999212598 N
OS 0.7554 4.000880019685
OC 0.751230019685 3.9968 0.760004133858 3.992003444882 N
OS 0.721769980315 3.9968
OC 0.7162 4.001469980315 0.713000984252 3.99199773622 N
OS 0.7162 4.032530019685
OC 0.7226 4.0392 0.71300246063 4.042003641732 N
OE
SE
S P 0
OB 0.7696 4.0392 I
OS 0.7974 4.0392
OC 0.8026 4.033019980315 0.807 4.041999901575 N
OS 0.8026 4.000980019685
OC 0.798230019685 3.9968 0.807003149606 3.99200246063 N
OS 0.768769980315 3.9968
OC 0.7634 4.0014 0.760000984252 3.991997637795 N
OS 0.7634 4.0326
OC 0.7696 4.0392 0.76000246063 4.042003740157 N
OE
SE
S P 0
OB 0.8166 4.0392 I
OS 0.8444 4.0392
OC 0.8498 4.032919980315 0.854002755906 4.041995472441 N
OS 0.8498 4.001080019685
OC 0.845230019685 3.9968 0.85400757874 3.99200757874 N
OS 0.815769980315 3.9968
OC 0.8106 4.001330019685 0.806996653543 3.99200246063 N
OS 0.8106 4.032669980315
OC 0.8166 4.0392 0.806999704724 4.041999606299 N
OE
SE
S P 0
OB 0.8636 4.0392 I
OS 0.897 4.0392
OS 0.897 3.9968
OS 0.862769980315 3.9968
OC 0.8578 4.00125 0.853996948819 3.992002165354 N
OS 0.8578 4.03275
OC 0.8636 4.0392 0.853999901575 4.041999901575 N
OE
SE
S P 0
OB 0.669 3.9888 I
OS 0.703530019685 3.9888
OC 0.7082 3.983230019685 0.71300226378 3.991999015748 N
OS 0.7082 3.950769980315
OC 0.704019980315 3.9464 0.71299753937 3.941996850394 N
OS 0.669 3.9464
OS 0.669 3.9888
OE
SE
S P 0
OB 0.722469980315 3.9888 I
OS 0.750530019685 3.9888
OC 0.7554 3.983119980315 0.760004527559 3.991995570866 N
OS 0.7554 3.950880019685
OC 0.751019980315 3.9464 0.760000688976 3.942000885827 N
OS 0.721980019685 3.9464
OC 0.7162 3.951469980315 0.713003444882 3.941996062992 N
OS 0.7162 3.982530019685
OC 0.722469980315 3.9888 0.713 3.992 N
OE
SE
S P 0
OB 0.769469980315 3.9888 I
OS 0.797530019685 3.9888
OC 0.8026 3.983019980315 0.807003937008 3.991996555118 N
OS 0.8026 3.950980019685
OC 0.798019980315 3.9464 0.807 3.942 N
OS 0.768980019685 3.9464
OC 0.7634 3.9514 0.760003543307 3.941995866142 N
OS 0.7634 3.9826
OC 0.769469980315 3.9888 0.759999015748 3.992000984252 N
OE
SE
S P 0
OB 0.816469980315 3.9888 I
OS 0.844530019685 3.9888
OC 0.8498 3.982919980315 0.854006988189 3.991992125984 N
OS 0.8498 3.951080019685
OC 0.845019980315 3.9464 0.854004035433 3.942005019685 N
OS 0.815980019685 3.9464
OC 0.8106 3.951330019685 0.806999704724 3.942000492126 N
OS 0.8106 3.982669980315
OC 0.816469980315 3.9888 0.806995964567 3.991996653543 N
OE
SE
S P 0
OB 0.863469980315 3.9888 I
OS 0.897 3.9888
OS 0.897 3.9464
OS 0.862980019685 3.9464
OC 0.8578 3.95125 0.853999901575 3.942000098425 N
OS 0.8578 3.98275
OC 0.863469980315 3.9888 0.853996161417 3.991996850394 N
OE
SE
S P 0
OB 0.863330019685 3.9384 I
OS 0.897 3.9384
OS 0.897 3.896
OS 0.8578 3.896
OS 0.8578 3.93275
OC 0.863330019685 3.9384 0.854000393701 3.94200019685 N
OE
SE
S P 0
OB 0.816330019685 3.9384 I
OS 0.844669980315 3.9384
OC 0.8498 3.932919980315 0.854002854331 3.941995570866 N
OS 0.8498 3.896
OS 0.8106 3.896
OS 0.8106 3.932669980315
OC 0.816330019685 3.9384 0.807 3.942 N
OE
SE
S P 0
OB 0.769330019685 3.9384 I
OS 0.797669980315 3.9384
OC 0.8026 3.933019980315 0.806999507874 3.942000295276 N
OS 0.8026 3.896
OS 0.7634 3.896
OS 0.7634 3.9326
OC 0.769330019685 3.9384 0.760003346457 3.942004232283 N
OE
SE
S P 0
OB 0.722330019685 3.9384 I
OS 0.750669980315 3.9384
OC 0.7554 3.933119980315 0.760000098425 3.941999606299 N
OS 0.7554 3.896
OS 0.7162 3.896
OS 0.7162 3.932530019685
OC 0.722330019685 3.9384 0.713003346457 3.942004035433 N
OE
SE
S P 0
OB 0.669 3.9384 I
OS 0.703669980315 3.9384
OC 0.7082 3.933230019685 0.71299753937 3.942003346457 N
OS 0.7082 3.896
OS 0.669 3.896
OS 0.669 3.9384
OE
SE
S P 0
OB 5.5605 3.69868996063 I
OS 5.5605 3.68868996063
OS 5.5115 3.68868996063
OS 5.5115 3.69868996063
OS 5.5605 3.69868996063
OE
SE
S P 0
OB 5.5605 3.734130019685 I
OS 5.5605 3.724130019685
OS 5.5115 3.724130019685
OS 5.5115 3.734130019685
OS 5.5605 3.734130019685
OE
SE
S P 0
OB 5.5605 3.76956003937 I
OS 5.5605 3.75956003937
OS 5.5115 3.75956003937
OS 5.5115 3.76956003937
OS 5.5605 3.76956003937
OE
SE
S P 0
OB 5.5605 3.80498996063 I
OS 5.5605 3.79498996063
OS 5.5115 3.79498996063
OS 5.5115 3.80498996063
OS 5.5605 3.80498996063
OE
SE
S P 0
OB 0.518430019685 1.5605 I
OS 0.481569980315 1.5605
OS 0.481569980315 1.5795
OS 0.518430019685 1.5795
OS 0.518430019685 1.5605
OE
SE
S P 0
OB 0.495569980315 1.0095 I
OS 0.532430019685 1.0095
OS 0.532430019685 0.9905
OS 0.495569980315 0.9905
OS 0.495569980315 1.0095
OE
SE
S P 0
OB 0.488569980315 2.6895 I
OS 0.525430019685 2.6895
OS 0.525430019685 2.6705
OS 0.488569980315 2.6705
OS 0.488569980315 2.6895
OE
SE
S P 0
OB 0.524430019685 2.1565 I
OS 0.487569980315 2.1565
OS 0.487569980315 2.1755
OS 0.524430019685 2.1755
OS 0.524430019685 2.1565
OE
SE
S P 0
OB 1.743430019685 2.8905 I
OS 1.706569980315 2.8905
OS 1.706569980315 2.9095
OS 1.743430019685 2.9095
OS 1.743430019685 2.8905
OE
SE
P 5.721 3.712 62 P 0 8 0
S P 0
OB 5.514430019685 3.9215 I
OS 5.514430019685 3.9025
OS 5.477569980315 3.9025
OS 5.477569980315 3.9215
OS 5.514430019685 3.9215
OE
SE
S P 0
OB 1.474430019685 4.0955 I
OS 1.474430019685 4.0765
OS 1.437569980315 4.0765
OS 1.437569980315 4.0955
OS 1.474430019685 4.0955
OE
SE
S P 0
OB 1.479430019685 4.0405 I
OS 1.479430019685 4.0215
OS 1.442569980315 4.0215
OS 1.442569980315 4.0405
OS 1.479430019685 4.0405
OE
SE
S P 0
OB 1.479430019685 3.9105 I
OS 1.479430019685 3.8915
OS 1.442569980315 3.8915
OS 1.442569980315 3.9105
OS 1.479430019685 3.9105
OE
SE
S P 0
OB 1.261569980315 3.7995 I
OS 1.298430019685 3.7995
OS 1.298430019685 3.7805
OS 1.261569980315 3.7805
OS 1.261569980315 3.7995
OE
SE
S P 0
OB 1.206569980315 3.7995 I
OS 1.243430019685 3.7995
OS 1.243430019685 3.7805
OS 1.206569980315 3.7805
OS 1.206569980315 3.7995
OE
SE
P 3.63673002 2.402 45 P 0 8 0
P 3.63673002 2.336 45 P 0 8 0
S P 0
OB 5.468430019685 0.6255 I
OS 5.431569980315 0.6255
OS 5.431569980315 0.6445
OS 5.468430019685 0.6445
OS 5.468430019685 0.6255
OE
SE
S P 0
OB 5.788430019685 0.6185 I
OS 5.788430019685 0.5995
OS 5.751569980315 0.5995
OS 5.751569980315 0.6185
OS 5.788430019685 0.6185
OE
SE
S P 0
OB 3.933569980315 2.7835 I
OS 3.970430019685 2.7835
OS 3.970430019685 2.7645
OS 3.933569980315 2.7645
OS 3.933569980315 2.7835
OE
SE
S P 0
OB 4.981430019685 2.7865 I
OS 4.981430019685 2.7675
OS 4.944569980315 2.7675
OS 4.944569980315 2.7865
OS 4.981430019685 2.7865
OE
SE
S P 0
OB 3.9725 3.108430019685 I
OS 3.9915 3.108430019685
OS 3.9915 3.071569980315
OS 3.9725 3.071569980315
OS 3.9725 3.108430019685
OE
SE
P 3.538 3.947 62 P 0 8 0
P 3.538 3.892 62 P 0 8 0
P 3.537 4.121 62 P 0 8 0
S P 0
OB 5.298430019685 2.7155 I
OS 5.261569980315 2.7155
OS 5.261569980315 2.7345
OS 5.298430019685 2.7345
OS 5.298430019685 2.7155
OE
SE
P 5.51 2.34 45 P 0 8 0
P 5.64 2.34 45 P 0 8 0
P 5.695 2.345 45 P 0 8 0
S P 0
OB 1.772 0.22231003937 I
OS 3.122 0.22231003937
OS 3.122 0.01981003937
OS 3.102 -0.00018996063
OS 1.792 -0.00018996063
OS 1.772 0.01981003937
OS 1.772 0.22231003937
OE
SE

### steps/pcb/layers/spb/features
#
#Num Features
#
F 1927

#
#Units
#
U INCH

#
#Feature symbol names
#
$0 r5
$1 r6
$2 r10
$3 r25
$4 rect108x85 I
$5 rect13x38 I
$6 rect14x24 I
$7 rect15x12 I
$8 rect20x47 I
$9 rect24x14 I
$10 rect24x28 I
$11 rect24x5 I
$12 rect28x24 I
$13 rect30x34 I
$14 rect34x30 I
$15 rect38x54 I
$16 rect39x57 I
$17 rect43x57 I
$18 rect45x104 I
$19 rect54x38 I
$20 rect55x39 I
$21 rect5x24 I
$22 rect60x18 I
$23 rect65x20 I

#
#Feature attribute names
#
@0 .smd
@1 .nomenclature
@2 .geometry
@3 .string
@4 .pad_usage
@5 .string_angle

#
#Feature attribute text strings
#
&0 S028X024
&1 S030X034
&2 S020X065
&3 S038X054
&4 S057X039
&5 S039X055
&6 S018X060
&7 S025C
&8 S020X047
&9 S045X104
&10 S013X038
&11 S005X024_V3_NSM
&12 S012X015
&13 S085X108
&14 S057X043
&15 SOLDERPASTE_BOT
&16 P/N : R4006-B0001-02
&17 Date: 2022-02-25
&18 Layer:
&19 Rev : 01
&20 SOLDERPASTE BOT

#
#Layer features
#
P 4.266 4.065 12 P 0 8 0;0,2=0,4=0
P 4.354 4.065 12 P 0 8 0;0,2=0,4=0
P 4.266 4.115 12 P 0 8 0;0,2=0,4=0
P 4.354 4.115 12 P 0 8 0;0,2=0,4=0
P 4.354 3.865 12 P 0 8 0;0,2=0,4=0
P 4.24 3.941 10 P 0 8 0;0,2=0,4=0
P 3.298 3.385 12 P 0 8 0;0,2=0,4=0
P 3.298 3.475 12 P 0 8 0;0,2=0,4=0
P 3.298 3.43 12 P 0 8 0;0,2=0,4=0
P 4.736 0.965 12 P 0 8 0;0,2=0,4=0
P 4.736 0.915 12 P 0 8 0;0,2=0,4=0
P 4.015 3.291 12 P 0 8 0;0,2=0,4=0
P 4.015 3.239 12 P 0 8 0;0,2=0,4=0
P 3.881 3.81 12 P 0 8 0;0,2=0,4=0
P 3.881 3.758 12 P 0 8 0;0,2=0,4=0
P 3.746 1.72 12 P 0 8 0;0,2=0,4=0
P 0.53 2.091 10 P 0 8 0;0,2=0,4=0
P 0.53 2.626 10 P 0 8 0;0,2=0,4=0
P 0.535 0.926 10 P 0 8 0;0,2=0,4=0
P 0.53 1.486 10 P 0 8 0;0,2=0,4=0
P 1.055 3.731 10 P 0 8 0;0,2=0,4=0
P 0.7 3.426 10 P 0 8 0;0,2=0,4=0
P 1.085 3.564 10 P 0 8 0;0,2=0,4=0
P 1.13 3.564 10 P 0 8 0;0,2=0,4=0
P 1.09 3.512 14 P 0 8 0;0,2=1,4=0
P 1.22 3.564 10 P 0 8 0;0,2=0,4=0
P 1.265 3.564 10 P 0 8 0;0,2=0,4=0
P 1.32 3.548 14 P 0 8 0;0,2=1,4=0
P 4.778 3.551 12 P 0 8 0;0,2=0,4=0
P 4.656 3.895 12 P 0 8 0;0,2=0,4=0
P 4.656 3.94 12 P 0 8 0;0,2=0,4=0
P 6.145 4.094 10 P 0 8 0;0,2=0,4=0
P 1.32 3.602 14 P 0 8 0;0,2=1,4=0
P 1.375 3.601 10 P 0 8 0;0,2=0,4=0
P 1.7485 3.438 23 P 0 8 0;0,2=2,4=0
P 1.7485 3.538 23 P 0 8 0;0,2=2,4=0
P 1.63 3.546 10 P 0 8 0;0,2=0,4=0
P 1.09 3.458 14 P 0 8 0;0,2=1,4=0
P 1.154 3.475 12 P 0 8 0;0,2=0,4=0
P 0.911 3.455 12 P 0 8 0;0,2=0,4=0
P 2.146 3.36 12 P 0 8 0;0,2=0,4=0
P 2.146 3.55 12 P 0 8 0;0,2=0,4=0
P 2.146 3.5 12 P 0 8 0;0,2=0,4=0
P 1.381 3.235 12 P 0 8 0;0,2=0,4=0
P 0.746 3.245 12 P 0 8 0;0,2=0,4=0
P 0.746 3.2 12 P 0 8 0;0,2=0,4=0
P 5.527 3.206 15 P 0 8 0;0,2=3,4=0
P 5.531 3.364 15 P 0 8 0;0,2=3,4=0
P 5.531 3.288 15 P 0 8 0;0,2=3,4=0
P 5.531 3.441 15 P 0 8 0;0,2=3,4=0
P 0.698 0.953 10 P 0 8 0;0,2=0,4=0
P 0.743 0.953 10 P 0 8 0;0,2=0,4=0
P 0.833 0.953 10 P 0 8 0;0,2=0,4=0
P 0.788 0.953 10 P 0 8 0;0,2=0,4=0
P 0.878 0.953 10 P 0 8 0;0,2=0,4=0
P 1.351 0.753 12 P 0 8 0;0,2=0,4=0
P 1.521 3 12 P 0 8 0;0,2=0,4=0
P 1.885 2.939 10 P 0 8 0;0,2=0,4=0
P 1.04 3.564 10 P 0 8 0;0,2=0,4=0
P 1.175 3.564 10 P 0 8 0;0,2=0,4=0
P 5.98 1.581 10 P 0 8 0;0,2=0,4=0
P 6.17 1.576 10 P 0 8 0;0,2=0,4=0
P 5.98 1.461 10 P 0 8 0;0,2=0,4=0
P 6.17 1.476 10 P 0 8 0;0,2=0,4=0
P 5.98 1.676 10 P 0 8 0;0,2=0,4=0
P 6.17 1.676 10 P 0 8 0;0,2=0,4=0
P 5.98 1.781 10 P 0 8 0;0,2=0,4=0
P 6.155 1.769 10 P 0 8 0;0,2=0,4=0
P 6.145 4.136 10 P 0 8 0;0,2=0,4=0
P 1.1737 0.7086 12 P 0 8 0;0,2=0,4=0
P 1.08 0.718 12 P 0 8 0;0,2=0,4=0
P 0.847 0.71 12 P 0 8 0;0,2=0,4=0
P 0.799 0.711 10 P 0 8 0;0,2=0,4=0
P 0.809 0.665 12 P 0 8 0;0,2=0,4=0
P 0.721 0.817 10 P 0 8 0;0,2=0,4=0
P 0.869 3.41 12 P 0 8 0;0,2=0,4=0
P 0.869 3.455 12 P 0 8 0;0,2=0,4=0
P 0.869 3.5 12 P 0 8 0;0,2=0,4=0
P 0.882 3.553 10 P 0 8 0;0,2=0,4=0
P 0.95 3.564 10 P 0 8 0;0,2=0,4=0
P 0.746 3.155 12 P 0 8 0;0,2=0,4=0
P 1.28 3.136 10 P 0 8 0;0,2=0,4=0
P 1.339 3.235 12 P 0 8 0;0,2=0,4=0
P 1.339 3.28 12 P 0 8 0;0,2=0,4=0
P 1.04 3.606 10 P 0 8 0;0,2=0,4=0
P 1.055 3.689 10 P 0 8 0;0,2=0,4=0
P 0.995 3.606 10 P 0 8 0;0,2=0,4=0
P 2.105 3.409 10 P 0 8 0;0,2=0,4=0
P 2.104 3.36 12 P 0 8 0;0,2=0,4=0
P 1.9695 3.388 23 P 0 8 0;0,2=2,4=0
P 2.105 3.451 10 P 0 8 0;0,2=0,4=0
P 1.9695 3.438 23 P 0 8 0;0,2=2,4=0
P 1.9695 3.538 23 P 0 8 0;0,2=2,4=0
P 2.104 3.55 12 P 0 8 0;0,2=0,4=0
P 1.9695 3.488 23 P 0 8 0;0,2=2,4=0
P 2.104 3.5 12 P 0 8 0;0,2=0,4=0
P 1.035 3.136 10 P 0 8 0;0,2=0,4=0
P 1.334 3.5 12 P 0 8 0;0,2=0,4=0
P 0.911 3.41 12 P 0 8 0;0,2=0,4=0
P 0.911 3.5 12 P 0 8 0;0,2=0,4=0
P 0.882 3.595 10 P 0 8 0;0,2=0,4=0
P 0.95 3.606 10 P 0 8 0;0,2=0,4=0
P 0.704 3.155 12 P 0 8 0;0,2=0,4=0
P 0.704 3.2 12 P 0 8 0;0,2=0,4=0
P 0.704 3.245 12 P 0 8 0;0,2=0,4=0
P 5.6705 2.9225 16 P 0 8 0;0,2=4,4=0
P 5.544 2.9225 12 P 0 8 0;0,2=0,4=0
P 5.546 2.77 12 P 0 8 0;0,2=0,4=0
P 5.6755 2.7245 16 P 0 8 0;0,2=4,4=0
P 5.546 3.02 12 P 0 8 0;0,2=0,4=0
P 5.6705 3.0095 16 P 0 8 0;0,2=4,4=0
P 5.6755 2.6375 16 P 0 8 0;0,2=4,4=0
P 5.546 2.64 12 P 0 8 0;0,2=0,4=0
P 1.28 3.094 10 P 0 8 0;0,2=0,4=0
P 1.381 3.28 12 P 0 8 0;0,2=0,4=0
P 1.2157 0.7086 12 P 0 8 0;0,2=0,4=0
P 0.799 0.753 10 P 0 8 0;0,2=0,4=0
P 4.15 2.51 10 P 0 8 0;0,2=0,4=0
P 6.17 1.434 10 P 0 8 0;0,2=0,4=0
P 4.209 2.51 10 P 0 8 0;0,2=0,4=0
P 6.17 1.534 10 P 0 8 0;0,2=0,4=0
P 4.093 2.51 10 P 0 8 0;0,2=0,4=0
P 6.17 1.634 10 P 0 8 0;0,2=0,4=0
P 4.037 2.51 10 P 0 8 0;0,2=0,4=0
P 6.155 1.811 10 P 0 8 0;0,2=0,4=0
P 5.98 1.419 10 P 0 8 0;0,2=0,4=0
P 3.801 2.51 10 P 0 8 0;0,2=0,4=0
P 5.98 1.539 10 P 0 8 0;0,2=0,4=0
P 3.86 2.51 10 P 0 8 0;0,2=0,4=0
P 5.98 1.634 10 P 0 8 0;0,2=0,4=0
P 3.919 2.51 10 P 0 8 0;0,2=0,4=0
P 5.98 1.739 10 P 0 8 0;0,2=0,4=0
P 3.978 2.51 10 P 0 8 0;0,2=0,4=0
P 4.35 2.461 10 P 0 8 0;0,2=0,4=0
P 3.506 3.235 12 P 0 8 0;0,2=0,4=0
P 3.744 3.415 12 P 0 8 0;0,2=0,4=0
P 3.744 3.325 12 P 0 8 0;0,2=0,4=0
P 3.506 3.415 12 P 0 8 0;0,2=0,4=0
P 3.786 3.235 12 P 0 8 0;0,2=0,4=0
P 3.464 3.325 12 P 0 8 0;0,2=0,4=0
P 1.3085 0.658 12 P 0 8 0;0,2=0,4=0
P 1.2158 0.6587 12 P 0 8 0;0,2=0,4=0
P 0.721 0.859 10 P 0 8 0;0,2=0,4=0
P 1.3087 0.708 12 P 0 8 0;0,2=0,4=0
P 3.485 2.864 10 P 0 8 0;0,2=0,4=0
P 3.44 2.864 10 P 0 8 0;0,2=0,4=0
P 3.395 2.906 10 P 0 8 0;0,2=0,4=0
P 3.35 2.906 10 P 0 8 0;0,2=0,4=0
P 1.7485 3.488 23 P 0 8 0;0,2=2,4=0
P 0.674 1.495 12 P 0 8 0;0,2=0,4=0
P 0.85 1.684 12 P 0 8 0;0,2=0,4=0
P 3.026 3.21 12 P 0 8 0;0,2=0,4=0
P 3.026 3.26 12 P 0 8 0;0,2=0,4=0
P 0.896 2.444 10 P 0 8 0;0,2=0,4=0
P 4.396 3.865 12 P 0 8 0;0,2=0,4=0
P 4.396 4.065 12 P 0 8 0;0,2=0,4=0
P 4.396 4.115 12 P 0 8 0;0,2=0,4=0
P 0.805 2.402 10 P 0 8 0;0,2=0,4=0
P 0.76 2.402 10 P 0 8 0;0,2=0,4=0
P 6.025 4.131 10 P 0 8 0;0,2=0,4=0
P 5.91 4.131 10 P 0 8 0;0,2=0,4=0
P 0.53 2.049 10 P 0 8 0;0,2=0,4=0
P 0.53 2.584 10 P 0 8 0;0,2=0,4=0
P 0.53 0.697 10 P 0 8 0;0,2=0,4=0
P 0.53 0.655 10 P 0 8 0;0,2=0,4=0
P 6.379 0.965 12 P 0 8 0;0,2=0,4=0
P 6.379 1.02 12 P 0 8 0;0,2=0,4=0
P 6.379 1.08 12 P 0 8 0;0,2=0,4=0
P 2.083 2.973 10 P 0 8 0;0,2=0,4=0
P 2.128 2.973 10 P 0 8 0;0,2=0,4=0
P 2.173 2.973 10 P 0 8 0;0,2=0,4=0
P 2.9715 2.278 20 P 0 8 0;0,2=5,4=0
P 2.9665 2.18 20 P 0 8 0;0,2=5,4=0
P 2.91 2.299 10 P 0 8 0;0,2=0,4=0
P 3.0585 2.315 20 P 0 8 0;0,2=5,4=0
P 2.845 2.222 14 P 0 8 0;0,2=1,4=0
P 2.85 2.277 19 P 0 8 0;0,2=3,4=0
P 0.5505 2.9772 22 P 0 8 0;0,2=6,4=0
P 0.699 2.915 12 P 0 8 0;0,2=0,4=0
P 5.994 2.79 12 P 0 8 0;0,2=0,4=0
P 5.994 2.615 12 P 0 8 0;0,2=0,4=0
P 4.67901998 2.07965 3 P 0 8 0;0,2=7,4=0
P 4.71838996 2.11901998 3 P 0 8 0;0,2=7,4=0
P 4.639 1.755 12 P 0 8 0;0,2=0,4=0
P 4.67901004 1.68595 3 P 0 8 0;0,2=7,4=0
P 6.027 4.261 10 P 0 8 0;0,2=0,4=0
P 0.577 0.655 10 P 0 8 0;0,2=0,4=0
P 3.47 2.334 10 P 0 8 0;0,2=0,4=0
P 0.858 2.789 10 P 0 8 0;0,2=0,4=0
P 4.366 2.975 12 P 0 8 0;0,2=0,4=0
P 6.14 4.261 10 P 0 8 0;0,2=0,4=0
P 2.6526 2.1935 8 P 0 8 0;0,2=8,4=0
P 2.641 2.375 12 P 0 8 0;0,2=0,4=0
P 0.908 2.789 10 P 0 8 0;0,2=0,4=0
P 3.419 2.21 12 P 0 8 0;0,2=0,4=0
P 3.371 2.21 12 P 0 8 0;0,2=0,4=0
P 3.256 3.475 12 P 0 8 0;0,2=0,4=0
P 3.335 2.553 10 P 0 8 0;0,2=0,4=0
P 6.01901998 1.90865 10 P 0 8 0;0,2=0,4=0
P 2.599 2.375 12 P 0 8 0;0,2=0,4=0
P 2.551 2.375 12 P 0 8 0;0,2=0,4=0
P 4.884 1.855 12 P 0 8 0;0,2=0,4=0
P 4.5609 1.84343002 3 P 0 8 0;0,2=7,4=0
P 4.67901998 1.88281004 3 P 0 8 0;0,2=7,4=0
P 4.885 3.504 10 P 0 8 0;0,2=0,4=0
P 4.60028996 1.8828 3 P 0 8 0;0,2=7,4=0
P 5.404 0.64 12 P 0 8 0;0,2=0,4=0
P 4.884 1.765 12 P 0 8 0;0,2=0,4=0
P 3.44 2.906 10 P 0 8 0;0,2=0,4=0
P 3.35 2.864 10 P 0 8 0;0,2=0,4=0
P 4.524 2.945 12 P 0 8 0;0,2=0,4=0
P 4.524 2.795 12 P 0 8 0;0,2=0,4=0
P 4.524 2.845 12 P 0 8 0;0,2=0,4=0
P 4.524 2.895 12 P 0 8 0;0,2=0,4=0
P 3.068 3.26 12 P 0 8 0;0,2=0,4=0
P 3.256 3.385 12 P 0 8 0;0,2=0,4=0
P 3.256 3.34 12 P 0 8 0;0,2=0,4=0
P 3.068 3.35 12 P 0 8 0;0,2=0,4=0
P 3.256 3.205 12 P 0 8 0;0,2=0,4=0
P 3.485 2.906 10 P 0 8 0;0,2=0,4=0
P 3.98 3.429 10 P 0 8 0;0,2=0,4=0
P 3.744 3.37 12 P 0 8 0;0,2=0,4=0
P 3.506 3.37 12 P 0 8 0;0,2=0,4=0
P 4.17 3.429 10 P 0 8 0;0,2=0,4=0
P 3.973 3.291 12 P 0 8 0;0,2=0,4=0
P 3.744 3.28 12 P 0 8 0;0,2=0,4=0
P 3.744 3.235 12 P 0 8 0;0,2=0,4=0
P 3.506 3.28 12 P 0 8 0;0,2=0,4=0
P 3.395 2.864 10 P 0 8 0;0,2=0,4=0
P 3.419 2.255 12 P 0 8 0;0,2=0,4=0
P 3.371 2.255 12 P 0 8 0;0,2=0,4=0
P 4.884 2.025 12 P 0 8 0;0,2=0,4=0
P 4.926 1.975 12 P 0 8 0;0,2=0,4=0
P 3.505 1.831 10 P 0 8 0;0,2=0,4=0
P 4.63965 1.68595 3 P 0 8 0;0,2=7,4=0
P 3.97036004 2.00091004 3 P 0 8 0;0,2=7,4=0
P 3.97035 2.04028002 3 P 0 8 0;0,2=7,4=0
P 4.306 1.837 10 P 0 8 0;0,2=0,4=0
P 4.31006004 1.8978 3 P 0 8 0;0,2=7,4=0
P 4.0491 1.92216998 3 P 0 8 0;0,2=7,4=0
P 4.00973002 1.92216998 3 P 0 8 0;0,2=7,4=0
P 3.93098002 1.84343002 3 P 0 8 0;0,2=7,4=0
P 4.20658002 1.84343002 3 P 0 8 0;0,2=7,4=0
P 4.60028002 1.84343002 3 P 0 8 0;0,2=7,4=0
P 4.324 2.975 12 P 0 8 0;0,2=0,4=0
P 4.48216004 1.92216004 3 P 0 8 0;0,2=7,4=0
P 4.2 2.936 15 P 0 8 0;0,2=3,4=0
P 4.2 2.855 15 P 0 8 0;0,2=3,4=0
P 4.575 2.461 10 P 0 8 0;0,2=0,4=0
P 4.53 2.461 10 P 0 8 0;0,2=0,4=0
P 4.395 2.461 10 P 0 8 0;0,2=0,4=0
P 4.51311004 1.755 12 P 0 8 0;0,2=0,4=0
P 4.52153996 1.80406004 3 P 0 8 0;0,2=7,4=0
P 4.63965 1.84343002 3 P 0 8 0;0,2=7,4=0
P 4.63965 1.80406004 3 P 0 8 0;0,2=7,4=0
P 4.12783996 1.96153996 3 P 0 8 0;0,2=7,4=0
P 4.16721004 1.96153996 3 P 0 8 0;0,2=7,4=0
P 4.3 1.987 10 P 0 8 0;0,2=0,4=0
P 4.4428 1.92216998 3 P 0 8 0;0,2=7,4=0
P 4.60028002 1.92216998 3 P 0 8 0;0,2=7,4=0
P 4.60028002 1.96153996 3 P 0 8 0;0,2=7,4=0
P 4.78 1.86311004 10 P 0 8 0;0,2=0,4=0
P 4.71838996 2.00091004 3 P 0 8 0;0,2=7,4=0
P 3.93098002 2.15838996 3 P 0 8 0;0,2=7,4=0
P 3.93098002 2.11901998 3 P 0 8 0;0,2=7,4=0
P 4.066 2.215 12 P 0 8 0;0,2=0,4=0
P 4.12783996 2.04028002 3 P 0 8 0;0,2=7,4=0
P 4.24595 2.11901998 3 P 0 8 0;0,2=7,4=0
P 4.40343002 2.15838996 3 P 0 8 0;0,2=7,4=0
P 4.49685 2.22 12 P 0 8 0;0,2=0,4=0
P 4.52153996 2.07965 3 P 0 8 0;0,2=7,4=0
P 4.67901998 2.11901998 3 P 0 8 0;0,2=7,4=0
P 4.0875 2.325 18 P 0 8 0;0,2=9,4=0
P 4.926 1.765 12 P 0 8 0;0,2=0,4=0
P 4.926 1.63 12 P 0 8 0;0,2=0,4=0
P 3.839 3.81 12 P 0 8 0;0,2=0,4=0
P 4.989 3.455 12 P 0 8 0;0,2=0,4=0
P 6.01901998 1.95065 10 P 0 8 0;0,2=0,4=0
P 6.06901998 1.95065 10 P 0 8 0;0,2=0,4=0
P 5.452 3.061 10 P 0 8 0;0,2=0,4=0
P 5.452 2.813 10 P 0 8 0;0,2=0,4=0
P 5.544 2.721 12 P 0 8 0;0,2=0,4=0
P 5.452 2.9645 10 P 0 8 0;0,2=0,4=0
P 5.91901998 1.90865 10 P 0 8 0;0,2=0,4=0
P 5.273 4.20101004 10 P 0 8 0;0,2=0,4=0
P 4.354 3.965 12 P 0 8 0;0,2=0,4=0
P 4.224 4.065 12 P 0 8 0;0,2=0,4=0
P 4.224 4.115 12 P 0 8 0;0,2=0,4=0
P 6.14 4.219 10 P 0 8 0;0,2=0,4=0
P 6.027 4.219 10 P 0 8 0;0,2=0,4=0
P 5.79 4.219 10 P 0 8 0;0,2=0,4=0
P 5.67 4.219 10 P 0 8 0;0,2=0,4=0
P 5.555 4.219 10 P 0 8 0;0,2=0,4=0
P 5.435 4.219 10 P 0 8 0;0,2=0,4=0
P 5.435 4.166 10 P 0 8 0;0,2=0,4=0
P 4.694 0.965 12 P 0 8 0;0,2=0,4=0
P 5.555 0.608 10 P 0 8 0;0,2=0,4=0
P 2.509 2.375 12 P 0 8 0;0,2=0,4=0
P 2.46558996 2.287 5 P 0 8 0;0,2=10,4=0
P 2.461 2.355 12 P 0 8 0;0,2=0,4=0
P 0.741 2.915 12 P 0 8 0;0,2=0,4=0
P 0.241 3.075 12 P 0 8 0;0,2=0,4=0
P 0.3695 3.0284 22 P 0 8 0;0,2=6,4=0
P 0.199 2.975 12 P 0 8 0;0,2=0,4=0
P 0.199 2.925 12 P 0 8 0;0,2=0,4=0
P 0.335 2.829 10 P 0 8 0;0,2=0,4=0
P 0.85 2.402 10 P 0 8 0;0,2=0,4=0
P 0.896 2.402 10 P 0 8 0;0,2=0,4=0
P 0.715 2.402 10 P 0 8 0;0,2=0,4=0
P 0.85 1.549 12 P 0 8 0;0,2=0,4=0
P 0.85 1.639 12 P 0 8 0;0,2=0,4=0
P 0.86 0.791 10 P 0 8 0;0,2=0,4=0
P 0.743 0.911 10 P 0 8 0;0,2=0,4=0
P 0.788 0.911 10 P 0 8 0;0,2=0,4=0
P 1.309 0.753 12 P 0 8 0;0,2=0,4=0
P 1.1738 0.6587 12 P 0 8 0;0,2=0,4=0
P 0.851 0.665 12 P 0 8 0;0,2=0,4=0
P 0.577 0.697 10 P 0 8 0;0,2=0,4=0
P 0.635 0.615 12 P 0 8 0;0,2=0,4=0
P 4.67901998 1.56783996 3 P 0 8 0;0,2=7,4=0
P 4.60028002 1.52846998 3 P 0 8 0;0,2=7,4=0
P 4.16721004 1.52846998 3 P 0 8 0;0,2=7,4=0
P 4.16721004 1.4891 3 P 0 8 0;0,2=7,4=0
P 4.76666004 1.42805 3 P 0 8 0;0,2=7,4=0
P 4.60028002 1.41035 3 P 0 8 0;0,2=7,4=0
P 4.52153996 1.37096998 3 P 0 8 0;0,2=7,4=0
P 4.4428 1.44973002 3 P 0 8 0;0,2=7,4=0
P 4.40343002 1.33161004 3 P 0 8 0;0,2=7,4=0
P 4.36406004 1.44973002 3 P 0 8 0;0,2=7,4=0
P 4.309 1.44531004 3 P 0 8 0;0,2=7,4=0
P 4.20658002 1.41035 3 P 0 8 0;0,2=7,4=0
P 4.0491 1.37098002 3 P 0 8 0;0,2=7,4=0
P 3.91828996 1.29361004 12 P 0 8 0;0,2=0,4=0
P 4.999 1.263 15 P 0 8 0;0,2=3,4=0
P 4.37 1.079 10 P 0 8 0;0,2=0,4=0
P 4.415 1.079 10 P 0 8 0;0,2=0,4=0
P 3.732 1.06 15 P 0 8 0;0,2=3,4=0
P 3.068 3.21 12 P 0 8 0;0,2=0,4=0
P 5.529 4.07 12 P 0 8 0;0,2=0,4=0
P 4.42311004 1.755 12 P 0 8 0;0,2=0,4=0
P 4.4428 1.68595 3 P 0 8 0;0,2=7,4=0
P 4.36406004 1.80406004 3 P 0 8 0;0,2=7,4=0
P 4.365 1.741 12 P 0 8 0;0,2=0,4=0
P 4.24595 1.80406004 3 P 0 8 0;0,2=7,4=0
P 4.241 1.75 12 P 0 8 0;0,2=0,4=0
P 4.20658002 1.64658002 3 P 0 8 0;0,2=7,4=0
P 4.14 1.75 12 P 0 8 0;0,2=0,4=0
P 4.0491 1.80406004 3 P 0 8 0;0,2=7,4=0
P 5.775 0.796 10 P 0 8 0;0,2=0,4=0
P 4.566 2.945 12 P 0 8 0;0,2=0,4=0
P 1.435 3.901 12 P 0 8 0;0,2=0,4=0
P 3.612 2.23 15 P 0 8 0;0,2=3,4=0
P 3.609 2.17 12 P 0 8 0;0,2=0,4=0
P 5.278 2.653 10 P 0 8 0;0,2=0,4=0
P 4.961 2.686 10 P 0 8 0;0,2=0,4=0
P 3.793 3.092 12 P 0 8 0;0,2=0,4=0
P 3.52 1.376 10 P 0 8 0;0,2=0,4=0
P 3.618 1.395 13 P 0 8 0;0,2=1,4=0
P 3.46 1.378 19 P 0 8 0;0,2=3,4=0
P 3.835 3.092 12 P 0 8 0;0,2=0,4=0
P 3.891 3.092 12 P 0 8 0;0,2=0,4=0
P 5.51 2.024 10 P 0 8 0;0,2=0,4=0
P 5.589 1.98 12 P 0 8 0;0,2=0,4=0
P 5.431 2.275 12 P 0 8 0;0,2=0,4=0
P 4.52153996 1.68595 3 P 0 8 0;0,2=7,4=0
P 4.40343002 1.68595 3 P 0 8 0;0,2=7,4=0
P 4.305 1.691 10 P 0 8 0;0,2=0,4=0
P 4.24595 1.68595 3 P 0 8 0;0,2=7,4=0
P 4.12783996 1.68595 3 P 0 8 0;0,2=7,4=0
P 4.48216998 1.60721004 3 P 0 8 0;0,2=7,4=0
P 4.4428 1.64658002 3 P 0 8 0;0,2=7,4=0
P 4.4428 1.56783996 3 P 0 8 0;0,2=7,4=0
P 4.36406004 1.56783996 3 P 0 8 0;0,2=7,4=0
P 4.40343002 1.60721004 3 P 0 8 0;0,2=7,4=0
P 4.36406004 1.60721004 3 P 0 8 0;0,2=7,4=0
P 4.305 1.549 10 P 0 8 0;0,2=0,4=0
P 4.24595 1.60721004 3 P 0 8 0;0,2=7,4=0
P 4.16721004 1.60721004 3 P 0 8 0;0,2=7,4=0
P 4.16721004 1.64658002 3 P 0 8 0;0,2=7,4=0
P 4.20658002 1.52846998 3 P 0 8 0;0,2=7,4=0
P 4.20658002 1.56783996 3 P 0 8 0;0,2=7,4=0
P 4.00973002 1.64658002 3 P 0 8 0;0,2=7,4=0
P 4.08846998 1.56783996 3 P 0 8 0;0,2=7,4=0
P 4.08846998 1.60721004 3 P 0 8 0;0,2=7,4=0
P 4.0491 1.60721004 3 P 0 8 0;0,2=7,4=0
P 4.00973002 1.4891 3 P 0 8 0;0,2=7,4=0
P 4.00973002 1.52846998 3 P 0 8 0;0,2=7,4=0
P 5.39 1.646 10 P 0 8 0;0,2=0,4=0
P 5.4 1.787 19 P 0 8 0;0,2=3,4=0
P 5.754 2.324 10 P 0 8 0;0,2=0,4=0
P 5.7 2.318 14 P 0 8 0;0,2=1,4=0
P 5.6 2.324 10 P 0 8 0;0,2=0,4=0
P 5.51 2.171 10 P 0 8 0;0,2=0,4=0
P 5.64 2.1745 11 P 0 8 0;0,2=11,4=0
P 5.754 2.366 10 P 0 8 0;0,2=0,4=0
P 5.7 2.372 14 P 0 8 0;0,2=1,4=0
P 5.645 2.33456998 7 P 0 8 0;0,2=12,4=0
P 5.465 2.366 10 P 0 8 0;0,2=0,4=0
P 5.645 2.35543002 7 P 0 8 0;0,2=12,4=0
P 5.6 2.366 10 P 0 8 0;0,2=0,4=0
P 5.465 2.324 10 P 0 8 0;0,2=0,4=0
P 5.51 2.324 10 P 0 8 0;0,2=0,4=0
P 5.555 2.324 10 P 0 8 0;0,2=0,4=0
P 5.687 1.99 15 P 0 8 0;0,2=3,4=0
P 5.631 1.98 12 P 0 8 0;0,2=0,4=0
P 5.51 2.129 10 P 0 8 0;0,2=0,4=0
P 5.51 2.066 10 P 0 8 0;0,2=0,4=0
P 3.77 0.917 14 P 0 8 0;0,2=1,4=0
P 4.27 0.832 14 P 0 8 0;0,2=1,4=0
P 4.275 0.919 10 P 0 8 0;0,2=0,4=0
P 4.32 0.919 10 P 0 8 0;0,2=0,4=0
P 5.446 0.69 12 P 0 8 0;0,2=0,4=0
P 5.557 0.705 10 P 0 8 0;0,2=0,4=0
P 5.446 0.64 12 P 0 8 0;0,2=0,4=0
P 5.555 0.65 10 P 0 8 0;0,2=0,4=0
P 5.772 0.7 10 P 0 8 0;0,2=0,4=0
P 5.825 0.754 10 P 0 8 0;0,2=0,4=0
P 5.775 0.754 10 P 0 8 0;0,2=0,4=0
P 5.811 4.12 12 P 0 8 0;0,2=0,4=0
P 5.811 4.075 12 P 0 8 0;0,2=0,4=0
P 5.571 4.115 12 P 0 8 0;0,2=0,4=0
P 5.571 4.07 12 P 0 8 0;0,2=0,4=0
P 5.435 4.124 10 P 0 8 0;0,2=0,4=0
P 5.529 4.115 12 P 0 8 0;0,2=0,4=0
P 5.769 4.12 12 P 0 8 0;0,2=0,4=0
P 5.675 4.126 10 P 0 8 0;0,2=0,4=0
P 5.323 4.20101004 10 P 0 8 0;0,2=0,4=0
P 3.786 3.37 12 P 0 8 0;0,2=0,4=0
P 3.786 3.415 12 P 0 8 0;0,2=0,4=0
P 3.464 3.235 12 P 0 8 0;0,2=0,4=0
P 3.464 3.28 12 P 0 8 0;0,2=0,4=0
P 3.786 3.28 12 P 0 8 0;0,2=0,4=0
P 3.786 3.325 12 P 0 8 0;0,2=0,4=0
P 3.464 3.415 12 P 0 8 0;0,2=0,4=0
P 3.464 3.37 12 P 0 8 0;0,2=0,4=0
P 4.884 1.975 12 P 0 8 0;0,2=0,4=0
P 4.985 3.504 10 P 0 8 0;0,2=0,4=0
P 5.031 3.455 12 P 0 8 0;0,2=0,4=0
P 4.935 3.504 10 P 0 8 0;0,2=0,4=0
P 3.552 4.197 12 P 0 8 0;0,2=0,4=0
P 3.539 4.13 12 P 0 8 0;0,2=0,4=0
P 0.718 1.599 12 P 0 8 0;0,2=0,4=0
P 0.808 1.594 12 P 0 8 0;0,2=0,4=0
P 0.808 1.639 12 P 0 8 0;0,2=0,4=0
P 0.808 1.684 12 P 0 8 0;0,2=0,4=0
P 0.804 1.5 12 P 0 8 0;0,2=0,4=0
P 0.808 1.549 12 P 0 8 0;0,2=0,4=0
P 0.716 1.495 12 P 0 8 0;0,2=0,4=0
P 0.717 1.544 12 P 0 8 0;0,2=0,4=0
P 4.884 1.81 12 P 0 8 0;0,2=0,4=0
P 4.62 2.419 10 P 0 8 0;0,2=0,4=0
P 4.575 2.419 10 P 0 8 0;0,2=0,4=0
P 1.3505 0.658 12 P 0 8 0;0,2=0,4=0
P 0.85 1.594 12 P 0 8 0;0,2=0,4=0
P 1.3507 0.708 12 P 0 8 0;0,2=0,4=0
P 0.846 1.5 12 P 0 8 0;0,2=0,4=0
P 2.3431 0.6259 10 P 0 8 0;0,2=0,4=0
P 4.08846998 1.68595 3 P 0 8 0;0,2=7,4=0
P 4.04908996 1.68595 3 P 0 8 0;0,2=7,4=0
P 2.39311004 0.626 10 P 0 8 0;0,2=0,4=0
P 4.415 1.121 10 P 0 8 0;0,2=0,4=0
P 4.48216998 1.44973002 3 P 0 8 0;0,2=7,4=0
P 4.37 1.121 10 P 0 8 0;0,2=0,4=0
P 4.52155 1.44973002 3 P 0 8 0;0,2=7,4=0
P 4.08846998 1.4891 3 P 0 8 0;0,2=7,4=0
P 4.04908996 1.4891 3 P 0 8 0;0,2=7,4=0
P 2.46558996 2.193 5 P 0 8 0;0,2=10,4=0
P 2.54 2.264 10 P 0 8 0;0,2=0,4=0
P 2.54 2.216 10 P 0 8 0;0,2=0,4=0
P 3.93098002 1.72531998 3 P 0 8 0;0,2=7,4=0
P 3.8863 1.745 12 P 0 8 0;0,2=0,4=0
P 3.704 1.72 12 P 0 8 0;0,2=0,4=0
P 3.93098002 1.52846998 3 P 0 8 0;0,2=7,4=0
P 3.93098002 1.64658002 3 P 0 8 0;0,2=7,4=0
P 3.97035 1.44973002 3 P 0 8 0;0,2=7,4=0
P 3.93098002 1.4891 3 P 0 8 0;0,2=7,4=0
P 3.672 1.395 13 P 0 8 0;0,2=1,4=0
P 3.785 1.368 19 P 0 8 0;0,2=3,4=0
P 4.884 1.63 12 P 0 8 0;0,2=0,4=0
P 4.884 1.675 12 P 0 8 0;0,2=0,4=0
P 4.53 1.181 10 P 0 8 0;0,2=0,4=0
P 4.60026998 1.29223996 3 P 0 8 0;0,2=7,4=0
P 4.585 1.181 10 P 0 8 0;0,2=0,4=0
P 4.63965 1.29223996 3 P 0 8 0;0,2=7,4=0
P 5.323 4.15901004 10 P 0 8 0;0,2=0,4=0
P 5.273 4.15901004 10 P 0 8 0;0,2=0,4=0
P 4.485 2.419 10 P 0 8 0;0,2=0,4=0
P 4.53 2.419 10 P 0 8 0;0,2=0,4=0
P 4.44 2.419 10 P 0 8 0;0,2=0,4=0
P 4.395 2.419 10 P 0 8 0;0,2=0,4=0
P 4.35 2.419 10 P 0 8 0;0,2=0,4=0
P 2.44 2.193 5 P 0 8 0;0,2=10,4=0
P 6.255 1.96773996 10 P 0 8 0;0,2=0,4=0
P 6.3 1.96773996 10 P 0 8 0;0,2=0,4=0
P 6.3 2.00973996 10 P 0 8 0;0,2=0,4=0
P 1.8 4.024 10 P 0 8 0;0,2=0,4=0
P 1.766 3.91 12 P 0 8 0;0,2=0,4=0
P 1.467 3.851 12 P 0 8 0;0,2=0,4=0
P 1.477 4.142 12 P 0 8 0;0,2=0,4=0
P 1.472 4.09 13 P 0 8 0;0,2=1,4=0
P 1.477 3.991 12 P 0 8 0;0,2=0,4=0
P 1.624 3.885 12 P 0 8 0;0,2=0,4=0
P 1.435 4.142 12 P 0 8 0;0,2=0,4=0
P 1.6265 4.031 21 P 0 8 0;0,2=11,4=0
P 1.477 4.036 12 P 0 8 0;0,2=0,4=0
P 1.418 4.09 13 P 0 8 0;0,2=1,4=0
P 5.675 4.084 10 P 0 8 0;0,2=0,4=0
P 3.245 2.901 10 P 0 8 0;0,2=0,4=0
P 3.185 2.907 14 P 0 8 0;0,2=1,4=0
P 3.244 4.07 12 P 0 8 0;0,2=0,4=0
P 3.185 3.921 10 P 0 8 0;0,2=0,4=0
P 5.51 2.366 10 P 0 8 0;0,2=0,4=0
P 3.594 4.197 12 P 0 8 0;0,2=0,4=0
P 3.516 3.887 13 P 0 8 0;0,2=1,4=0
P 3.522 4.077 12 P 0 8 0;0,2=0,4=0
P 3.522 4.032 12 P 0 8 0;0,2=0,4=0
P 3.522 3.987 12 P 0 8 0;0,2=0,4=0
P 3.386 4.095 12 P 0 8 0;0,2=0,4=0
P 3.57 3.887 13 P 0 8 0;0,2=1,4=0
P 3.3725 3.947 21 P 0 8 0;0,2=11,4=0
P 3.522 3.942 12 P 0 8 0;0,2=0,4=0
P 5.72 3.857 12 P 0 8 0;0,2=0,4=0
P 5.72 3.907 12 P 0 8 0;0,2=0,4=0
P 5.769 4.075 12 P 0 8 0;0,2=0,4=0
P 5.316 3.69401004 4 P 0 8 0;0,2=13,4=0
P 1.582 3.776 12 P 0 8 0;0,2=0,4=0
P 3.564 4.077 12 P 0 8 0;0,2=0,4=0
P 3.0535 2.217 20 P 0 8 0;0,2=5,4=0
P 2.41441004 2.287 5 P 0 8 0;0,2=10,4=0
P 2.54 2.306 10 P 0 8 0;0,2=0,4=0
P 2.6526 2.3065 8 P 0 8 0;0,2=8,4=0
P 2.59 2.306 10 P 0 8 0;0,2=0,4=0
P 3.185 3.879 10 P 0 8 0;0,2=0,4=0
P 3.185 3.823 19 P 0 8 0;0,2=3,4=0
P 3.344 4.095 12 P 0 8 0;0,2=0,4=0
P 3.286 4.07 12 P 0 8 0;0,2=0,4=0
P 3.564 3.942 12 P 0 8 0;0,2=0,4=0
P 3.564 3.987 12 P 0 8 0;0,2=0,4=0
P 1.807 4.13 15 P 0 8 0;0,2=3,4=0
P 1.8 4.066 10 P 0 8 0;0,2=0,4=0
P 1.666 3.885 12 P 0 8 0;0,2=0,4=0
P 1.724 3.91 12 P 0 8 0;0,2=0,4=0
P 1.435 4.036 12 P 0 8 0;0,2=0,4=0
P 1.435 3.991 12 P 0 8 0;0,2=0,4=0
P 5.502 2.721 12 P 0 8 0;0,2=0,4=0
P 0.53 1.444 10 P 0 8 0;0,2=0,4=0
P 0.535 0.884 10 P 0 8 0;0,2=0,4=0
P 6.255 2.00973996 10 P 0 8 0;0,2=0,4=0
P 6.21 2.00973996 10 P 0 8 0;0,2=0,4=0
P 1.54 3.776 12 P 0 8 0;0,2=0,4=0
P 1.477 3.946 12 P 0 8 0;0,2=0,4=0
P 1.477 3.901 12 P 0 8 0;0,2=0,4=0
P 3.533 1.88648996 12 P 0 8 0;0,2=0,4=0
P 3.533 1.93148996 12 P 0 8 0;0,2=0,4=0
P 0.908 2.831 10 P 0 8 0;0,2=0,4=0
P 5.7455 3.0095 16 P 0 8 0;0,2=4,4=0
P 5.7505 2.7245 16 P 0 8 0;0,2=4,4=0
P 5.085 3.896 10 P 0 8 0;0,2=0,4=0
P 5.035 3.896 10 P 0 8 0;0,2=0,4=0
P 2.999 2.05 12 P 0 8 0;0,2=0,4=0
P 2.79 2.164 10 P 0 8 0;0,2=0,4=0
P 2.7274 2.1935 8 P 0 8 0;0,2=8,4=0
P 2.845 2.168 14 P 0 8 0;0,2=1,4=0
P 3.002 1.945 15 P 0 8 0;0,2=3,4=0
P 2.999 2.005 12 P 0 8 0;0,2=0,4=0
P 3.185 2.853 14 P 0 8 0;0,2=1,4=0
P 2.9715 2.352 20 P 0 8 0;0,2=5,4=0
P 2.91 2.341 10 P 0 8 0;0,2=0,4=0
P 2.7274 2.3065 8 P 0 8 0;0,2=8,4=0
P 2.85 2.343 19 P 0 8 0;0,2=3,4=0
P 2.96 2.847 19 P 0 8 0;0,2=3,4=0
P 3.035 2.847 19 P 0 8 0;0,2=3,4=0
P 3.11 2.847 19 P 0 8 0;0,2=3,4=0
P 2.855 2.844 10 P 0 8 0;0,2=0,4=0
P 2.9 2.844 10 P 0 8 0;0,2=0,4=0
P 2.79 2.338 10 P 0 8 0;0,2=0,4=0
P 2.155 0.614 10 P 0 8 0;0,2=0,4=0
P 2.2 0.614 10 P 0 8 0;0,2=0,4=0
P 2.26 0.623 14 P 0 8 0;0,2=1,4=0
P 5.91 4.089 10 P 0 8 0;0,2=0,4=0
P 6.025 4.089 10 P 0 8 0;0,2=0,4=0
P 1.425 3.851 12 P 0 8 0;0,2=0,4=0
P 3.581 4.13 12 P 0 8 0;0,2=0,4=0
P 3.662 3.018 19 P 0 8 0;0,2=3,4=0
P 4.566 2.795 12 P 0 8 0;0,2=0,4=0
P 5.014 2.454 15 P 0 8 0;0,2=3,4=0
P 5.389 2.275 12 P 0 8 0;0,2=0,4=0
P 3.77 0.863 14 P 0 8 0;0,2=1,4=0
P 3.77 0.811 10 P 0 8 0;0,2=0,4=0
P 4.269 0.73 12 P 0 8 0;0,2=0,4=0
P 4.27 0.778 14 P 0 8 0;0,2=1,4=0
P 2.26 0.677 14 P 0 8 0;0,2=1,4=0
P 3.47 2.376 10 P 0 8 0;0,2=0,4=0
P 0.5505 3.0284 22 P 0 8 0;0,2=6,4=0
P 0.66 3.014 10 P 0 8 0;0,2=0,4=0
P 0.3695 2.9516 22 P 0 8 0;0,2=6,4=0
P 0.29 2.871 10 P 0 8 0;0,2=0,4=0
P 0.335 2.871 10 P 0 8 0;0,2=0,4=0
P 0.241 2.875 12 P 0 8 0;0,2=0,4=0
P 0.3695 2.9772 22 P 0 8 0;0,2=6,4=0
P 0.241 2.925 12 P 0 8 0;0,2=0,4=0
P 0.3695 3.0028 22 P 0 8 0;0,2=6,4=0
P 0.241 2.975 12 P 0 8 0;0,2=0,4=0
P 0.241 3.025 12 P 0 8 0;0,2=0,4=0
P 3.026 3.35 12 P 0 8 0;0,2=0,4=0
P 3.026 3.305 12 P 0 8 0;0,2=0,4=0
P 3.298 3.34 12 P 0 8 0;0,2=0,4=0
P 3.298 3.295 12 P 0 8 0;0,2=0,4=0
P 3.298 3.25 12 P 0 8 0;0,2=0,4=0
P 3.298 3.205 12 P 0 8 0;0,2=0,4=0
P 1.8646 0.6442 10 P 0 8 0;0,2=0,4=0
P 5.79 4.261 10 P 0 8 0;0,2=0,4=0
P 5.435 4.261 10 P 0 8 0;0,2=0,4=0
P 5.555 4.261 10 P 0 8 0;0,2=0,4=0
P 5.67 4.261 10 P 0 8 0;0,2=0,4=0
P 5.91901998 1.95065 10 P 0 8 0;0,2=0,4=0
P 6.06901998 1.90865 10 P 0 8 0;0,2=0,4=0
P 5.96901998 1.95065 10 P 0 8 0;0,2=0,4=0
P 3.785 1.302 19 P 0 8 0;0,2=3,4=0
P 3.52 1.334 10 P 0 8 0;0,2=0,4=0
P 3.46 1.312 19 P 0 8 0;0,2=3,4=0
P 2.2 0.656 10 P 0 8 0;0,2=0,4=0
P 2.155 0.656 10 P 0 8 0;0,2=0,4=0
P 3.505 1.789 10 P 0 8 0;0,2=0,4=0
P 3.798 1.06 15 P 0 8 0;0,2=3,4=0
P 3.77 0.769 10 P 0 8 0;0,2=0,4=0
P 4.00973002 1.44971998 3 P 0 8 0;0,2=7,4=0
P 4.0491 1.41036004 3 P 0 8 0;0,2=7,4=0
P 4.00971998 1.80406004 3 P 0 8 0;0,2=7,4=0
P 4.12783996 1.64656998 3 P 0 8 0;0,2=7,4=0
P 4.12785 1.56783996 3 P 0 8 0;0,2=7,4=0
P 4.00973002 1.6072 3 P 0 8 0;0,2=7,4=0
P 4.0491 1.64658996 3 P 0 8 0;0,2=7,4=0
P 4.00973002 1.56785 3 P 0 8 0;0,2=7,4=0
P 4.12785 1.60721004 3 P 0 8 0;0,2=7,4=0
P 3.97036004 1.84343002 3 P 0 8 0;0,2=7,4=0
P 3.93098002 1.7647 3 P 0 8 0;0,2=7,4=0
P 3.8443 1.745 12 P 0 8 0;0,2=0,4=0
P 3.97036004 1.64658002 3 P 0 8 0;0,2=7,4=0
P 3.97036004 1.52846998 3 P 0 8 0;0,2=7,4=0
P 3.97035 1.48911004 3 P 0 8 0;0,2=7,4=0
P 3.8916 1.4891 3 P 0 8 0;0,2=7,4=0
P 3.87628996 1.29361004 12 P 0 8 0;0,2=0,4=0
P 4.24 3.983 10 P 0 8 0;0,2=0,4=0
P 1.265 3.606 10 P 0 8 0;0,2=0,4=0
P 5.465 3.441 15 P 0 8 0;0,2=3,4=0
P 5.465 3.288 15 P 0 8 0;0,2=3,4=0
P 5.465 3.364 15 P 0 8 0;0,2=3,4=0
P 5.461 3.206 15 P 0 8 0;0,2=3,4=0
P 1.885 2.981 10 P 0 8 0;0,2=0,4=0
P 1.479 3 12 P 0 8 0;0,2=0,4=0
P 4.7184 2.07965 3 P 0 8 0;0,2=7,4=0
P 4.71838996 2.1584 3 P 0 8 0;0,2=7,4=0
P 4.681 1.755 12 P 0 8 0;0,2=0,4=0
P 4.71838996 1.68595 3 P 0 8 0;0,2=7,4=0
P 4.67901998 1.84343002 3 P 0 8 0;0,2=7,4=0
P 4.56091004 1.8828 3 P 0 8 0;0,2=7,4=0
P 4.694 0.915 12 P 0 8 0;0,2=0,4=0
P 0.5505 2.9516 22 P 0 8 0;0,2=6,4=0
P 0.199 3.025 12 P 0 8 0;0,2=0,4=0
P 0.199 3.075 12 P 0 8 0;0,2=0,4=0
P 0.7 3.384 10 P 0 8 0;0,2=0,4=0
P 3.506 3.325 12 P 0 8 0;0,2=0,4=0
P 0.995 3.564 10 P 0 8 0;0,2=0,4=0
P 4.48216998 1.80405 3 P 0 8 0;0,2=7,4=0
P 4.4428 1.80405 3 P 0 8 0;0,2=7,4=0
P 4.40343996 1.80406004 3 P 0 8 0;0,2=7,4=0
P 4.48216004 1.96153996 3 P 0 8 0;0,2=7,4=0
P 4.311 0.73 12 P 0 8 0;0,2=0,4=0
P 1.63 3.504 10 P 0 8 0;0,2=0,4=0
P 1.035 3.094 10 P 0 8 0;0,2=0,4=0
P 1.376 3.5 12 P 0 8 0;0,2=0,4=0
P 1.196 3.475 12 P 0 8 0;0,2=0,4=0
P 1.085 3.606 10 P 0 8 0;0,2=0,4=0
P 1.375 3.559 10 P 0 8 0;0,2=0,4=0
P 1.175 3.606 10 P 0 8 0;0,2=0,4=0
P 1.22 3.606 10 P 0 8 0;0,2=0,4=0
P 1.13 3.606 10 P 0 8 0;0,2=0,4=0
P 6.21 1.96773996 10 P 0 8 0;0,2=0,4=0
P 4.209 2.552 10 P 0 8 0;0,2=0,4=0
P 4.15 2.552 10 P 0 8 0;0,2=0,4=0
P 4.093 2.552 10 P 0 8 0;0,2=0,4=0
P 4.037 2.552 10 P 0 8 0;0,2=0,4=0
P 3.978 2.552 10 P 0 8 0;0,2=0,4=0
P 3.919 2.552 10 P 0 8 0;0,2=0,4=0
P 3.801 2.552 10 P 0 8 0;0,2=0,4=0
P 3.86 2.552 10 P 0 8 0;0,2=0,4=0
P 4.17 3.471 10 P 0 8 0;0,2=0,4=0
P 3.98 3.471 10 P 0 8 0;0,2=0,4=0
P 3.973 3.239 12 P 0 8 0;0,2=0,4=0
P 3.839 3.758 12 P 0 8 0;0,2=0,4=0
P 5.316 3.51998996 4 P 0 8 0;0,2=13,4=0
P 0.199 2.875 12 P 0 8 0;0,2=0,4=0
P 0.29 2.829 10 P 0 8 0;0,2=0,4=0
P 0.86 0.833 10 P 0 8 0;0,2=0,4=0
P 0.833 0.911 10 P 0 8 0;0,2=0,4=0
P 0.878 0.911 10 P 0 8 0;0,2=0,4=0
P 0.698 0.911 10 P 0 8 0;0,2=0,4=0
P 0.677 0.615 12 P 0 8 0;0,2=0,4=0
P 4.585 1.139 10 P 0 8 0;0,2=0,4=0
P 4.53 1.139 10 P 0 8 0;0,2=0,4=0
P 0.858 2.831 10 P 0 8 0;0,2=0,4=0
P 3.0535 2.143 20 P 0 8 0;0,2=5,4=0
P 3.651 2.17 12 P 0 8 0;0,2=0,4=0
P 5.4 1.853 19 P 0 8 0;0,2=3,4=0
P 5.39 1.604 10 P 0 8 0;0,2=0,4=0
P 1.6355 4.031 21 P 0 8 0;0,2=11,4=0
P 1.435 3.946 12 P 0 8 0;0,2=0,4=0
P 1.873 4.13 15 P 0 8 0;0,2=3,4=0
P 2.128 2.931 10 P 0 8 0;0,2=0,4=0
P 2.083 2.931 10 P 0 8 0;0,2=0,4=0
P 2.173 2.931 10 P 0 8 0;0,2=0,4=0
P 4.566 2.845 12 P 0 8 0;0,2=0,4=0
P 4.566 2.895 12 P 0 8 0;0,2=0,4=0
P 5.753 1.99 15 P 0 8 0;0,2=3,4=0
P 3.185 3.757 19 P 0 8 0;0,2=3,4=0
P 5.772 0.658 10 P 0 8 0;0,2=0,4=0
P 2.419 2.355 12 P 0 8 0;0,2=0,4=0
P 2.79 2.206 10 P 0 8 0;0,2=0,4=0
P 2.79 2.296 10 P 0 8 0;0,2=0,4=0
P 4.55511004 1.755 12 P 0 8 0;0,2=0,4=0
P 4.52153996 1.84343996 3 P 0 8 0;0,2=7,4=0
P 4.32 0.961 10 P 0 8 0;0,2=0,4=0
P 4.275 0.961 10 P 0 8 0;0,2=0,4=0
P 3.041 2.05 12 P 0 8 0;0,2=0,4=0
P 3.041 2.005 12 P 0 8 0;0,2=0,4=0
P 3.068 1.945 15 P 0 8 0;0,2=3,4=0
P 2.41441004 2.193 5 P 0 8 0;0,2=10,4=0
P 5.035 3.854 10 P 0 8 0;0,2=0,4=0
P 5.085 3.854 10 P 0 8 0;0,2=0,4=0
P 4.614 3.94 12 P 0 8 0;0,2=0,4=0
P 4.614 3.895 12 P 0 8 0;0,2=0,4=0
P 4.62 2.461 10 P 0 8 0;0,2=0,4=0
P 2.54 2.174 10 P 0 8 0;0,2=0,4=0
P 2.59 2.264 10 P 0 8 0;0,2=0,4=0
P 5.825 0.796 10 P 0 8 0;0,2=0,4=0
P 5.404 0.69 12 P 0 8 0;0,2=0,4=0
P 4.933 1.263 15 P 0 8 0;0,2=3,4=0
P 4.485 2.461 10 P 0 8 0;0,2=0,4=0
P 4.926 1.675 12 P 0 8 0;0,2=0,4=0
P 4.024 2.215 12 P 0 8 0;0,2=0,4=0
P 3.9825 2.325 18 P 0 8 0;0,2=9,4=0
P 3.678 2.23 15 P 0 8 0;0,2=3,4=0
P 4.75776998 2.00091004 3 P 0 8 0;0,2=7,4=0
P 5.557 0.747 10 P 0 8 0;0,2=0,4=0
P 2.96 2.913 19 P 0 8 0;0,2=3,4=0
P 3.035 2.913 19 P 0 8 0;0,2=3,4=0
P 3.11 2.913 19 P 0 8 0;0,2=3,4=0
P 2.855 2.886 10 P 0 8 0;0,2=0,4=0
P 2.9 2.886 10 P 0 8 0;0,2=0,4=0
P 3.662 2.952 19 P 0 8 0;0,2=3,4=0
P 4.78 1.82111004 10 P 0 8 0;0,2=0,4=0
P 4.40343002 2.19776998 3 P 0 8 0;0,2=7,4=0
P 4.45485 2.22 12 P 0 8 0;0,2=0,4=0
P 4.24595 2.1584 3 P 0 8 0;0,2=7,4=0
P 4.67903002 1.80406004 3 P 0 8 0;0,2=7,4=0
P 4.67901998 2.1584 3 P 0 8 0;0,2=7,4=0
P 3.8916 2.15838996 3 P 0 8 0;0,2=7,4=0
P 3.93098002 2.07963996 3 P 0 8 0;0,2=7,4=0
P 3.97035 1.92216998 3 P 0 8 0;0,2=7,4=0
P 4.20658002 1.48908996 3 P 0 8 0;0,2=7,4=0
P 4.20658002 1.44973002 3 P 0 8 0;0,2=7,4=0
P 4.12783002 1.4891 3 P 0 8 0;0,2=7,4=0
P 4.24596004 1.56783996 3 P 0 8 0;0,2=7,4=0
P 4.16721004 1.56783002 3 P 0 8 0;0,2=7,4=0
P 4.309 1.48468996 3 P 0 8 0;0,2=7,4=0
P 4.12783002 1.52846998 3 P 0 8 0;0,2=7,4=0
P 4.16721998 2.04028002 3 P 0 8 0;0,2=7,4=0
P 4.31006004 1.93718002 3 P 0 8 0;0,2=7,4=0
P 4.3 2.029 10 P 0 8 0;0,2=0,4=0
P 4.16721004 2.00091998 3 P 0 8 0;0,2=7,4=0
P 4.0491 1.96155 3 P 0 8 0;0,2=7,4=0
P 4.08846004 1.96153996 3 P 0 8 0;0,2=7,4=0
P 4.20658002 1.88281004 3 P 0 8 0;0,2=7,4=0
P 4.199 1.75 12 P 0 8 0;0,2=0,4=0
P 4.306 1.795 10 P 0 8 0;0,2=0,4=0
P 4.323 1.741 12 P 0 8 0;0,2=0,4=0
P 4.098 1.75 12 P 0 8 0;0,2=0,4=0
P 4.20656998 1.80406004 3 P 0 8 0;0,2=7,4=0
P 4.20656998 1.68595 3 P 0 8 0;0,2=7,4=0
P 4.16721004 1.68596004 3 P 0 8 0;0,2=7,4=0
P 4.20658002 1.6072 3 P 0 8 0;0,2=7,4=0
P 4.305 1.591 10 P 0 8 0;0,2=0,4=0
P 4.305 1.649 10 P 0 8 0;0,2=0,4=0
P 4.24595 1.64658996 3 P 0 8 0;0,2=7,4=0
P 4.52153996 1.64656998 3 P 0 8 0;0,2=7,4=0
P 4.60026998 1.68595 3 P 0 8 0;0,2=7,4=0
P 4.63963996 1.56783996 3 P 0 8 0;0,2=7,4=0
P 4.60028002 1.56785 3 P 0 8 0;0,2=7,4=0
P 4.48218002 1.64658002 3 P 0 8 0;0,2=7,4=0
P 4.48218002 1.68595 3 P 0 8 0;0,2=7,4=0
P 4.46511004 1.755 12 P 0 8 0;0,2=0,4=0
P 4.63965 1.88281004 3 P 0 8 0;0,2=7,4=0
P 4.4428 1.60721998 3 P 0 8 0;0,2=7,4=0
P 4.40343002 1.64656998 3 P 0 8 0;0,2=7,4=0
P 4.36406004 1.64658996 3 P 0 8 0;0,2=7,4=0
P 4.48216998 1.56783002 3 P 0 8 0;0,2=7,4=0
P 4.52153996 1.41035 3 P 0 8 0;0,2=7,4=0
P 4.5609 1.41035 3 P 0 8 0;0,2=7,4=0
P 4.40343002 1.56783002 3 P 0 8 0;0,2=7,4=0
P 4.40343002 1.37098996 3 P 0 8 0;0,2=7,4=0
P 4.4428 1.41035 3 P 0 8 0;0,2=7,4=0
P 4.36406004 1.52846004 3 P 0 8 0;0,2=7,4=0
P 4.36406004 1.48911004 3 P 0 8 0;0,2=7,4=0
P 4.40341998 1.92216998 3 P 0 8 0;0,2=7,4=0
P 4.48216004 2.07965 3 P 0 8 0;0,2=7,4=0
P 3.3635 3.947 21 P 0 8 0;0,2=11,4=0
P 3.256 3.43 12 P 0 8 0;0,2=0,4=0
P 4.134 2.936 15 P 0 8 0;0,2=3,4=0
P 4.134 2.855 15 P 0 8 0;0,2=3,4=0
P 4.961 2.728 10 P 0 8 0;0,2=0,4=0
P 3.068 3.305 12 P 0 8 0;0,2=0,4=0
P 3.933 3.092 12 P 0 8 0;0,2=0,4=0
P 3.564 4.032 12 P 0 8 0;0,2=0,4=0
P 4.396 3.965 12 P 0 8 0;0,2=0,4=0
P 5.7425 2.6375 17 P 0 8 0;0,2=14,4=0
P 5.278 2.611 10 P 0 8 0;0,2=0,4=0
P 5.7375 2.9225 17 P 0 8 0;0,2=14,4=0
P 5.64 2.1655 11 P 0 8 0;0,2=11,4=0
P 5.08 2.454 15 P 0 8 0;0,2=3,4=0
P 5.555 2.366 10 P 0 8 0;0,2=0,4=0
P 5.4525 2.6795 10 P 0 8 0;0,2=0,4=0
P 3.256 3.295 12 P 0 8 0;0,2=0,4=0
P 3.256 3.25 12 P 0 8 0;0,2=0,4=0
P 4.63966004 1.96153996 3 P 0 8 0;0,2=7,4=0
P 4.63966004 1.92216998 3 P 0 8 0;0,2=7,4=0
P 3.93098002 2.00091004 3 P 0 8 0;0,2=7,4=0
P 3.93096998 2.04028002 3 P 0 8 0;0,2=7,4=0
P 4.44 2.461 10 P 0 8 0;0,2=0,4=0
P 4.76666004 1.38866998 3 P 0 8 0;0,2=7,4=0
P 2.69 2.1935 8 P 0 8 0;0,2=8,4=0
P 3.245 2.859 10 P 0 8 0;0,2=0,4=0
P 6.421 1.08 12 P 0 8 0;0,2=0,4=0
P 6.421 0.965 12 P 0 8 0;0,2=0,4=0
P 6.421 1.02 12 P 0 8 0;0,2=0,4=0
P 0.889 0.71 12 P 0 8 0;0,2=0,4=0
P 1.038 0.718 12 P 0 8 0;0,2=0,4=0
P 1.7485 3.388 23 P 0 8 0;0,2=2,4=0
P 5.96901998 1.90865 10 P 0 8 0;0,2=0,4=0
P 5.762 3.907 12 P 0 8 0;0,2=0,4=0
P 5.762 3.857 12 P 0 8 0;0,2=0,4=0
P 6.036 2.79 12 P 0 8 0;0,2=0,4=0
P 6.036 2.615 12 P 0 8 0;0,2=0,4=0
P 4.926 2.025 12 P 0 8 0;0,2=0,4=0
P 2.7965 1.945 12 P 0 8 0;0,2=0,4=0
P 2.8385 1.945 12 P 0 8 0;0,2=0,4=0
P 2.795 1.88 10 P 0 8 0;0,2=0,4=0
P 2.795 1.838 10 P 0 8 0;0,2=0,4=0
P 4.926 1.855 12 P 0 8 0;0,2=0,4=0
P 3.335 2.511 10 P 0 8 0;0,2=0,4=0
P 5.454 2.87 12 P 0 8 0;0,2=0,4=0
P 5.546 2.815 12 P 0 8 0;0,2=0,4=0
P 5.546 3.065 12 P 0 8 0;0,2=0,4=0
P 5.546 2.595 12 P 0 8 0;0,2=0,4=0
P 0.676 1.599 12 P 0 8 0;0,2=0,4=0
P 0.675 1.544 12 P 0 8 0;0,2=0,4=0
P 4.4428 1.84343002 3 P 0 8 0;0,2=7,4=0
P 3.575 1.88648996 12 P 0 8 0;0,2=0,4=0
P 4.48216998 1.84343002 3 P 0 8 0;0,2=7,4=0
P 3.575 1.93148996 12 P 0 8 0;0,2=0,4=0
P 0.66 3.056 10 P 0 8 0;0,2=0,4=0
P 0.5505 3.0028 22 P 0 8 0;0,2=6,4=0
P 0.805 2.444 10 P 0 8 0;0,2=0,4=0
P 0.85 2.444 10 P 0 8 0;0,2=0,4=0
P 0.76 2.444 10 P 0 8 0;0,2=0,4=0
P 0.715 2.444 10 P 0 8 0;0,2=0,4=0
P 4.985 3.546 10 P 0 8 0;0,2=0,4=0
P 4.935 3.546 10 P 0 8 0;0,2=0,4=0
P 4.736 3.551 12 P 0 8 0;0,2=0,4=0
P 4.885 3.546 10 P 0 8 0;0,2=0,4=0
P 5.496 2.87 12 P 0 8 0;0,2=0,4=0
P 5.502 2.9225 12 P 0 8 0;0,2=0,4=0
P 5.452 2.9225 10 P 0 8 0;0,2=0,4=0
P 5.504 2.815 12 P 0 8 0;0,2=0,4=0
P 4.926 1.81 12 P 0 8 0;0,2=0,4=0
P 5.452 2.771 10 P 0 8 0;0,2=0,4=0
P 5.504 2.77 12 P 0 8 0;0,2=0,4=0
P 5.504 3.065 12 P 0 8 0;0,2=0,4=0
P 5.504 3.02 12 P 0 8 0;0,2=0,4=0
P 5.452 3.019 10 P 0 8 0;0,2=0,4=0
P 5.504 2.595 12 P 0 8 0;0,2=0,4=0
P 5.4525 2.6375 10 P 0 8 0;0,2=0,4=0
P 5.504 2.64 12 P 0 8 0;0,2=0,4=0
P 2.3431 0.5839 10 P 0 8 0;0,2=0,4=0
P 2.39311004 0.584 10 P 0 8 0;0,2=0,4=0
P 2.97303002 0.584 10 P 0 8 0;0,2=0,4=0
P 3.02303002 0.584 10 P 0 8 0;0,2=0,4=0
P 2.80055 0.584 10 P 0 8 0;0,2=0,4=0
P 2.85055 0.584 10 P 0 8 0;0,2=0,4=0
P 2.65806998 0.584 10 P 0 8 0;0,2=0,4=0
P 2.70806998 0.584 10 P 0 8 0;0,2=0,4=0
P 2.46121998 0.584 10 P 0 8 0;0,2=0,4=0
P 2.51121998 0.584 10 P 0 8 0;0,2=0,4=0
P 2.97303002 0.626 10 P 0 8 0;0,2=0,4=0
P 3.02303002 0.626 10 P 0 8 0;0,2=0,4=0
P 2.80055 0.626 10 P 0 8 0;0,2=0,4=0
P 2.85055 0.626 10 P 0 8 0;0,2=0,4=0
P 2.65806998 0.626 10 P 0 8 0;0,2=0,4=0
P 2.70806998 0.626 10 P 0 8 0;0,2=0,4=0
P 2.46121998 0.626 10 P 0 8 0;0,2=0,4=0
P 2.51121998 0.626 10 P 0 8 0;0,2=0,4=0
P 1.8646 0.6022 10 P 0 8 0;0,2=0,4=0
P 3.461 2.255 12 P 0 8 0;0,2=0,4=0
P 3.461 2.21 12 P 0 8 0;0,2=0,4=0
P 3.329 2.21 12 P 0 8 0;0,2=0,4=0
P 3.329 2.255 12 P 0 8 0;0,2=0,4=0
L 3.8089999 -1.31933563 3.817 -1.32600089 1 P 0 ;1,3=15,5=0.000000
L 3.817 -1.32600089 3.8259999 -1.33 1 P 0 ;1,3=15,5=0.000000
L 3.8259999 -1.33 3.834 -1.33 1 P 0 ;1,3=15,5=0.000000
L 3.834 -1.33 3.8420001 -1.32600089 1 P 0 ;1,3=15,5=0.000000
L 3.8420001 -1.32600089 3.84800069 -1.31933563 1 P 0 ;1,3=15,5=0.000000
L 3.84800069 -1.31933563 3.851 -1.30999941 1 P 0 ;1,3=15,5=0.000000
L 3.851 -1.30999941 3.84900049 -1.30066811 1 P 0 ;1,3=15,5=0.000000
L 3.84900049 -1.30066811 3.8439997 -1.29266732 1 P 0 ;1,3=15,5=0.000000
L 3.8439997 -1.29266732 3.8349998 -1.28733278 1 P 0 ;1,3=15,5=0.000000
L 3.8349998 -1.28733278 3.82300049 -1.28466663 1 P 0 ;1,3=15,5=0.000000
L 3.82300049 -1.28466663 3.8160002 -1.27933445 1 P 0 ;1,3=15,5=0.000000
L 3.8160002 -1.27933445 3.81299902 -1.27000069 1 P 0 ;1,3=15,5=0.000000
L 3.81299902 -1.27000069 3.81500039 -1.26066683 1 P 0 ;1,3=15,5=0.000000
L 3.81500039 -1.26066683 3.81999931 -1.25400167 1 P 0 ;1,3=15,5=0.000000
L 3.81999931 -1.25400167 3.8269997 -1.25 1 P 0 ;1,3=15,5=0.000000
L 3.8269997 -1.25 3.834 -1.25 1 P 0 ;1,3=15,5=0.000000
L 3.834 -1.25 3.84100039 -1.25266614 1 P 0 ;1,3=15,5=0.000000
L 3.84100039 -1.25266614 3.84700089 -1.25933386 1 P 0 ;1,3=15,5=0.000000
L 3.90999902 -1.33 3.90199892 -1.32866703 1 P 0 ;1,3=15,5=0.000000
L 3.90199892 -1.32866703 3.89500039 -1.32333484 1 P 0 ;1,3=15,5=0.000000
L 3.89500039 -1.32333484 3.8889999 -1.31533406 1 P 0 ;1,3=15,5=0.000000
L 3.8889999 -1.31533406 3.88499892 -1.3060003 1 P 0 ;1,3=15,5=0.000000
L 3.88499892 -1.3060003 3.88299931 -1.29533346 1 P 0 ;1,3=15,5=0.000000
L 3.88299931 -1.29533346 3.88299931 -1.28466663 1 P 0 ;1,3=15,5=0.000000
L 3.88299931 -1.28466663 3.88499892 -1.2739998 1 P 0 ;1,3=15,5=0.000000
L 3.88499892 -1.2739998 3.8889999 -1.26466604 1 P 0 ;1,3=15,5=0.000000
L 3.8889999 -1.26466604 3.89500039 -1.25666772 1 P 0 ;1,3=15,5=0.000000
L 3.89500039 -1.25666772 3.90199892 -1.25133307 1 P 0 ;1,3=15,5=0.000000
L 3.90199892 -1.25133307 3.90999902 -1.25 1 P 0 ;1,3=15,5=0.000000
L 3.90999902 -1.25 3.91799911 -1.25133307 1 P 0 ;1,3=15,5=0.000000
L 3.91799911 -1.25133307 3.92499951 -1.25666772 1 P 0 ;1,3=15,5=0.000000
L 3.92499951 -1.25666772 3.931 -1.26466604 1 P 0 ;1,3=15,5=0.000000
L 3.931 -1.26466604 3.93500098 -1.2739998 1 P 0 ;1,3=15,5=0.000000
L 3.93500098 -1.2739998 3.93700059 -1.28466663 1 P 0 ;1,3=15,5=0.000000
L 3.93700059 -1.28466663 3.93700059 -1.29533346 1 P 0 ;1,3=15,5=0.000000
L 3.93700059 -1.29533346 3.93500098 -1.3060003 1 P 0 ;1,3=15,5=0.000000
L 3.93500098 -1.3060003 3.931 -1.31533406 1 P 0 ;1,3=15,5=0.000000
L 3.931 -1.31533406 3.92499951 -1.32333484 1 P 0 ;1,3=15,5=0.000000
L 3.92499951 -1.32333484 3.91799911 -1.32866703 1 P 0 ;1,3=15,5=0.000000
L 3.91799911 -1.32866703 3.90999902 -1.33 1 P 0 ;1,3=15,5=0.000000
L 3.96999961 -1.25 3.96999961 -1.33 1 P 0 ;1,3=15,5=0.000000
L 3.96999961 -1.33 4.0100003 -1.33 1 P 0 ;1,3=15,5=0.000000
L 4.0480001 -1.33 4.0480001 -1.25 1 P 0 ;1,3=15,5=0.000000
L 4.0480001 -1.25 4.06799951 -1.25 1 P 0 ;1,3=15,5=0.000000
L 4.06799951 -1.25 4.07599961 -1.25400167 1 P 0 ;1,3=15,5=0.000000
L 4.07599961 -1.25400167 4.0820001 -1.25933386 1 P 0 ;1,3=15,5=0.000000
L 4.0820001 -1.25933386 4.08700089 -1.26733209 1 P 0 ;1,3=15,5=0.000000
L 4.08700089 -1.26733209 4.091 -1.27666831 1 P 0 ;1,3=15,5=0.000000
L 4.091 -1.27666831 4.0919998 -1.29000128 1 P 0 ;1,3=15,5=0.000000
L 4.0919998 -1.29000128 4.091 -1.30333415 1 P 0 ;1,3=15,5=0.000000
L 4.091 -1.30333415 4.08700089 -1.31266801 1 P 0 ;1,3=15,5=0.000000
L 4.08700089 -1.31266801 4.0820001 -1.3206687 1 P 0 ;1,3=15,5=0.000000
L 4.0820001 -1.3206687 4.07599961 -1.32600089 1 P 0 ;1,3=15,5=0.000000
L 4.07599961 -1.32600089 4.06799951 -1.33 1 P 0 ;1,3=15,5=0.000000
L 4.06799951 -1.33 4.0480001 -1.33 1 P 0 ;1,3=15,5=0.000000
L 4.1700003 -1.33 4.12999961 -1.33 1 P 0 ;1,3=15,5=0.000000
L 4.12999961 -1.33 4.12999961 -1.25 1 P 0 ;1,3=15,5=0.000000
L 4.12999961 -1.25 4.1700003 -1.25 1 P 0 ;1,3=15,5=0.000000
L 4.154 -1.28866575 4.12999961 -1.28866575 1 P 0 ;1,3=15,5=0.000000
L 4.20999961 -1.33 4.20999961 -1.25 1 P 0 ;1,3=15,5=0.000000
L 4.20999961 -1.25 4.2349998 -1.25 1 P 0 ;1,3=15,5=0.000000
L 4.2349998 -1.25 4.2429999 -1.25400167 1 P 0 ;1,3=15,5=0.000000
L 4.2429999 -1.25400167 4.24800069 -1.25933386 1 P 0 ;1,3=15,5=0.000000
L 4.24800069 -1.25933386 4.2500003 -1.27000069 1 P 0 ;1,3=15,5=0.000000
L 4.2500003 -1.27000069 4.24800069 -1.28066752 1 P 0 ;1,3=15,5=0.000000
L 4.24800069 -1.28066752 4.2420001 -1.28733278 1 P 0 ;1,3=15,5=0.000000
L 4.2420001 -1.28733278 4.2349998 -1.29133435 1 P 0 ;1,3=15,5=0.000000
L 4.2349998 -1.29133435 4.20999961 -1.29133435 1 P 0 ;1,3=15,5=0.000000
L 4.2349998 -1.29133435 4.2500003 -1.33 1 P 0 ;1,3=15,5=0.000000
L 4.28999961 -1.33 4.28999961 -1.25 1 P 0 ;1,3=15,5=0.000000
L 4.28999961 -1.25 4.314 -1.25 1 P 0 ;1,3=15,5=0.000000
L 4.314 -1.25 4.3220001 -1.25400167 1 P 0 ;1,3=15,5=0.000000
L 4.3220001 -1.25400167 4.32800069 -1.26333297 1 P 0 ;1,3=15,5=0.000000
L 4.32800069 -1.26333297 4.3300003 -1.2739998 1 P 0 ;1,3=15,5=0.000000
L 4.3300003 -1.2739998 4.32800069 -1.28466663 1 P 0 ;1,3=15,5=0.000000
L 4.32800069 -1.28466663 4.3229999 -1.29266732 1 P 0 ;1,3=15,5=0.000000
L 4.3229999 -1.29266732 4.314 -1.296669 1 P 0 ;1,3=15,5=0.000000
L 4.314 -1.296669 4.28999961 -1.296669 1 P 0 ;1,3=15,5=0.000000
L 4.36499892 -1.33 4.38999902 -1.25 1 P 0 ;1,3=15,5=0.000000
L 4.38999902 -1.25 4.41500098 -1.33 1 P 0 ;1,3=15,5=0.000000
L 4.40599931 -1.30200118 4.37399882 -1.30200118 1 P 0 ;1,3=15,5=0.000000
L 4.4489999 -1.31933563 4.457 -1.32600089 1 P 0 ;1,3=15,5=0.000000
L 4.457 -1.32600089 4.4659999 -1.33 1 P 0 ;1,3=15,5=0.000000
L 4.4659999 -1.33 4.474 -1.33 1 P 0 ;1,3=15,5=0.000000
L 4.474 -1.33 4.4820001 -1.32600089 1 P 0 ;1,3=15,5=0.000000
L 4.4820001 -1.32600089 4.48800069 -1.31933563 1 P 0 ;1,3=15,5=0.000000
L 4.48800069 -1.31933563 4.491 -1.30999941 1 P 0 ;1,3=15,5=0.000000
L 4.491 -1.30999941 4.48900049 -1.30066811 1 P 0 ;1,3=15,5=0.000000
L 4.48900049 -1.30066811 4.4839997 -1.29266732 1 P 0 ;1,3=15,5=0.000000
L 4.4839997 -1.29266732 4.4749998 -1.28733278 1 P 0 ;1,3=15,5=0.000000
L 4.4749998 -1.28733278 4.46300049 -1.28466663 1 P 0 ;1,3=15,5=0.000000
L 4.46300049 -1.28466663 4.4560002 -1.27933445 1 P 0 ;1,3=15,5=0.000000
L 4.4560002 -1.27933445 4.45299902 -1.27000069 1 P 0 ;1,3=15,5=0.000000
L 4.45299902 -1.27000069 4.45500039 -1.26066683 1 P 0 ;1,3=15,5=0.000000
L 4.45500039 -1.26066683 4.45999931 -1.25400167 1 P 0 ;1,3=15,5=0.000000
L 4.45999931 -1.25400167 4.4669997 -1.25 1 P 0 ;1,3=15,5=0.000000
L 4.4669997 -1.25 4.474 -1.25 1 P 0 ;1,3=15,5=0.000000
L 4.474 -1.25 4.48100039 -1.25266614 1 P 0 ;1,3=15,5=0.000000
L 4.48100039 -1.25266614 4.48700089 -1.25933386 1 P 0 ;1,3=15,5=0.000000
L 4.54999902 -1.25 4.54999902 -1.33 1 P 0 ;1,3=15,5=0.000000
L 4.5270003 -1.25 4.57299961 -1.25 1 P 0 ;1,3=15,5=0.000000
L 4.6500003 -1.33 4.60999961 -1.33 1 P 0 ;1,3=15,5=0.000000
L 4.60999961 -1.33 4.60999961 -1.25 1 P 0 ;1,3=15,5=0.000000
L 4.60999961 -1.25 4.6500003 -1.25 1 P 0 ;1,3=15,5=0.000000
L 4.634 -1.28866575 4.60999961 -1.28866575 1 P 0 ;1,3=15,5=0.000000
L 4.68 -1.35666585 4.74 -1.35666585 1 P 0 ;1,3=15,5=0.000000
L 4.79799911 -1.28733278 4.8020001 -1.28333356 1 P 0 ;1,3=15,5=0.000000
L 4.8020001 -1.28333356 4.80499951 -1.27666831 1 P 0 ;1,3=15,5=0.000000
L 4.80499951 -1.27666831 4.80700089 -1.26733209 1 P 0 ;1,3=15,5=0.000000
L 4.80700089 -1.26733209 4.80499951 -1.25933386 1 P 0 ;1,3=15,5=0.000000
L 4.80499951 -1.25933386 4.80100039 -1.25400167 1 P 0 ;1,3=15,5=0.000000
L 4.80100039 -1.25400167 4.794 -1.25 1 P 0 ;1,3=15,5=0.000000
L 4.794 -1.25 4.7670003 -1.25 1 P 0 ;1,3=15,5=0.000000
L 4.7670003 -1.25 4.7670003 -1.33 1 P 0 ;1,3=15,5=0.000000
L 4.7670003 -1.33 4.80000059 -1.33 1 P 0 ;1,3=15,5=0.000000
L 4.80000059 -1.33 4.80700089 -1.32466782 1 P 0 ;1,3=15,5=0.000000
L 4.80700089 -1.32466782 4.811 -1.31666713 1 P 0 ;1,3=15,5=0.000000
L 4.811 -1.31666713 4.81299961 -1.30733337 1 P 0 ;1,3=15,5=0.000000
L 4.81299961 -1.30733337 4.811 -1.29800197 1 P 0 ;1,3=15,5=0.000000
L 4.811 -1.29800197 4.80499951 -1.29000128 1 P 0 ;1,3=15,5=0.000000
L 4.80499951 -1.29000128 4.79799911 -1.28733278 1 P 0 ;1,3=15,5=0.000000
L 4.79799911 -1.28733278 4.7670003 -1.28733278 1 P 0 ;1,3=15,5=0.000000
L 4.86999902 -1.33 4.86199892 -1.32866703 1 P 0 ;1,3=15,5=0.000000
L 4.86199892 -1.32866703 4.85500039 -1.32333484 1 P 0 ;1,3=15,5=0.000000
L 4.85500039 -1.32333484 4.8489999 -1.31533406 1 P 0 ;1,3=15,5=0.000000
L 4.8489999 -1.31533406 4.84499892 -1.3060003 1 P 0 ;1,3=15,5=0.000000
L 4.84499892 -1.3060003 4.84299931 -1.29533346 1 P 0 ;1,3=15,5=0.000000
L 4.84299931 -1.29533346 4.84299931 -1.28466663 1 P 0 ;1,3=15,5=0.000000
L 4.84299931 -1.28466663 4.84499892 -1.2739998 1 P 0 ;1,3=15,5=0.000000
L 4.84499892 -1.2739998 4.8489999 -1.26466604 1 P 0 ;1,3=15,5=0.000000
L 4.8489999 -1.26466604 4.85500039 -1.25666772 1 P 0 ;1,3=15,5=0.000000
L 4.85500039 -1.25666772 4.86199892 -1.25133307 1 P 0 ;1,3=15,5=0.000000
L 4.86199892 -1.25133307 4.86999902 -1.25 1 P 0 ;1,3=15,5=0.000000
L 4.86999902 -1.25 4.87799911 -1.25133307 1 P 0 ;1,3=15,5=0.000000
L 4.87799911 -1.25133307 4.88499951 -1.25666772 1 P 0 ;1,3=15,5=0.000000
L 4.88499951 -1.25666772 4.891 -1.26466604 1 P 0 ;1,3=15,5=0.000000
L 4.891 -1.26466604 4.89500098 -1.2739998 1 P 0 ;1,3=15,5=0.000000
L 4.89500098 -1.2739998 4.89700059 -1.28466663 1 P 0 ;1,3=15,5=0.000000
L 4.89700059 -1.28466663 4.89700059 -1.29533346 1 P 0 ;1,3=15,5=0.000000
L 4.89700059 -1.29533346 4.89500098 -1.3060003 1 P 0 ;1,3=15,5=0.000000
L 4.89500098 -1.3060003 4.891 -1.31533406 1 P 0 ;1,3=15,5=0.000000
L 4.891 -1.31533406 4.88499951 -1.32333484 1 P 0 ;1,3=15,5=0.000000
L 4.88499951 -1.32333484 4.87799911 -1.32866703 1 P 0 ;1,3=15,5=0.000000
L 4.87799911 -1.32866703 4.86999902 -1.33 1 P 0 ;1,3=15,5=0.000000
L 4.94999902 -1.25 4.94999902 -1.33 1 P 0 ;1,3=15,5=0.000000
L 4.9270003 -1.25 4.97299961 -1.25 1 P 0 ;1,3=15,5=0.000000
L 3.16 -0.655 3.16 -1.58 2 P 0 
L 1.36 -0.655 1.36 -1.58 2 P 0 
L 1.36 -1.58 5.06 -1.58 2 P 0 
L 5.06 -1.58 5.06 -0.655 2 P 0 
L 5.06 -0.655 1.36 -0.655 2 P 0 
A 1.559 -1.33655 1.559 -1.33655 1.55268002 -1.33655 1 P 0 N
A 1.54775 -1.205 1.54775 -1.205 1.53883002 -1.205 1 P 0 N
A 1.54763996 -0.99775 1.54763996 -0.99775 1.53871998 -0.99775 1 P 0 N
A 1.54063996 -1.10118002 1.54063996 -1.10118002 1.52603996 -1.10118002 1 P 0 N
A 1.49695 -1.10118002 1.49695 -1.10118002 1.48656998 -1.10118002 1 P 0 N
A 1.45963996 -1.10118002 1.45963996 -1.10118002 1.4533 -1.10118002 1 P 0 N
A 1.52135 -0.98681004 1.52135 -0.98681004 1.51503002 -0.98681004 1 P 0 N
A 1.79433002 -1.43586998 1.79433002 -1.43586998 1.78798996 -1.43586998 1 P 0 N
A 1.79841004 -1.40261004 1.79841004 -1.40261004 1.78798996 -1.40261004 1 P 0 N
A 1.80255 -1.36311004 1.80255 -1.36311004 1.78798996 -1.36311004 1 P 0 N
A 1.80668996 -1.31528002 1.80668996 -1.31528002 1.78798996 -1.31528002 1 P 0 N
A 1.68013002 -1.37456004 1.68013002 -1.37456004 1.67378996 -1.37456004 1 P 0 N
A 1.69321998 -1.35033002 1.69321998 -1.35033002 1.6843 -1.35033002 1 P 0 N
A 1.7108 -1.31738996 1.7108 -1.31738996 1.69798002 -1.31738996 1 P 0 N
A 1.89666998 -1.31511004 1.89666998 -1.31511004 1.88383996 -1.31511004 1 P 0 N
A 1.88198996 -1.16876004 1.88198996 -1.16876004 1.85558996 -1.16876004 1 P 0 N
A 1.87928002 -1.27801998 1.87928002 -1.27801998 1.86343996 -1.27801998 1 P 0 N
A 1.86176998 -1.23075 1.86176998 -1.23075 1.84206004 -1.23075 1 P 0 N
A 1.80978996 -1.25916998 1.80978996 -1.25916998 1.78798996 -1.25916998 1 P 0 N
A 1.74681004 -1.16876004 1.74681004 -1.16876004 1.72041004 -1.16876004 1 P 0 N
A 1.67813002 -1.15513002 1.67813002 -1.15513002 1.65841998 -1.15513002 1 P 0 N
A 1.73018002 -1.27816004 1.73018002 -1.27816004 1.71433996 -1.27816004 1 P 0 N
A 1.75373002 -1.23081004 1.75373002 -1.23081004 1.73405 -1.23081004 1 P 0 N
A 1.65531004 -1.25255 1.65531004 -1.25255 1.63661998 -1.25255 1 P 0 N
A 1.69808996 -1.21291998 1.69808996 -1.21291998 1.67628996 -1.21291998 1 P 0 N
A 1.81438996 -1.1968 1.81438996 -1.1968 1.78798996 -1.1968 1 P 0 N
A 1.6269 -1.1749 1.6269 -1.1749 1.61106004 -1.1749 1 P 0 N
A 1.58461004 -1.19126004 1.58461004 -1.19126004 1.57178002 -1.19126004 1 P 0 N
A 1.5853 -1.31428002 1.5853 -1.31428002 1.57488996 -1.31428002 1 P 0 N
A 1.61735 -1.28638996 1.61735 -1.28638996 1.60276998 -1.28638996 1 P 0 N
A 1.88198996 -1.03361004 1.88198996 -1.03361004 1.85558996 -1.03361004 1 P 0 N
A 1.71881004 -1.10118002 1.71881004 -1.10118002 1.69238996 -1.10118002 1 P 0 N
A 1.65183002 -1.10118002 1.65183002 -1.10118002 1.63003002 -1.10118002 1 P 0 N
A 1.67801998 -1.04738996 1.67801998 -1.04738996 1.65831004 -1.04738996 1 P 0 N
A 1.74681004 -1.03361004 1.74681004 -1.03361004 1.72041004 -1.03361004 1 P 0 N
A 1.69811998 -0.98951004 1.69811998 -0.98951004 1.67631998 -0.98951004 1 P 0 N
A 1.81438996 -1.00556004 1.81438996 -1.00556004 1.78798996 -1.00556004 1 P 0 N
A 1.59258002 -1.10118002 1.59258002 -1.10118002 1.5739 -1.10118002 1 P 0 N
A 1.58451004 -1.01148996 1.58451004 -1.01148996 1.57168002 -1.01148996 1 P 0 N
A 1.62681004 -1.02773996 1.62681004 -1.02773996 1.61096998 -1.02773996 1 P 0 N
A 1.92148002 -1.21285 1.92148002 -1.21285 1.89968002 -1.21285 1 P 0 N
A 1.92148002 -0.98951004 1.92148002 -0.98951004 1.89968002 -0.98951004 1 P 0 N
A 1.80978996 -0.9432 1.80978996 -0.9432 1.78798996 -0.9432 1 P 0 N
A 1.80668996 -0.88708002 1.80668996 -0.88708002 1.78798996 -0.88708002 1 P 0 N
A 1.80255 -0.83923996 1.80255 -0.83923996 1.78798996 -0.83923996 1 P 0 N
A 1.8919 -0.88538002 1.8919 -0.88538002 1.87906998 -0.88538002 1 P 0 N
A 1.87838996 -0.92456998 1.87838996 -0.92456998 1.86255 -0.92456998 1 P 0 N
A 1.65531004 -0.94981004 1.65531004 -0.94981004 1.63661998 -0.94981004 1 P 0 N
A 1.73123002 -0.92378002 1.73123002 -0.92378002 1.71538996 -0.92378002 1 P 0 N
A 1.71216998 -0.88443996 1.71216998 -0.88443996 1.69935 -0.88443996 1 P 0 N
A 1.86225 -0.97178002 1.86225 -0.97178002 1.84253996 -0.97178002 1 P 0 N
A 1.75451998 -0.97123996 1.75451998 -0.97123996 1.73483996 -0.97123996 1 P 0 N
A 1.61741998 -0.91601004 1.61741998 -0.91601004 1.60283996 -0.91601004 1 P 0 N
A 1.5853 -0.88808996 1.5853 -0.88808996 1.57488996 -0.88808996 1 P 0 N
A 1.79841004 -0.79975 1.79841004 -0.79975 1.78798996 -0.79975 1 P 0 N
A 1.79433002 -0.76648002 1.79433002 -0.76648002 1.78798996 -0.76648002 1 P 0 N
A 1.92135 -1.36781004 1.92135 -1.36781004 1.91503996 -1.36781004 1 P 0 N
A 1.91096004 -1.34658002 1.91096004 -1.34658002 1.90203996 -1.34658002 1 P 0 N
A 2.19078996 -1.1806 2.26591004 -1.16473002 2.21741014 -1.12088169 1 P 0 N
A 2.15903002 -1.1402 2.19078996 -1.18061004 2.22093406 -1.12423278 1 P 0 N
A 2.05721004 -1.16178996 2.08853002 -1.16658996 2.08281614 -1.09929134 1 P 0 N
A 2.00546998 -1.13951998 2.03345 -1.17196004 2.07793927 -1.10530069 1 P 0 N
A 2.03346004 -1.17195 2.0847 -1.18461004 2.07891181 -1.09801299 1 P 0 N
A 2.0847 -1.18461998 2.14261004 -1.15663002 2.07348435 -1.08751378 1 P 0 N
A 2.08853996 -1.16658002 2.13313002 -1.14451998 2.06368967 -1.06025512 1 P 0 N
A 1.95808002 -1.25255 1.95808002 -1.25255 1.93938996 -1.25255 1 P 0 N
A 1.98775 -1.28635 1.98775 -1.28635 1.97316998 -1.28635 1 P 0 N
A 2.27411998 -1.11835 2.15906004 -1.11835 2.21658996 -1.11611998 1 P 0 N
L 2.25188002 -1.11418002 2.1807 -1.11418002 1 P 0 
L 2.1807 -1.11418002 2.1807 -1.11398996 1 P 8191 
A 2.25188996 -1.11398996 2.18071004 -1.11398996 2.2163 -1.1124 1 P 0 N
A 2.08028996 -1.03428996 2.02048996 -1.08258996 2.0798126 -1.09486801 1 P 0 N
A 2.13151998 -1.05146004 2.0803 -1.0343 2.0802999 -1.11932195 1 P 0 N
A 2.1315 -1.05146998 2.14175 -1.03951004 2.1356003 -1.04461171 1 P 0 N
A 2.14175 -1.03951004 2.08283002 -1.01613002 2.07772461 -1.11492805 1 P 0 N
A 2.08283996 -1.01611998 2.00698002 -1.05835 2.08064724 -1.10143169 1 P 0 N
L 2.27413002 -1.12868996 2.18073996 -1.12868996 1 P 0 
A 2.18075 -1.12868996 2.19083002 -1.15751998 2.22417795 -1.12968307 1 P 0 N
A 2.19083002 -1.15753002 2.25311004 -1.15211004 2.21927195 -1.12381791 1 P 0 N
L 2.15903996 -1.1402 2.15903996 -1.11835 1 P 8191 
A 2.02048996 -1.0826 2.05721998 -1.16181004 2.09087933 -1.0980811 1 P 0 N
A 2.00698996 -1.05836004 2.00546998 -1.13953002 2.09672953 -1.10063967 1 P 0 N
A 2.14258996 -1.15661004 2.13313996 -1.14453002 2.13544892 -1.15246004 1 P 0 N
A 1.95808002 -0.94981004 1.95808002 -0.94981004 1.93938996 -0.94981004 1 P 0 N
A 1.90183996 -0.8525 1.90183996 -0.8525 1.89291004 -0.8525 1 P 0 N
A 1.91108002 -0.82726998 1.91108002 -0.82726998 1.90473996 -0.82726998 1 P 0 N
L 2.32081004 -1.02041004 2.32081004 -1.17625 1 P 0 
A 2.49568002 -1.15528996 2.47898002 -1.16443002 2.4882003 -1.1614502 1 P 0 N
A 2.47896998 -1.16443996 2.50283002 -1.18086004 2.51649242 -1.13546152 1 P 0 N
A 2.50281998 -1.18086998 2.54318002 -1.1834 2.52887392 -1.08843022 1 P 0 N
A 2.52306998 -1.16761004 2.52848996 -1.16771998 2.52673258 -1.12070098 1 P 0 N
A 2.49566004 -1.15528996 2.52306998 -1.1676 2.5255122 -1.12549094 1 P 0 N
A 2.37851998 -1.15753002 2.4408 -1.15211004 2.40696191 -1.12381791 1 P 0 N
A 2.45358002 -1.16471998 2.44078996 -1.1521 2.44541191 -1.16020689 1 P 0 N
A 2.37848002 -1.1806 2.4536 -1.16473002 2.4051001 -1.12088169 1 P 0 N
A 2.34673002 -1.1402 2.37848996 -1.18061004 2.40863406 -1.12423278 1 P 0 N
A 2.2659 -1.16471998 2.25311004 -1.1521 2.25773199 -1.16020689 1 P 0 N
A 2.3006 -1.17626004 2.3208 -1.17626004 2.3107 -1.17386841 1 P 0 N
L 2.30058996 -1.17625 2.30058996 -1.02033996 1 P 0 
A 2.50836998 -1.10106004 2.54306004 -1.11513002 2.56106673 -1.02093386 1 P 0 N
A 2.51081004 -1.07948002 2.50836998 -1.10103996 2.51886093 -1.09130915 1 P 0 N
A 2.53611004 -1.07688996 2.5108 -1.07948996 2.52742205 -1.11680827 1 P 0 N
A 2.56883996 -1.07368002 2.50178002 -1.06358996 2.5273123 -1.12178858 1 P 0 N
A 2.50178996 -1.06358996 2.48536998 -1.08248996 2.52926211 -1.10403986 1 P 0 N
L 2.48536998 -1.0825 2.48536998 -1.09748002 1 P 8191 
A 2.48536998 -1.09748002 2.49956004 -1.12031004 2.51189104 -1.09682067 1 P 0 N
A 2.46181004 -1.11835 2.34675 -1.11835 2.40428002 -1.11611998 1 P 0 N
L 2.43956998 -1.11418002 2.36841004 -1.11418002 1 P 0 
L 2.36841004 -1.11418002 2.36841004 -1.11398996 1 P 8191 
A 2.43958002 -1.11398996 2.3684 -1.11398996 2.40398996 -1.1124 1 P 0 N
L 2.43956998 -1.11398996 2.43956998 -1.11418002 1 P 8191 
A 2.49955 -1.1203 2.52723002 -1.12985 2.58163209 -0.92727982 1 P 0 N
A 2.55001998 -1.14328002 2.52723002 -1.12986004 2.51462185 -1.17733228 1 P 0 N
L 2.46181004 -1.12868996 2.36843996 -1.12868996 1 P 0 
A 2.36843996 -1.12868996 2.37851998 -1.15751998 2.41186801 -1.12968307 1 P 0 N
L 2.34675 -1.1402 2.34675 -1.11835 1 P 8191 
L 2.46181004 -1.11835 2.46181004 -1.12868996 1 P 8191 
L 2.25188002 -1.11398996 2.25188002 -1.11418002 1 P 8191 
A 2.3208 -1.02041004 2.3006 -1.02033996 2.31069163 -1.02276978 1 P 0 N
L 2.27413002 -1.11835 2.27413002 -1.12868996 1 P 8191 
A 2.52848996 -1.16771004 2.54891998 -1.15895 2.52774557 -1.13777087 1 P 0 N
A 2.55608002 -1.08618002 2.53611998 -1.07688996 2.5249185 -1.12704419 1 P 0 N
L 2.71926004 -1.06796998 2.71926004 -1.17483996 1 P 0 
A 2.78888996 -1.16296998 2.81508002 -1.16676998 2.8083499 -1.12100167 1 P 0 N
A 2.8151 -1.16675 2.83966004 -1.15211998 2.80521398 -1.12222392 1 P 0 N
A 2.85201004 -1.16508002 2.83966004 -1.15211004 2.84505768 -1.15933514 1 P 0 N
L 2.85201004 -1.16508002 2.84523996 -1.17161004 1 P 8191 
A 2.81425 -1.1835 2.84525 -1.17161004 2.81425 -1.13714291 1 P 0 N
L 2.81425 -1.1835 2.79571004 -1.1835 1 P 8191 
A 2.75886998 -1.16443002 2.79571998 -1.18351998 2.80278976 -1.12476142 1 P 0 N
A 2.74528996 -1.13568002 2.75888002 -1.16443002 2.80246565 -1.12624016 1 P 0 N
A 2.54316998 -1.1834 2.56906004 -1.1647 2.5305814 -1.13869892 1 P 0 N
A 2.56906004 -1.1647 2.57053996 -1.13728002 2.53763041 -1.14925374 1 P 0 N
A 2.65463996 -1.18351998 2.66863996 -1.17373996 2.65440246 -1.16826969 1 P 0 N
L 2.65463002 -1.1835 2.64165 -1.1835 1 P 8191 
A 2.60955 -1.16043002 2.64163996 -1.18351004 2.63911063 -1.15317815 1 P 0 N
A 2.62978002 -1.15461998 2.66001998 -1.16328996 2.6502374 -1.14033868 1 P 0 N
A 2.66863996 -1.17375 2.66001998 -1.16328996 2.66100344 -1.17126132 1 P 0 N
A 2.6962 -1.17483996 2.71926004 -1.17483996 2.70773002 -1.17286427 1 P 0 N
L 2.69618996 -1.17483996 2.69618996 -1.06796998 1 P 0 
A 2.83833002 -1.09275 2.82661998 -1.08201998 2.74555758 -1.18224094 1 P 0 N
A 2.82661998 -1.08198996 2.80036998 -1.07538996 2.80348839 -1.11848878 1 P 0 N
A 2.80036004 -1.07541998 2.76848996 -1.09933002 2.80700217 -1.1174685 1 P 0 N
A 2.76848996 -1.09931998 2.76446004 -1.12066004 2.82315728 -1.120694 1 P 0 N
A 2.74998002 -1.09273996 2.74528996 -1.11838996 2.8498563 -1.12425591 1 P 0 N
A 2.7954 -1.05776998 2.74998996 -1.09273996 2.80799961 -1.12109961 1 P 0 N
L 2.79541004 -1.05776998 2.80918996 -1.05776998 1 P 8191 
A 2.85401998 -1.08106004 2.80918996 -1.05776998 2.80626024 -1.1181998 1 P 0 N
A 2.83833002 -1.09273996 2.85403002 -1.08106004 2.84418386 -1.08421683 1 P 0 N
L 2.76445 -1.12066004 2.76445 -1.12943002 1 P 8191 
A 2.76446004 -1.12943002 2.76836998 -1.14305 2.80607844 -1.12485364 1 P 0 N
A 2.76836998 -1.14305 2.78891004 -1.16296998 2.80906152 -1.12164144 1 P 0 N
L 2.74528996 -1.13566004 2.74528996 -1.11838996 1 P 8191 
A 2.55606004 -1.0862 2.56885 -1.07366998 2.56205354 -1.0795252 1 P 0 N
L 2.60953996 -1.07953996 2.59981998 -1.07953996 1 P 8191 
A 2.5993 -1.05931998 2.59981004 -1.07955 2.6022813 -1.06936624 1 P 0 N
L 2.5993 -1.05931998 2.60953996 -1.05931998 1 P 8191 
L 2.60953996 -1.05931998 2.60953996 -1.03491998 1 P 8191 
A 2.62971998 -1.03418002 2.60953996 -1.03491004 2.61966791 -1.03559478 1 P 0 N
L 2.62971004 -1.03418996 2.62978002 -1.05931998 1 P 8191 
L 2.62978002 -1.05931998 2.66008002 -1.05931998 1 P 8191 
A 2.66003996 -1.07955 2.66008002 -1.05931998 2.65827421 -1.0694314 1 P 0 N
L 2.66003002 -1.07953996 2.62978002 -1.07953996 1 P 8191 
A 2.71926004 -1.06796998 2.6962 -1.06796998 2.70773002 -1.0720561 1 P 0 N
A 2.71968996 -1.02341998 2.71968996 -1.02341998 2.70775 -1.02341998 1 P 0 N
A 2.57053996 -1.13728996 2.54306998 -1.11513002 2.53584449 -1.15219301 1 P 0 N
A 2.54891998 -1.15895 2.55001004 -1.14328002 2.54127923 -1.15054557 1 P 0 N
L 2.60953996 -1.16041004 2.60953996 -1.07953996 1 P 0 
L 2.62978002 -1.07953996 2.62978002 -1.15463002 1 P 0 
L 2.98495 -1.09393996 2.98495 -1.17625 1 P 0 
A 2.96473996 -1.17626998 2.98493996 -1.17626998 2.97483996 -1.17442303 1 P 0 N
L 2.96473002 -1.17625 2.96473002 -1.17226004 1 P 8191 
A 2.94165 -1.1835 2.96471004 -1.17226004 2.93076516 -1.1318935 1 P 0 N
L 2.94165 -1.1835 2.90701004 -1.1835 1 P 8191 
A 2.90671004 -1.10841998 2.90703002 -1.18351004 2.9153065 -1.14592904 1 P 0 N
A 2.91853002 -1.12288996 2.91853002 -1.16618996 2.92048209 -1.14453996 1 P 0 N
L 2.91853002 -1.1662 2.94456004 -1.1662 1 P 8191 
A 2.94456998 -1.16618996 2.94456998 -1.12288996 2.94406004 -1.14453996 1 P 0 N
A 2.96473002 -1.09686004 2.94741998 -1.07955 2.94874833 -1.09553169 1 P 0 N
L 2.9474 -1.07953996 2.90986998 -1.07953996 1 P 8191 
A 2.90986998 -1.07953996 2.89821004 -1.0852 2.92433445 -1.12417766 1 P 0 N
A 2.89111998 -1.07086004 2.8982 -1.0852 2.8969689 -1.07688996 1 P 0 N
A 2.91561998 -1.05931998 2.89111998 -1.07085 2.92146033 -1.103525 1 P 0 N
L 2.91563002 -1.05931998 2.95031004 -1.05931998 1 P 8191 
A 2.98496004 -1.09393996 2.95031004 -1.05933002 2.9453438 -1.09895197 1 P 0 N
A 2.92878996 -1.10535 2.9067 -1.10841998 2.93158484 -1.20646998 1 P 0 N
A 2.96471998 -1.10841004 2.92878002 -1.10536004 2.93215738 -1.27883829 1 P 0 N
L 2.96473002 -1.10841004 2.96473002 -1.09686004 1 P 8191 
L 2.94456004 -1.12288002 2.91853002 -1.12288002 1 P 8191 
L 3.04731004 -1.06001004 3.04191998 -1.07631998 1 P 8191 
L 3.04191998 -1.07631998 3.03648002 -1.06001004 1 P 8191 
L 3.03648002 -1.06001004 3.03243002 -1.06001004 1 P 8191 
L 3.03243002 -1.06001004 3.02698002 -1.08543996 1 P 8191 
L 3.02698002 -1.08543996 3.03226004 -1.08543996 1 P 8191 
L 3.03226004 -1.08543996 3.03501004 -1.06886998 1 P 8191 
L 3.03501004 -1.06886998 3.04086004 -1.08543996 1 P 8191 
L 3.04086004 -1.08543996 3.04308996 -1.08543996 1 P 8191 
L 3.04308996 -1.08543996 3.04888996 -1.06871004 1 P 8191 
L 3.04888996 -1.06871004 3.05171004 -1.08543996 1 P 8191 
L 3.05171004 -1.08543996 3.05713002 -1.08543996 1 P 8191 
L 3.05713002 -1.08543996 3.05163996 -1.06001004 1 P 8191 
L 3.05163996 -1.06001004 3.04731004 -1.06001004 1 P 8191 
L 3.01066998 -1.06508002 3.00223002 -1.06508002 1 P 8191 
L 3.00223002 -1.06508002 3.00223002 -1.06001004 1 P 8191 
L 3.00223002 -1.06001004 3.02461004 -1.06001004 1 P 8191 
L 3.02461004 -1.06001004 3.02461004 -1.06508002 1 P 8191 
L 3.02461004 -1.06508002 3.01615 -1.06508002 1 P 8191 
L 3.01615 -1.06508002 3.01615 -1.08533996 1 P 8191 
L 3.01615 -1.08533996 3.01066998 -1.08533996 1 P 8191 
L 3.01066998 -1.08533996 3.01066998 -1.06508002 1 P 8191 
L 3.36933297 -0.955 3.36933297 -0.88 0 P 0 ;1,3=16,5=0.000000
L 3.36933297 -0.88 3.39173337 -0.88 0 P 0 ;1,3=16,5=0.000000
L 3.39173337 -0.88 3.3992001 -0.88375157 0 P 0 ;1,3=16,5=0.000000
L 3.3992001 -0.88375157 3.40480059 -0.8924997 0 P 0 ;1,3=16,5=0.000000
L 3.40480059 -0.8924997 3.40666693 -0.9024998 0 P 0 ;1,3=16,5=0.000000
L 3.40666693 -0.9024998 3.40480059 -0.9125 0 P 0 ;1,3=16,5=0.000000
L 3.40480059 -0.9125 3.40013327 -0.92000069 0 P 0 ;1,3=16,5=0.000000
L 3.40013327 -0.92000069 3.39173337 -0.92375217 0 P 0 ;1,3=16,5=0.000000
L 3.39173337 -0.92375217 3.36933297 -0.92375217 0 P 0 ;1,3=16,5=0.000000
L 3.44619931 -0.95749941 3.47980059 -0.88 0 P 0 ;1,3=16,5=0.000000
L 3.51653356 -0.955 3.51653356 -0.88 0 P 0 ;1,3=16,5=0.000000
L 3.51653356 -0.88 3.55946634 -0.955 0 P 0 ;1,3=16,5=0.000000
L 3.55946634 -0.955 3.55946634 -0.88 0 P 0 ;1,3=16,5=0.000000
L 3.68799911 -0.95749941 3.68613287 -0.9562497 0 P 0 ;1,3=16,5=0.000000
L 3.68613287 -0.9562497 3.68613287 -0.9537503 0 P 0 ;1,3=16,5=0.000000
L 3.68613287 -0.9537503 3.68799911 -0.95250059 0 P 0 ;1,3=16,5=0.000000
L 3.68799911 -0.95250059 3.68986703 -0.9537503 0 P 0 ;1,3=16,5=0.000000
L 3.68986703 -0.9537503 3.68986703 -0.9562497 0 P 0 ;1,3=16,5=0.000000
L 3.68986703 -0.9562497 3.68799911 -0.95749941 0 P 0 ;1,3=16,5=0.000000
L 3.68799911 -0.92375217 3.68613287 -0.9225001 0 P 0 ;1,3=16,5=0.000000
L 3.68613287 -0.9225001 3.68613287 -0.92000069 0 P 0 ;1,3=16,5=0.000000
L 3.68613287 -0.92000069 3.68799911 -0.91875089 0 P 0 ;1,3=16,5=0.000000
L 3.68799911 -0.91875089 3.68986703 -0.92000069 0 P 0 ;1,3=16,5=0.000000
L 3.68986703 -0.92000069 3.68986703 -0.9225001 0 P 0 ;1,3=16,5=0.000000
L 3.68986703 -0.9225001 3.68799911 -0.92375217 0 P 0 ;1,3=16,5=0.000000
L 3.81933297 -0.955 3.81933297 -0.88 0 P 0 ;1,3=16,5=0.000000
L 3.81933297 -0.88 3.84266644 -0.88 0 P 0 ;1,3=16,5=0.000000
L 3.84266644 -0.88 3.85013327 -0.88375157 0 P 0 ;1,3=16,5=0.000000
L 3.85013327 -0.88375157 3.85480059 -0.88875049 0 P 0 ;1,3=16,5=0.000000
L 3.85480059 -0.88875049 3.85666693 -0.89875059 0 P 0 ;1,3=16,5=0.000000
L 3.85666693 -0.89875059 3.85480059 -0.90875079 0 P 0 ;1,3=16,5=0.000000
L 3.85480059 -0.90875079 3.8492001 -0.91499941 0 P 0 ;1,3=16,5=0.000000
L 3.8492001 -0.91499941 3.84266644 -0.91875089 0 P 0 ;1,3=16,5=0.000000
L 3.84266644 -0.91875089 3.81933297 -0.91875089 0 P 0 ;1,3=16,5=0.000000
L 3.84266644 -0.91875089 3.85666693 -0.955 0 P 0 ;1,3=16,5=0.000000
L 3.9242001 -0.955 3.9242001 -0.88 0 P 0 ;1,3=16,5=0.000000
L 3.9242001 -0.88 3.88966565 -0.93375 0 P 0 ;1,3=16,5=0.000000
L 3.88966565 -0.93375 3.93633425 -0.93375 0 P 0 ;1,3=16,5=0.000000
L 3.98799911 -0.88 3.98053228 -0.88249951 0 P 0 ;1,3=16,5=0.000000
L 3.98053228 -0.88249951 3.97493346 -0.88875049 0 P 0 ;1,3=16,5=0.000000
L 3.97493346 -0.88875049 3.97119931 -0.89624882 0 P 0 ;1,3=16,5=0.000000
L 3.97119931 -0.89624882 3.9683999 -0.90625128 0 P 0 ;1,3=16,5=0.000000
L 3.9683999 -0.90625128 3.96746673 -0.91750118 0 P 0 ;1,3=16,5=0.000000
L 3.96746673 -0.91750118 3.9683999 -0.92875108 0 P 0 ;1,3=16,5=0.000000
L 3.9683999 -0.92875108 3.97119931 -0.93875128 0 P 0 ;1,3=16,5=0.000000
L 3.97119931 -0.93875128 3.97493346 -0.94625187 0 P 0 ;1,3=16,5=0.000000
L 3.97493346 -0.94625187 3.98053228 -0.95250059 0 P 0 ;1,3=16,5=0.000000
L 3.98053228 -0.95250059 3.98799911 -0.955 0 P 0 ;1,3=16,5=0.000000
L 3.98799911 -0.955 3.99546585 -0.95250059 0 P 0 ;1,3=16,5=0.000000
L 3.99546585 -0.95250059 4.00106644 -0.94625187 0 P 0 ;1,3=16,5=0.000000
L 4.00106644 -0.94625187 4.00480059 -0.93875128 0 P 0 ;1,3=16,5=0.000000
L 4.00480059 -0.93875128 4.0076 -0.92875108 0 P 0 ;1,3=16,5=0.000000
L 4.0076 -0.92875108 4.00853317 -0.91750118 0 P 0 ;1,3=16,5=0.000000
L 4.00853317 -0.91750118 4.0076 -0.90625128 0 P 0 ;1,3=16,5=0.000000
L 4.0076 -0.90625128 4.00480059 -0.89624882 0 P 0 ;1,3=16,5=0.000000
L 4.00480059 -0.89624882 4.00106644 -0.88875049 0 P 0 ;1,3=16,5=0.000000
L 4.00106644 -0.88875049 3.99546585 -0.88249951 0 P 0 ;1,3=16,5=0.000000
L 3.99546585 -0.88249951 3.98799911 -0.88 0 P 0 ;1,3=16,5=0.000000
L 4.06299911 -0.88 4.05553228 -0.88249951 0 P 0 ;1,3=16,5=0.000000
L 4.05553228 -0.88249951 4.04993346 -0.88875049 0 P 0 ;1,3=16,5=0.000000
L 4.04993346 -0.88875049 4.04619931 -0.89624882 0 P 0 ;1,3=16,5=0.000000
L 4.04619931 -0.89624882 4.0433999 -0.90625128 0 P 0 ;1,3=16,5=0.000000
L 4.0433999 -0.90625128 4.04246673 -0.91750118 0 P 0 ;1,3=16,5=0.000000
L 4.04246673 -0.91750118 4.0433999 -0.92875108 0 P 0 ;1,3=16,5=0.000000
L 4.0433999 -0.92875108 4.04619931 -0.93875128 0 P 0 ;1,3=16,5=0.000000
L 4.04619931 -0.93875128 4.04993346 -0.94625187 0 P 0 ;1,3=16,5=0.000000
L 4.04993346 -0.94625187 4.05553228 -0.95250059 0 P 0 ;1,3=16,5=0.000000
L 4.05553228 -0.95250059 4.06299911 -0.955 0 P 0 ;1,3=16,5=0.000000
L 4.06299911 -0.955 4.07046585 -0.95250059 0 P 0 ;1,3=16,5=0.000000
L 4.07046585 -0.95250059 4.07606644 -0.94625187 0 P 0 ;1,3=16,5=0.000000
L 4.07606644 -0.94625187 4.07980059 -0.93875128 0 P 0 ;1,3=16,5=0.000000
L 4.07980059 -0.93875128 4.0826 -0.92875108 0 P 0 ;1,3=16,5=0.000000
L 4.0826 -0.92875108 4.08353317 -0.91750118 0 P 0 ;1,3=16,5=0.000000
L 4.08353317 -0.91750118 4.0826 -0.90625128 0 P 0 ;1,3=16,5=0.000000
L 4.0826 -0.90625128 4.07980059 -0.89624882 0 P 0 ;1,3=16,5=0.000000
L 4.07980059 -0.89624882 4.07606644 -0.88875049 0 P 0 ;1,3=16,5=0.000000
L 4.07606644 -0.88875049 4.07046585 -0.88249951 0 P 0 ;1,3=16,5=0.000000
L 4.07046585 -0.88249951 4.06299911 -0.88 0 P 0 ;1,3=16,5=0.000000
L 4.12026614 -0.92375217 4.1267998 -0.91499941 0 P 0 ;1,3=16,5=0.000000
L 4.1267998 -0.91499941 4.1324003 -0.91000049 0 P 0 ;1,3=16,5=0.000000
L 4.1324003 -0.91000049 4.13986703 -0.90750108 0 P 0 ;1,3=16,5=0.000000
L 4.13986703 -0.90750108 4.14640069 -0.91000049 0 P 0 ;1,3=16,5=0.000000
L 4.14640069 -0.91000049 4.15106644 -0.91499941 0 P 0 ;1,3=16,5=0.000000
L 4.15106644 -0.91499941 4.15480059 -0.9225001 0 P 0 ;1,3=16,5=0.000000
L 4.15480059 -0.9225001 4.15573376 -0.93125059 0 P 0 ;1,3=16,5=0.000000
L 4.15573376 -0.93125059 4.15480059 -0.93875128 0 P 0 ;1,3=16,5=0.000000
L 4.15480059 -0.93875128 4.15106644 -0.94625187 0 P 0 ;1,3=16,5=0.000000
L 4.15106644 -0.94625187 4.14546585 -0.95250059 0 P 0 ;1,3=16,5=0.000000
L 4.14546585 -0.95250059 4.13893396 -0.955 0 P 0 ;1,3=16,5=0.000000
L 4.13893396 -0.955 4.13146713 -0.95250059 0 P 0 ;1,3=16,5=0.000000
L 4.13146713 -0.95250059 4.12493346 -0.94500217 0 P 0 ;1,3=16,5=0.000000
L 4.12493346 -0.94500217 4.12119931 -0.93375 0 P 0 ;1,3=16,5=0.000000
L 4.12119931 -0.93375 4.12026614 -0.92125039 0 P 0 ;1,3=16,5=0.000000
L 4.12026614 -0.92125039 4.12213238 -0.90500157 0 P 0 ;1,3=16,5=0.000000
L 4.12213238 -0.90500157 4.12493346 -0.89624882 0 P 0 ;1,3=16,5=0.000000
L 4.12493346 -0.89624882 4.12959921 -0.88750069 0 P 0 ;1,3=16,5=0.000000
L 4.12959921 -0.88750069 4.13613287 -0.8812498 0 P 0 ;1,3=16,5=0.000000
L 4.13613287 -0.8812498 4.14266644 -0.88 0 P 0 ;1,3=16,5=0.000000
L 4.14266644 -0.88 4.1492001 -0.88249951 0 P 0 ;1,3=16,5=0.000000
L 4.1492001 -0.88249951 4.15386752 -0.88875049 0 P 0 ;1,3=16,5=0.000000
L 4.20086663 -0.93000079 4.22513327 -0.93000079 0 P 0 ;1,3=16,5=0.000000
L 4.29546585 -0.91499941 4.2992001 -0.9112502 0 P 0 ;1,3=16,5=0.000000
L 4.2992001 -0.9112502 4.30199951 -0.90500157 0 P 0 ;1,3=16,5=0.000000
L 4.30199951 -0.90500157 4.30386752 -0.89624882 0 P 0 ;1,3=16,5=0.000000
L 4.30386752 -0.89624882 4.30199951 -0.88875049 0 P 0 ;1,3=16,5=0.000000
L 4.30199951 -0.88875049 4.29826703 -0.88375157 0 P 0 ;1,3=16,5=0.000000
L 4.29826703 -0.88375157 4.29173337 -0.88 0 P 0 ;1,3=16,5=0.000000
L 4.29173337 -0.88 4.26653356 -0.88 0 P 0 ;1,3=16,5=0.000000
L 4.26653356 -0.88 4.26653356 -0.955 0 P 0 ;1,3=16,5=0.000000
L 4.26653356 -0.955 4.29733386 -0.955 0 P 0 ;1,3=16,5=0.000000
L 4.29733386 -0.955 4.30386752 -0.95000108 0 P 0 ;1,3=16,5=0.000000
L 4.30386752 -0.95000108 4.3076 -0.94250039 0 P 0 ;1,3=16,5=0.000000
L 4.3076 -0.94250039 4.30946634 -0.93375 0 P 0 ;1,3=16,5=0.000000
L 4.30946634 -0.93375 4.3076 -0.92500187 0 P 0 ;1,3=16,5=0.000000
L 4.3076 -0.92500187 4.30199951 -0.91750118 0 P 0 ;1,3=16,5=0.000000
L 4.30199951 -0.91750118 4.29546585 -0.91499941 0 P 0 ;1,3=16,5=0.000000
L 4.29546585 -0.91499941 4.26653356 -0.91499941 0 P 0 ;1,3=16,5=0.000000
L 4.36299911 -0.88 4.35553228 -0.88249951 0 P 0 ;1,3=16,5=0.000000
L 4.35553228 -0.88249951 4.34993346 -0.88875049 0 P 0 ;1,3=16,5=0.000000
L 4.34993346 -0.88875049 4.34619931 -0.89624882 0 P 0 ;1,3=16,5=0.000000
L 4.34619931 -0.89624882 4.3433999 -0.90625128 0 P 0 ;1,3=16,5=0.000000
L 4.3433999 -0.90625128 4.34246673 -0.91750118 0 P 0 ;1,3=16,5=0.000000
L 4.34246673 -0.91750118 4.3433999 -0.92875108 0 P 0 ;1,3=16,5=0.000000
L 4.3433999 -0.92875108 4.34619931 -0.93875128 0 P 0 ;1,3=16,5=0.000000
L 4.34619931 -0.93875128 4.34993346 -0.94625187 0 P 0 ;1,3=16,5=0.000000
L 4.34993346 -0.94625187 4.35553228 -0.95250059 0 P 0 ;1,3=16,5=0.000000
L 4.35553228 -0.95250059 4.36299911 -0.955 0 P 0 ;1,3=16,5=0.000000
L 4.36299911 -0.955 4.37046585 -0.95250059 0 P 0 ;1,3=16,5=0.000000
L 4.37046585 -0.95250059 4.37606644 -0.94625187 0 P 0 ;1,3=16,5=0.000000
L 4.37606644 -0.94625187 4.37980059 -0.93875128 0 P 0 ;1,3=16,5=0.000000
L 4.37980059 -0.93875128 4.3826 -0.92875108 0 P 0 ;1,3=16,5=0.000000
L 4.3826 -0.92875108 4.38353317 -0.91750118 0 P 0 ;1,3=16,5=0.000000
L 4.38353317 -0.91750118 4.3826 -0.90625128 0 P 0 ;1,3=16,5=0.000000
L 4.3826 -0.90625128 4.37980059 -0.89624882 0 P 0 ;1,3=16,5=0.000000
L 4.37980059 -0.89624882 4.37606644 -0.88875049 0 P 0 ;1,3=16,5=0.000000
L 4.37606644 -0.88875049 4.37046585 -0.88249951 0 P 0 ;1,3=16,5=0.000000
L 4.37046585 -0.88249951 4.36299911 -0.88 0 P 0 ;1,3=16,5=0.000000
L 4.43799911 -0.88 4.43053228 -0.88249951 0 P 0 ;1,3=16,5=0.000000
L 4.43053228 -0.88249951 4.42493346 -0.88875049 0 P 0 ;1,3=16,5=0.000000
L 4.42493346 -0.88875049 4.42119931 -0.89624882 0 P 0 ;1,3=16,5=0.000000
L 4.42119931 -0.89624882 4.4183999 -0.90625128 0 P 0 ;1,3=16,5=0.000000
L 4.4183999 -0.90625128 4.41746673 -0.91750118 0 P 0 ;1,3=16,5=0.000000
L 4.41746673 -0.91750118 4.4183999 -0.92875108 0 P 0 ;1,3=16,5=0.000000
L 4.4183999 -0.92875108 4.42119931 -0.93875128 0 P 0 ;1,3=16,5=0.000000
L 4.42119931 -0.93875128 4.42493346 -0.94625187 0 P 0 ;1,3=16,5=0.000000
L 4.42493346 -0.94625187 4.43053228 -0.95250059 0 P 0 ;1,3=16,5=0.000000
L 4.43053228 -0.95250059 4.43799911 -0.955 0 P 0 ;1,3=16,5=0.000000
L 4.43799911 -0.955 4.44546585 -0.95250059 0 P 0 ;1,3=16,5=0.000000
L 4.44546585 -0.95250059 4.45106644 -0.94625187 0 P 0 ;1,3=16,5=0.000000
L 4.45106644 -0.94625187 4.45480059 -0.93875128 0 P 0 ;1,3=16,5=0.000000
L 4.45480059 -0.93875128 4.4576 -0.92875108 0 P 0 ;1,3=16,5=0.000000
L 4.4576 -0.92875108 4.45853317 -0.91750118 0 P 0 ;1,3=16,5=0.000000
L 4.45853317 -0.91750118 4.4576 -0.90625128 0 P 0 ;1,3=16,5=0.000000
L 4.4576 -0.90625128 4.45480059 -0.89624882 0 P 0 ;1,3=16,5=0.000000
L 4.45480059 -0.89624882 4.45106644 -0.88875049 0 P 0 ;1,3=16,5=0.000000
L 4.45106644 -0.88875049 4.44546585 -0.88249951 0 P 0 ;1,3=16,5=0.000000
L 4.44546585 -0.88249951 4.43799911 -0.88 0 P 0 ;1,3=16,5=0.000000
L 4.51299911 -0.88 4.50553228 -0.88249951 0 P 0 ;1,3=16,5=0.000000
L 4.50553228 -0.88249951 4.49993346 -0.88875049 0 P 0 ;1,3=16,5=0.000000
L 4.49993346 -0.88875049 4.49619931 -0.89624882 0 P 0 ;1,3=16,5=0.000000
L 4.49619931 -0.89624882 4.4933999 -0.90625128 0 P 0 ;1,3=16,5=0.000000
L 4.4933999 -0.90625128 4.49246673 -0.91750118 0 P 0 ;1,3=16,5=0.000000
L 4.49246673 -0.91750118 4.4933999 -0.92875108 0 P 0 ;1,3=16,5=0.000000
L 4.4933999 -0.92875108 4.49619931 -0.93875128 0 P 0 ;1,3=16,5=0.000000
L 4.49619931 -0.93875128 4.49993346 -0.94625187 0 P 0 ;1,3=16,5=0.000000
L 4.49993346 -0.94625187 4.50553228 -0.95250059 0 P 0 ;1,3=16,5=0.000000
L 4.50553228 -0.95250059 4.51299911 -0.955 0 P 0 ;1,3=16,5=0.000000
L 4.51299911 -0.955 4.52046585 -0.95250059 0 P 0 ;1,3=16,5=0.000000
L 4.52046585 -0.95250059 4.52606644 -0.94625187 0 P 0 ;1,3=16,5=0.000000
L 4.52606644 -0.94625187 4.52980059 -0.93875128 0 P 0 ;1,3=16,5=0.000000
L 4.52980059 -0.93875128 4.5326 -0.92875108 0 P 0 ;1,3=16,5=0.000000
L 4.5326 -0.92875108 4.53353317 -0.91750118 0 P 0 ;1,3=16,5=0.000000
L 4.53353317 -0.91750118 4.5326 -0.90625128 0 P 0 ;1,3=16,5=0.000000
L 4.5326 -0.90625128 4.52980059 -0.89624882 0 P 0 ;1,3=16,5=0.000000
L 4.52980059 -0.89624882 4.52606644 -0.88875049 0 P 0 ;1,3=16,5=0.000000
L 4.52606644 -0.88875049 4.52046585 -0.88249951 0 P 0 ;1,3=16,5=0.000000
L 4.52046585 -0.88249951 4.51299911 -0.88 0 P 0 ;1,3=16,5=0.000000
L 4.58799911 -0.955 4.58799911 -0.88 0 P 0 ;1,3=16,5=0.000000
L 4.58799911 -0.88 4.5767998 -0.89499911 0 P 0 ;1,3=16,5=0.000000
L 4.5767998 -0.955 4.59919843 -0.955 0 P 0 ;1,3=16,5=0.000000
L 4.65086663 -0.93000079 4.67513327 -0.93000079 0 P 0 ;1,3=16,5=0.000000
L 4.73799911 -0.88 4.73053228 -0.88249951 0 P 0 ;1,3=16,5=0.000000
L 4.73053228 -0.88249951 4.72493346 -0.88875049 0 P 0 ;1,3=16,5=0.000000
L 4.72493346 -0.88875049 4.72119931 -0.89624882 0 P 0 ;1,3=16,5=0.000000
L 4.72119931 -0.89624882 4.7183999 -0.90625128 0 P 0 ;1,3=16,5=0.000000
L 4.7183999 -0.90625128 4.71746673 -0.91750118 0 P 0 ;1,3=16,5=0.000000
L 4.71746673 -0.91750118 4.7183999 -0.92875108 0 P 0 ;1,3=16,5=0.000000
L 4.7183999 -0.92875108 4.72119931 -0.93875128 0 P 0 ;1,3=16,5=0.000000
L 4.72119931 -0.93875128 4.72493346 -0.94625187 0 P 0 ;1,3=16,5=0.000000
L 4.72493346 -0.94625187 4.73053228 -0.95250059 0 P 0 ;1,3=16,5=0.000000
L 4.73053228 -0.95250059 4.73799911 -0.955 0 P 0 ;1,3=16,5=0.000000
L 4.73799911 -0.955 4.74546585 -0.95250059 0 P 0 ;1,3=16,5=0.000000
L 4.74546585 -0.95250059 4.75106644 -0.94625187 0 P 0 ;1,3=16,5=0.000000
L 4.75106644 -0.94625187 4.75480059 -0.93875128 0 P 0 ;1,3=16,5=0.000000
L 4.75480059 -0.93875128 4.7576 -0.92875108 0 P 0 ;1,3=16,5=0.000000
L 4.7576 -0.92875108 4.75853317 -0.91750118 0 P 0 ;1,3=16,5=0.000000
L 4.75853317 -0.91750118 4.7576 -0.90625128 0 P 0 ;1,3=16,5=0.000000
L 4.7576 -0.90625128 4.75480059 -0.89624882 0 P 0 ;1,3=16,5=0.000000
L 4.75480059 -0.89624882 4.75106644 -0.88875049 0 P 0 ;1,3=16,5=0.000000
L 4.75106644 -0.88875049 4.74546585 -0.88249951 0 P 0 ;1,3=16,5=0.000000
L 4.74546585 -0.88249951 4.73799911 -0.88 0 P 0 ;1,3=16,5=0.000000
L 4.79526614 -0.8924997 4.80086663 -0.88500128 0 P 0 ;1,3=16,5=0.000000
L 4.80086663 -0.88500128 4.8074003 -0.8812498 0 P 0 ;1,3=16,5=0.000000
L 4.8074003 -0.8812498 4.81486703 -0.88 0 P 0 ;1,3=16,5=0.000000
L 4.81486703 -0.88 4.8242001 -0.88249951 0 P 0 ;1,3=16,5=0.000000
L 4.8242001 -0.88249951 4.83073376 -0.88875049 0 P 0 ;1,3=16,5=0.000000
L 4.83073376 -0.88875049 4.8326 -0.89624882 0 P 0 ;1,3=16,5=0.000000
L 4.8326 -0.89624882 4.83166693 -0.90375187 0 P 0 ;1,3=16,5=0.000000
L 4.83166693 -0.90375187 4.82793268 -0.91000049 0 P 0 ;1,3=16,5=0.000000
L 4.82793268 -0.91000049 4.80926654 -0.9225001 0 P 0 ;1,3=16,5=0.000000
L 4.80926654 -0.9225001 4.80086663 -0.93125059 0 P 0 ;1,3=16,5=0.000000
L 4.80086663 -0.93125059 4.79526614 -0.94375246 0 P 0 ;1,3=16,5=0.000000
L 4.79526614 -0.94375246 4.7933999 -0.955 0 P 0 ;1,3=16,5=0.000000
L 4.7933999 -0.955 4.8326 -0.955 0 P 0 ;1,3=16,5=0.000000
L 3.36746673 -1.205 3.36746673 -1.13 0 P 0 ;1,3=17,5=0.000000
L 3.36746673 -1.13 3.38613287 -1.13 0 P 0 ;1,3=17,5=0.000000
L 3.38613287 -1.13 3.39359961 -1.13375157 0 P 0 ;1,3=17,5=0.000000
L 3.39359961 -1.13375157 3.3992001 -1.13875049 0 P 0 ;1,3=17,5=0.000000
L 3.3992001 -1.13875049 3.40386752 -1.14624882 0 P 0 ;1,3=17,5=0.000000
L 3.40386752 -1.14624882 3.4076 -1.15500157 0 P 0 ;1,3=17,5=0.000000
L 3.4076 -1.15500157 3.40853317 -1.16750118 0 P 0 ;1,3=17,5=0.000000
L 3.40853317 -1.16750118 3.4076 -1.18000079 0 P 0 ;1,3=17,5=0.000000
L 3.4076 -1.18000079 3.40386752 -1.18875128 0 P 0 ;1,3=17,5=0.000000
L 3.40386752 -1.18875128 3.3992001 -1.19625187 0 P 0 ;1,3=17,5=0.000000
L 3.3992001 -1.19625187 3.39359961 -1.20125089 0 P 0 ;1,3=17,5=0.000000
L 3.39359961 -1.20125089 3.38613287 -1.205 0 P 0 ;1,3=17,5=0.000000
L 3.38613287 -1.205 3.36746673 -1.205 0 P 0 ;1,3=17,5=0.000000
L 3.47980059 -1.205 3.47980059 -1.15500157 0 P 0 ;1,3=17,5=0.000000
L 3.47980059 -1.1637497 3.47606644 -1.15875079 0 P 0 ;1,3=17,5=0.000000
L 3.47606644 -1.15875079 3.47046585 -1.15625128 0 P 0 ;1,3=17,5=0.000000
L 3.47046585 -1.15625128 3.46393396 -1.15500157 0 P 0 ;1,3=17,5=0.000000
L 3.46393396 -1.15500157 3.4574003 -1.15750108 0 P 0 ;1,3=17,5=0.000000
L 3.4574003 -1.15750108 3.4517998 -1.1625 0 P 0 ;1,3=17,5=0.000000
L 3.4517998 -1.1625 3.44806555 -1.17000069 0 P 0 ;1,3=17,5=0.000000
L 3.44806555 -1.17000069 3.44619931 -1.18000079 0 P 0 ;1,3=17,5=0.000000
L 3.44619931 -1.18000079 3.44806555 -1.19000098 0 P 0 ;1,3=17,5=0.000000
L 3.44806555 -1.19000098 3.4517998 -1.19750167 0 P 0 ;1,3=17,5=0.000000
L 3.4517998 -1.19750167 3.4574003 -1.20250059 0 P 0 ;1,3=17,5=0.000000
L 3.4574003 -1.20250059 3.46393396 -1.205 0 P 0 ;1,3=17,5=0.000000
L 3.46393396 -1.205 3.47046585 -1.2037503 0 P 0 ;1,3=17,5=0.000000
L 3.47046585 -1.2037503 3.47606644 -1.20000108 0 P 0 ;1,3=17,5=0.000000
L 3.47606644 -1.20000108 3.47980059 -1.19500217 0 P 0 ;1,3=17,5=0.000000
L 3.53799911 -1.13 3.53799911 -1.205 0 P 0 ;1,3=17,5=0.000000
L 3.52493346 -1.15500157 3.55106644 -1.15500157 0 P 0 ;1,3=17,5=0.000000
L 3.59900039 -1.17125039 3.62886752 -1.17125039 0 P 0 ;1,3=17,5=0.000000
L 3.62886752 -1.17125039 3.62606644 -1.1625 0 P 0 ;1,3=17,5=0.000000
L 3.62606644 -1.1625 3.62140069 -1.15750108 0 P 0 ;1,3=17,5=0.000000
L 3.62140069 -1.15750108 3.61486703 -1.15500157 0 P 0 ;1,3=17,5=0.000000
L 3.61486703 -1.15500157 3.60833346 -1.15625128 0 P 0 ;1,3=17,5=0.000000
L 3.60833346 -1.15625128 3.60273287 -1.16000049 0 P 0 ;1,3=17,5=0.000000
L 3.60273287 -1.16000049 3.59900039 -1.16875089 0 P 0 ;1,3=17,5=0.000000
L 3.59900039 -1.16875089 3.59713238 -1.17625157 0 P 0 ;1,3=17,5=0.000000
L 3.59713238 -1.17625157 3.59713238 -1.18375 0 P 0 ;1,3=17,5=0.000000
L 3.59713238 -1.18375 3.59900039 -1.19125069 0 P 0 ;1,3=17,5=0.000000
L 3.59900039 -1.19125069 3.60366604 -1.19875138 0 P 0 ;1,3=17,5=0.000000
L 3.60366604 -1.19875138 3.60926654 -1.2037503 0 P 0 ;1,3=17,5=0.000000
L 3.60926654 -1.2037503 3.6158002 -1.205 0 P 0 ;1,3=17,5=0.000000
L 3.6158002 -1.205 3.62233386 -1.20250059 0 P 0 ;1,3=17,5=0.000000
L 3.62233386 -1.20250059 3.62886752 -1.19500217 0 P 0 ;1,3=17,5=0.000000
L 3.68799911 -1.20749941 3.68613287 -1.2062497 0 P 0 ;1,3=17,5=0.000000
L 3.68613287 -1.2062497 3.68613287 -1.2037503 0 P 0 ;1,3=17,5=0.000000
L 3.68613287 -1.2037503 3.68799911 -1.20250059 0 P 0 ;1,3=17,5=0.000000
L 3.68799911 -1.20250059 3.68986703 -1.2037503 0 P 0 ;1,3=17,5=0.000000
L 3.68986703 -1.2037503 3.68986703 -1.2062497 0 P 0 ;1,3=17,5=0.000000
L 3.68986703 -1.2062497 3.68799911 -1.20749941 0 P 0 ;1,3=17,5=0.000000
L 3.68799911 -1.17375217 3.68613287 -1.1725001 0 P 0 ;1,3=17,5=0.000000
L 3.68613287 -1.1725001 3.68613287 -1.17000069 0 P 0 ;1,3=17,5=0.000000
L 3.68613287 -1.17000069 3.68799911 -1.16875089 0 P 0 ;1,3=17,5=0.000000
L 3.68799911 -1.16875089 3.68986703 -1.17000069 0 P 0 ;1,3=17,5=0.000000
L 3.68986703 -1.17000069 3.68986703 -1.1725001 0 P 0 ;1,3=17,5=0.000000
L 3.68986703 -1.1725001 3.68799911 -1.17375217 0 P 0 ;1,3=17,5=0.000000
L 3.82026614 -1.1424997 3.82586663 -1.13500128 0 P 0 ;1,3=17,5=0.000000
L 3.82586663 -1.13500128 3.8324003 -1.1312498 0 P 0 ;1,3=17,5=0.000000
L 3.8324003 -1.1312498 3.83986703 -1.13 0 P 0 ;1,3=17,5=0.000000
L 3.83986703 -1.13 3.8492001 -1.13249951 0 P 0 ;1,3=17,5=0.000000
L 3.8492001 -1.13249951 3.85573376 -1.13875049 0 P 0 ;1,3=17,5=0.000000
L 3.85573376 -1.13875049 3.8576 -1.14624882 0 P 0 ;1,3=17,5=0.000000
L 3.8576 -1.14624882 3.85666693 -1.15375187 0 P 0 ;1,3=17,5=0.000000
L 3.85666693 -1.15375187 3.85293268 -1.16000049 0 P 0 ;1,3=17,5=0.000000
L 3.85293268 -1.16000049 3.83426654 -1.1725001 0 P 0 ;1,3=17,5=0.000000
L 3.83426654 -1.1725001 3.82586663 -1.18125059 0 P 0 ;1,3=17,5=0.000000
L 3.82586663 -1.18125059 3.82026614 -1.19375246 0 P 0 ;1,3=17,5=0.000000
L 3.82026614 -1.19375246 3.8183999 -1.205 0 P 0 ;1,3=17,5=0.000000
L 3.8183999 -1.205 3.8576 -1.205 0 P 0 ;1,3=17,5=0.000000
L 3.91299911 -1.13 3.90553228 -1.13249951 0 P 0 ;1,3=17,5=0.000000
L 3.90553228 -1.13249951 3.89993346 -1.13875049 0 P 0 ;1,3=17,5=0.000000
L 3.89993346 -1.13875049 3.89619931 -1.14624882 0 P 0 ;1,3=17,5=0.000000
L 3.89619931 -1.14624882 3.8933999 -1.15625128 0 P 0 ;1,3=17,5=0.000000
L 3.8933999 -1.15625128 3.89246673 -1.16750118 0 P 0 ;1,3=17,5=0.000000
L 3.89246673 -1.16750118 3.8933999 -1.17875108 0 P 0 ;1,3=17,5=0.000000
L 3.8933999 -1.17875108 3.89619931 -1.18875128 0 P 0 ;1,3=17,5=0.000000
L 3.89619931 -1.18875128 3.89993346 -1.19625187 0 P 0 ;1,3=17,5=0.000000
L 3.89993346 -1.19625187 3.90553228 -1.20250059 0 P 0 ;1,3=17,5=0.000000
L 3.90553228 -1.20250059 3.91299911 -1.205 0 P 0 ;1,3=17,5=0.000000
L 3.91299911 -1.205 3.92046585 -1.20250059 0 P 0 ;1,3=17,5=0.000000
L 3.92046585 -1.20250059 3.92606644 -1.19625187 0 P 0 ;1,3=17,5=0.000000
L 3.92606644 -1.19625187 3.92980059 -1.18875128 0 P 0 ;1,3=17,5=0.000000
L 3.92980059 -1.18875128 3.9326 -1.17875108 0 P 0 ;1,3=17,5=0.000000
L 3.9326 -1.17875108 3.93353317 -1.16750118 0 P 0 ;1,3=17,5=0.000000
L 3.93353317 -1.16750118 3.9326 -1.15625128 0 P 0 ;1,3=17,5=0.000000
L 3.9326 -1.15625128 3.92980059 -1.14624882 0 P 0 ;1,3=17,5=0.000000
L 3.92980059 -1.14624882 3.92606644 -1.13875049 0 P 0 ;1,3=17,5=0.000000
L 3.92606644 -1.13875049 3.92046585 -1.13249951 0 P 0 ;1,3=17,5=0.000000
L 3.92046585 -1.13249951 3.91299911 -1.13 0 P 0 ;1,3=17,5=0.000000
L 3.97026614 -1.1424997 3.97586663 -1.13500128 0 P 0 ;1,3=17,5=0.000000
L 3.97586663 -1.13500128 3.9824003 -1.1312498 0 P 0 ;1,3=17,5=0.000000
L 3.9824003 -1.1312498 3.98986703 -1.13 0 P 0 ;1,3=17,5=0.000000
L 3.98986703 -1.13 3.9992001 -1.13249951 0 P 0 ;1,3=17,5=0.000000
L 3.9992001 -1.13249951 4.00573376 -1.13875049 0 P 0 ;1,3=17,5=0.000000
L 4.00573376 -1.13875049 4.0076 -1.14624882 0 P 0 ;1,3=17,5=0.000000
L 4.0076 -1.14624882 4.00666693 -1.15375187 0 P 0 ;1,3=17,5=0.000000
L 4.00666693 -1.15375187 4.00293268 -1.16000049 0 P 0 ;1,3=17,5=0.000000
L 4.00293268 -1.16000049 3.98426654 -1.1725001 0 P 0 ;1,3=17,5=0.000000
L 3.98426654 -1.1725001 3.97586663 -1.18125059 0 P 0 ;1,3=17,5=0.000000
L 3.97586663 -1.18125059 3.97026614 -1.19375246 0 P 0 ;1,3=17,5=0.000000
L 3.97026614 -1.19375246 3.9683999 -1.205 0 P 0 ;1,3=17,5=0.000000
L 3.9683999 -1.205 4.0076 -1.205 0 P 0 ;1,3=17,5=0.000000
L 4.04526614 -1.1424997 4.05086663 -1.13500128 0 P 0 ;1,3=17,5=0.000000
L 4.05086663 -1.13500128 4.0574003 -1.1312498 0 P 0 ;1,3=17,5=0.000000
L 4.0574003 -1.1312498 4.06486703 -1.13 0 P 0 ;1,3=17,5=0.000000
L 4.06486703 -1.13 4.0742001 -1.13249951 0 P 0 ;1,3=17,5=0.000000
L 4.0742001 -1.13249951 4.08073376 -1.13875049 0 P 0 ;1,3=17,5=0.000000
L 4.08073376 -1.13875049 4.0826 -1.14624882 0 P 0 ;1,3=17,5=0.000000
L 4.0826 -1.14624882 4.08166693 -1.15375187 0 P 0 ;1,3=17,5=0.000000
L 4.08166693 -1.15375187 4.07793268 -1.16000049 0 P 0 ;1,3=17,5=0.000000
L 4.07793268 -1.16000049 4.05926654 -1.1725001 0 P 0 ;1,3=17,5=0.000000
L 4.05926654 -1.1725001 4.05086663 -1.18125059 0 P 0 ;1,3=17,5=0.000000
L 4.05086663 -1.18125059 4.04526614 -1.19375246 0 P 0 ;1,3=17,5=0.000000
L 4.04526614 -1.19375246 4.0433999 -1.205 0 P 0 ;1,3=17,5=0.000000
L 4.0433999 -1.205 4.0826 -1.205 0 P 0 ;1,3=17,5=0.000000
L 4.12586663 -1.18000079 4.15013327 -1.18000079 0 P 0 ;1,3=17,5=0.000000
L 4.21299911 -1.13 4.20553228 -1.13249951 0 P 0 ;1,3=17,5=0.000000
L 4.20553228 -1.13249951 4.19993346 -1.13875049 0 P 0 ;1,3=17,5=0.000000
L 4.19993346 -1.13875049 4.19619931 -1.14624882 0 P 0 ;1,3=17,5=0.000000
L 4.19619931 -1.14624882 4.1933999 -1.15625128 0 P 0 ;1,3=17,5=0.000000
L 4.1933999 -1.15625128 4.19246673 -1.16750118 0 P 0 ;1,3=17,5=0.000000
L 4.19246673 -1.16750118 4.1933999 -1.17875108 0 P 0 ;1,3=17,5=0.000000
L 4.1933999 -1.17875108 4.19619931 -1.18875128 0 P 0 ;1,3=17,5=0.000000
L 4.19619931 -1.18875128 4.19993346 -1.19625187 0 P 0 ;1,3=17,5=0.000000
L 4.19993346 -1.19625187 4.20553228 -1.20250059 0 P 0 ;1,3=17,5=0.000000
L 4.20553228 -1.20250059 4.21299911 -1.205 0 P 0 ;1,3=17,5=0.000000
L 4.21299911 -1.205 4.22046585 -1.20250059 0 P 0 ;1,3=17,5=0.000000
L 4.22046585 -1.20250059 4.22606644 -1.19625187 0 P 0 ;1,3=17,5=0.000000
L 4.22606644 -1.19625187 4.22980059 -1.18875128 0 P 0 ;1,3=17,5=0.000000
L 4.22980059 -1.18875128 4.2326 -1.17875108 0 P 0 ;1,3=17,5=0.000000
L 4.2326 -1.17875108 4.23353317 -1.16750118 0 P 0 ;1,3=17,5=0.000000
L 4.23353317 -1.16750118 4.2326 -1.15625128 0 P 0 ;1,3=17,5=0.000000
L 4.2326 -1.15625128 4.22980059 -1.14624882 0 P 0 ;1,3=17,5=0.000000
L 4.22980059 -1.14624882 4.22606644 -1.13875049 0 P 0 ;1,3=17,5=0.000000
L 4.22606644 -1.13875049 4.22046585 -1.13249951 0 P 0 ;1,3=17,5=0.000000
L 4.22046585 -1.13249951 4.21299911 -1.13 0 P 0 ;1,3=17,5=0.000000
L 4.27026614 -1.1424997 4.27586663 -1.13500128 0 P 0 ;1,3=17,5=0.000000
L 4.27586663 -1.13500128 4.2824003 -1.1312498 0 P 0 ;1,3=17,5=0.000000
L 4.2824003 -1.1312498 4.28986703 -1.13 0 P 0 ;1,3=17,5=0.000000
L 4.28986703 -1.13 4.2992001 -1.13249951 0 P 0 ;1,3=17,5=0.000000
L 4.2992001 -1.13249951 4.30573376 -1.13875049 0 P 0 ;1,3=17,5=0.000000
L 4.30573376 -1.13875049 4.3076 -1.14624882 0 P 0 ;1,3=17,5=0.000000
L 4.3076 -1.14624882 4.30666693 -1.15375187 0 P 0 ;1,3=17,5=0.000000
L 4.30666693 -1.15375187 4.30293268 -1.16000049 0 P 0 ;1,3=17,5=0.000000
L 4.30293268 -1.16000049 4.28426654 -1.1725001 0 P 0 ;1,3=17,5=0.000000
L 4.28426654 -1.1725001 4.27586663 -1.18125059 0 P 0 ;1,3=17,5=0.000000
L 4.27586663 -1.18125059 4.27026614 -1.19375246 0 P 0 ;1,3=17,5=0.000000
L 4.27026614 -1.19375246 4.2683999 -1.205 0 P 0 ;1,3=17,5=0.000000
L 4.2683999 -1.205 4.3076 -1.205 0 P 0 ;1,3=17,5=0.000000
L 4.35086663 -1.18000079 4.37513327 -1.18000079 0 P 0 ;1,3=17,5=0.000000
L 4.42026614 -1.1424997 4.42586663 -1.13500128 0 P 0 ;1,3=17,5=0.000000
L 4.42586663 -1.13500128 4.4324003 -1.1312498 0 P 0 ;1,3=17,5=0.000000
L 4.4324003 -1.1312498 4.43986703 -1.13 0 P 0 ;1,3=17,5=0.000000
L 4.43986703 -1.13 4.4492001 -1.13249951 0 P 0 ;1,3=17,5=0.000000
L 4.4492001 -1.13249951 4.45573376 -1.13875049 0 P 0 ;1,3=17,5=0.000000
L 4.45573376 -1.13875049 4.4576 -1.14624882 0 P 0 ;1,3=17,5=0.000000
L 4.4576 -1.14624882 4.45666693 -1.15375187 0 P 0 ;1,3=17,5=0.000000
L 4.45666693 -1.15375187 4.45293268 -1.16000049 0 P 0 ;1,3=17,5=0.000000
L 4.45293268 -1.16000049 4.43426654 -1.1725001 0 P 0 ;1,3=17,5=0.000000
L 4.43426654 -1.1725001 4.42586663 -1.18125059 0 P 0 ;1,3=17,5=0.000000
L 4.42586663 -1.18125059 4.42026614 -1.19375246 0 P 0 ;1,3=17,5=0.000000
L 4.42026614 -1.19375246 4.4183999 -1.205 0 P 0 ;1,3=17,5=0.000000
L 4.4183999 -1.205 4.4576 -1.205 0 P 0 ;1,3=17,5=0.000000
L 4.49246673 -1.19375246 4.49806555 -1.20000108 0 P 0 ;1,3=17,5=0.000000
L 4.49806555 -1.20000108 4.50459921 -1.2037503 0 P 0 ;1,3=17,5=0.000000
L 4.50459921 -1.2037503 4.51299911 -1.205 0 P 0 ;1,3=17,5=0.000000
L 4.51299911 -1.205 4.52140069 -1.20250059 0 P 0 ;1,3=17,5=0.000000
L 4.52140069 -1.20250059 4.52793268 -1.19750167 0 P 0 ;1,3=17,5=0.000000
L 4.52793268 -1.19750167 4.5326 -1.18875128 0 P 0 ;1,3=17,5=0.000000
L 4.5326 -1.18875128 4.53353317 -1.17875108 0 P 0 ;1,3=17,5=0.000000
L 4.53353317 -1.17875108 4.53166693 -1.16875089 0 P 0 ;1,3=17,5=0.000000
L 4.53166693 -1.16875089 4.52699951 -1.1625 0 P 0 ;1,3=17,5=0.000000
L 4.52699951 -1.1625 4.52046585 -1.15750108 0 P 0 ;1,3=17,5=0.000000
L 4.52046585 -1.15750108 4.51393396 -1.15625128 0 P 0 ;1,3=17,5=0.000000
L 4.51393396 -1.15625128 4.5074003 -1.15750108 0 P 0 ;1,3=17,5=0.000000
L 4.5074003 -1.15750108 4.49900039 -1.1625 0 P 0 ;1,3=17,5=0.000000
L 4.49900039 -1.1625 4.5017998 -1.13 0 P 0 ;1,3=17,5=0.000000
L 4.5017998 -1.13 4.52699951 -1.13 0 P 0 ;1,3=17,5=0.000000
L 3.29433297 -1.255 3.29433297 -1.33 0 P 0 ;1,3=18,5=0.000000
L 3.29433297 -1.33 3.33166693 -1.33 0 P 0 ;1,3=18,5=0.000000
L 3.40480059 -1.33 3.40480059 -1.28000157 0 P 0 ;1,3=18,5=0.000000
L 3.40480059 -1.2887497 3.40106644 -1.28375079 0 P 0 ;1,3=18,5=0.000000
L 3.40106644 -1.28375079 3.39546585 -1.28125128 0 P 0 ;1,3=18,5=0.000000
L 3.39546585 -1.28125128 3.38893396 -1.28000157 0 P 0 ;1,3=18,5=0.000000
L 3.38893396 -1.28000157 3.3824003 -1.28250108 0 P 0 ;1,3=18,5=0.000000
L 3.3824003 -1.28250108 3.3767998 -1.2875 0 P 0 ;1,3=18,5=0.000000
L 3.3767998 -1.2875 3.37306555 -1.29500069 0 P 0 ;1,3=18,5=0.000000
L 3.37306555 -1.29500069 3.37119931 -1.30500079 0 P 0 ;1,3=18,5=0.000000
L 3.37119931 -1.30500079 3.37306555 -1.31500098 0 P 0 ;1,3=18,5=0.000000
L 3.37306555 -1.31500098 3.3767998 -1.32250167 0 P 0 ;1,3=18,5=0.000000
L 3.3767998 -1.32250167 3.3824003 -1.32750059 0 P 0 ;1,3=18,5=0.000000
L 3.3824003 -1.32750059 3.38893396 -1.33 0 P 0 ;1,3=18,5=0.000000
L 3.38893396 -1.33 3.39546585 -1.3287503 0 P 0 ;1,3=18,5=0.000000
L 3.39546585 -1.3287503 3.40106644 -1.32500108 0 P 0 ;1,3=18,5=0.000000
L 3.40106644 -1.32500108 3.40480059 -1.32000217 0 P 0 ;1,3=18,5=0.000000
L 3.4433999 -1.3524997 3.44900039 -1.35499921 0 P 0 ;1,3=18,5=0.000000
L 3.44900039 -1.35499921 3.45646713 -1.3524997 0 P 0 ;1,3=18,5=0.000000
L 3.45646713 -1.3524997 3.46113287 -1.34750079 0 P 0 ;1,3=18,5=0.000000
L 3.46113287 -1.34750079 3.46486703 -1.3412498 0 P 0 ;1,3=18,5=0.000000
L 3.46486703 -1.3412498 3.47046585 -1.32125187 0 P 0 ;1,3=18,5=0.000000
L 3.47046585 -1.32125187 3.4826 -1.28000157 0 P 0 ;1,3=18,5=0.000000
L 3.45273287 -1.28000157 3.47046585 -1.32125187 0 P 0 ;1,3=18,5=0.000000
L 3.52400039 -1.29625039 3.55386752 -1.29625039 0 P 0 ;1,3=18,5=0.000000
L 3.55386752 -1.29625039 3.55106644 -1.2875 0 P 0 ;1,3=18,5=0.000000
L 3.55106644 -1.2875 3.54640069 -1.28250108 0 P 0 ;1,3=18,5=0.000000
L 3.54640069 -1.28250108 3.53986703 -1.28000157 0 P 0 ;1,3=18,5=0.000000
L 3.53986703 -1.28000157 3.53333346 -1.28125128 0 P 0 ;1,3=18,5=0.000000
L 3.53333346 -1.28125128 3.52773287 -1.28500049 0 P 0 ;1,3=18,5=0.000000
L 3.52773287 -1.28500049 3.52400039 -1.29375089 0 P 0 ;1,3=18,5=0.000000
L 3.52400039 -1.29375089 3.52213238 -1.30125157 0 P 0 ;1,3=18,5=0.000000
L 3.52213238 -1.30125157 3.52213238 -1.30875 0 P 0 ;1,3=18,5=0.000000
L 3.52213238 -1.30875 3.52400039 -1.31625069 0 P 0 ;1,3=18,5=0.000000
L 3.52400039 -1.31625069 3.52866604 -1.32375138 0 P 0 ;1,3=18,5=0.000000
L 3.52866604 -1.32375138 3.53426654 -1.3287503 0 P 0 ;1,3=18,5=0.000000
L 3.53426654 -1.3287503 3.5408002 -1.33 0 P 0 ;1,3=18,5=0.000000
L 3.5408002 -1.33 3.54733386 -1.32750059 0 P 0 ;1,3=18,5=0.000000
L 3.54733386 -1.32750059 3.55386752 -1.32000217 0 P 0 ;1,3=18,5=0.000000
L 3.59993346 -1.33 3.59993346 -1.28000157 0 P 0 ;1,3=18,5=0.000000
L 3.59993346 -1.28999941 3.60459921 -1.28500049 0 P 0 ;1,3=18,5=0.000000
L 3.60459921 -1.28500049 3.60926654 -1.28125128 0 P 0 ;1,3=18,5=0.000000
L 3.60926654 -1.28125128 3.6158002 -1.28000157 0 P 0 ;1,3=18,5=0.000000
L 3.6158002 -1.28000157 3.62046585 -1.28125128 0 P 0 ;1,3=18,5=0.000000
L 3.62046585 -1.28125128 3.62606644 -1.28500049 0 P 0 ;1,3=18,5=0.000000
L 3.68799911 -1.33249941 3.68613287 -1.3312497 0 P 0 ;1,3=18,5=0.000000
L 3.68613287 -1.3312497 3.68613287 -1.3287503 0 P 0 ;1,3=18,5=0.000000
L 3.68613287 -1.3287503 3.68799911 -1.32750059 0 P 0 ;1,3=18,5=0.000000
L 3.68799911 -1.32750059 3.68986703 -1.3287503 0 P 0 ;1,3=18,5=0.000000
L 3.68986703 -1.3287503 3.68986703 -1.3312497 0 P 0 ;1,3=18,5=0.000000
L 3.68986703 -1.3312497 3.68799911 -1.33249941 0 P 0 ;1,3=18,5=0.000000
L 3.68799911 -1.29875217 3.68613287 -1.2975001 0 P 0 ;1,3=18,5=0.000000
L 3.68613287 -1.2975001 3.68613287 -1.29500069 0 P 0 ;1,3=18,5=0.000000
L 3.68613287 -1.29500069 3.68799911 -1.29375089 0 P 0 ;1,3=18,5=0.000000
L 3.68799911 -1.29375089 3.68986703 -1.29500069 0 P 0 ;1,3=18,5=0.000000
L 3.68986703 -1.29500069 3.68986703 -1.2975001 0 P 0 ;1,3=18,5=0.000000
L 3.68986703 -1.2975001 3.68799911 -1.29875217 0 P 0 ;1,3=18,5=0.000000
L 3.36933297 -1.08 3.36933297 -1.005 0 P 0 ;1,3=19,5=0.000000
L 3.36933297 -1.005 3.39266644 -1.005 0 P 0 ;1,3=19,5=0.000000
L 3.39266644 -1.005 3.40013327 -1.00875157 0 P 0 ;1,3=19,5=0.000000
L 3.40013327 -1.00875157 3.40480059 -1.01375049 0 P 0 ;1,3=19,5=0.000000
L 3.40480059 -1.01375049 3.40666693 -1.02375059 0 P 0 ;1,3=19,5=0.000000
L 3.40666693 -1.02375059 3.40480059 -1.03375079 0 P 0 ;1,3=19,5=0.000000
L 3.40480059 -1.03375079 3.3992001 -1.03999941 0 P 0 ;1,3=19,5=0.000000
L 3.3992001 -1.03999941 3.39266644 -1.04375089 0 P 0 ;1,3=19,5=0.000000
L 3.39266644 -1.04375089 3.36933297 -1.04375089 0 P 0 ;1,3=19,5=0.000000
L 3.39266644 -1.04375089 3.40666693 -1.08 0 P 0 ;1,3=19,5=0.000000
L 3.44900039 -1.04625039 3.47886752 -1.04625039 0 P 0 ;1,3=19,5=0.000000
L 3.47886752 -1.04625039 3.47606644 -1.0375 0 P 0 ;1,3=19,5=0.000000
L 3.47606644 -1.0375 3.47140069 -1.03250108 0 P 0 ;1,3=19,5=0.000000
L 3.47140069 -1.03250108 3.46486703 -1.03000157 0 P 0 ;1,3=19,5=0.000000
L 3.46486703 -1.03000157 3.45833346 -1.03125128 0 P 0 ;1,3=19,5=0.000000
L 3.45833346 -1.03125128 3.45273287 -1.03500049 0 P 0 ;1,3=19,5=0.000000
L 3.45273287 -1.03500049 3.44900039 -1.04375089 0 P 0 ;1,3=19,5=0.000000
L 3.44900039 -1.04375089 3.44713238 -1.05125157 0 P 0 ;1,3=19,5=0.000000
L 3.44713238 -1.05125157 3.44713238 -1.05875 0 P 0 ;1,3=19,5=0.000000
L 3.44713238 -1.05875 3.44900039 -1.06625069 0 P 0 ;1,3=19,5=0.000000
L 3.44900039 -1.06625069 3.45366604 -1.07375138 0 P 0 ;1,3=19,5=0.000000
L 3.45366604 -1.07375138 3.45926654 -1.0787503 0 P 0 ;1,3=19,5=0.000000
L 3.45926654 -1.0787503 3.4658002 -1.08 0 P 0 ;1,3=19,5=0.000000
L 3.4658002 -1.08 3.47233386 -1.07750059 0 P 0 ;1,3=19,5=0.000000
L 3.47233386 -1.07750059 3.47886752 -1.07000217 0 P 0 ;1,3=19,5=0.000000
L 3.52119931 -1.03000157 3.53799911 -1.08 0 P 0 ;1,3=19,5=0.000000
L 3.53799911 -1.08 3.55480059 -1.03000157 0 P 0 ;1,3=19,5=0.000000
L 3.68799911 -1.08249941 3.68613287 -1.0812497 0 P 0 ;1,3=19,5=0.000000
L 3.68613287 -1.0812497 3.68613287 -1.0787503 0 P 0 ;1,3=19,5=0.000000
L 3.68613287 -1.0787503 3.68799911 -1.07750059 0 P 0 ;1,3=19,5=0.000000
L 3.68799911 -1.07750059 3.68986703 -1.0787503 0 P 0 ;1,3=19,5=0.000000
L 3.68986703 -1.0787503 3.68986703 -1.0812497 0 P 0 ;1,3=19,5=0.000000
L 3.68986703 -1.0812497 3.68799911 -1.08249941 0 P 0 ;1,3=19,5=0.000000
L 3.68799911 -1.04875217 3.68613287 -1.0475001 0 P 0 ;1,3=19,5=0.000000
L 3.68613287 -1.0475001 3.68613287 -1.04500069 0 P 0 ;1,3=19,5=0.000000
L 3.68613287 -1.04500069 3.68799911 -1.04375089 0 P 0 ;1,3=19,5=0.000000
L 3.68799911 -1.04375089 3.68986703 -1.04500069 0 P 0 ;1,3=19,5=0.000000
L 3.68986703 -1.04500069 3.68986703 -1.0475001 0 P 0 ;1,3=19,5=0.000000
L 3.68986703 -1.0475001 3.68799911 -1.04875217 0 P 0 ;1,3=19,5=0.000000
L 3.83799911 -1.005 3.83053228 -1.00749951 0 P 0 ;1,3=19,5=0.000000
L 3.83053228 -1.00749951 3.82493346 -1.01375049 0 P 0 ;1,3=19,5=0.000000
L 3.82493346 -1.01375049 3.82119931 -1.02124882 0 P 0 ;1,3=19,5=0.000000
L 3.82119931 -1.02124882 3.8183999 -1.03125128 0 P 0 ;1,3=19,5=0.000000
L 3.8183999 -1.03125128 3.81746673 -1.04250118 0 P 0 ;1,3=19,5=0.000000
L 3.81746673 -1.04250118 3.8183999 -1.05375108 0 P 0 ;1,3=19,5=0.000000
L 3.8183999 -1.05375108 3.82119931 -1.06375128 0 P 0 ;1,3=19,5=0.000000
L 3.82119931 -1.06375128 3.82493346 -1.07125187 0 P 0 ;1,3=19,5=0.000000
L 3.82493346 -1.07125187 3.83053228 -1.07750059 0 P 0 ;1,3=19,5=0.000000
L 3.83053228 -1.07750059 3.83799911 -1.08 0 P 0 ;1,3=19,5=0.000000
L 3.83799911 -1.08 3.84546585 -1.07750059 0 P 0 ;1,3=19,5=0.000000
L 3.84546585 -1.07750059 3.85106644 -1.07125187 0 P 0 ;1,3=19,5=0.000000
L 3.85106644 -1.07125187 3.85480059 -1.06375128 0 P 0 ;1,3=19,5=0.000000
L 3.85480059 -1.06375128 3.8576 -1.05375108 0 P 0 ;1,3=19,5=0.000000
L 3.8576 -1.05375108 3.85853317 -1.04250118 0 P 0 ;1,3=19,5=0.000000
L 3.85853317 -1.04250118 3.8576 -1.03125128 0 P 0 ;1,3=19,5=0.000000
L 3.8576 -1.03125128 3.85480059 -1.02124882 0 P 0 ;1,3=19,5=0.000000
L 3.85480059 -1.02124882 3.85106644 -1.01375049 0 P 0 ;1,3=19,5=0.000000
L 3.85106644 -1.01375049 3.84546585 -1.00749951 0 P 0 ;1,3=19,5=0.000000
L 3.84546585 -1.00749951 3.83799911 -1.005 0 P 0 ;1,3=19,5=0.000000
L 3.91299911 -1.08 3.91299911 -1.005 0 P 0 ;1,3=19,5=0.000000
L 3.91299911 -1.005 3.9017998 -1.01999911 0 P 0 ;1,3=19,5=0.000000
L 3.9017998 -1.08 3.92419843 -1.08 0 P 0 ;1,3=19,5=0.000000
L 3.82380994 -1.31929213 3.83127667 -1.32554085 0 P 0 ;1,3=20,5=0.000000
L 3.83127667 -1.32554085 3.83967657 -1.32928996 0 P 0 ;1,3=20,5=0.000000
L 3.83967657 -1.32928996 3.84714341 -1.32928996 0 P 0 ;1,3=20,5=0.000000
L 3.84714341 -1.32928996 3.85461014 -1.32554085 0 P 0 ;1,3=20,5=0.000000
L 3.85461014 -1.32554085 3.86021063 -1.31929213 0 P 0 ;1,3=20,5=0.000000
L 3.86021063 -1.31929213 3.86301004 -1.31053947 0 P 0 ;1,3=20,5=0.000000
L 3.86301004 -1.31053947 3.8611438 -1.30179134 0 P 0 ;1,3=20,5=0.000000
L 3.8611438 -1.30179134 3.85647648 -1.29429065 0 P 0 ;1,3=20,5=0.000000
L 3.85647648 -1.29429065 3.84807648 -1.28928937 0 P 0 ;1,3=20,5=0.000000
L 3.84807648 -1.28928937 3.83687717 -1.28678996 0 P 0 ;1,3=20,5=0.000000
L 3.83687717 -1.28678996 3.8303435 -1.28179104 0 P 0 ;1,3=20,5=0.000000
L 3.8303435 -1.28179104 3.82754242 -1.27304055 0 P 0 ;1,3=20,5=0.000000
L 3.82754242 -1.27304055 3.82941043 -1.26429016 0 P 0 ;1,3=20,5=0.000000
L 3.82941043 -1.26429016 3.83407608 -1.25804154 0 P 0 ;1,3=20,5=0.000000
L 3.83407608 -1.25804154 3.84060974 -1.25428996 0 P 0 ;1,3=20,5=0.000000
L 3.84060974 -1.25428996 3.84714341 -1.25428996 0 P 0 ;1,3=20,5=0.000000
L 3.84714341 -1.25428996 3.85367707 -1.25678947 0 P 0 ;1,3=20,5=0.000000
L 3.85367707 -1.25678947 3.85927756 -1.26304045 0 P 0 ;1,3=20,5=0.000000
L 3.91840915 -1.32928996 3.91094232 -1.32804026 0 P 0 ;1,3=20,5=0.000000
L 3.91094232 -1.32804026 3.90441043 -1.32304134 0 P 0 ;1,3=20,5=0.000000
L 3.90441043 -1.32304134 3.89880994 -1.31554065 0 P 0 ;1,3=20,5=0.000000
L 3.89880994 -1.31554065 3.89507569 -1.30679026 0 P 0 ;1,3=20,5=0.000000
L 3.89507569 -1.30679026 3.89320935 -1.29679006 0 P 0 ;1,3=20,5=0.000000
L 3.89320935 -1.29679006 3.89320935 -1.28678996 0 P 0 ;1,3=20,5=0.000000
L 3.89320935 -1.28678996 3.89507569 -1.27678976 0 P 0 ;1,3=20,5=0.000000
L 3.89507569 -1.27678976 3.89880994 -1.26803937 0 P 0 ;1,3=20,5=0.000000
L 3.89880994 -1.26803937 3.90441043 -1.26054094 0 P 0 ;1,3=20,5=0.000000
L 3.90441043 -1.26054094 3.91094232 -1.25553976 0 P 0 ;1,3=20,5=0.000000
L 3.91094232 -1.25553976 3.91840915 -1.25428996 0 P 0 ;1,3=20,5=0.000000
L 3.91840915 -1.25428996 3.92587589 -1.25553976 0 P 0 ;1,3=20,5=0.000000
L 3.92587589 -1.25553976 3.93240955 -1.26054094 0 P 0 ;1,3=20,5=0.000000
L 3.93240955 -1.26054094 3.93801004 -1.26803937 0 P 0 ;1,3=20,5=0.000000
L 3.93801004 -1.26803937 3.94174429 -1.27678976 0 P 0 ;1,3=20,5=0.000000
L 3.94174429 -1.27678976 3.94361063 -1.28678996 0 P 0 ;1,3=20,5=0.000000
L 3.94361063 -1.28678996 3.94361063 -1.29679006 0 P 0 ;1,3=20,5=0.000000
L 3.94361063 -1.29679006 3.94174429 -1.30679026 0 P 0 ;1,3=20,5=0.000000
L 3.94174429 -1.30679026 3.93801004 -1.31554065 0 P 0 ;1,3=20,5=0.000000
L 3.93801004 -1.31554065 3.93240955 -1.32304134 0 P 0 ;1,3=20,5=0.000000
L 3.93240955 -1.32304134 3.92587589 -1.32804026 0 P 0 ;1,3=20,5=0.000000
L 3.92587589 -1.32804026 3.91840915 -1.32928996 0 P 0 ;1,3=20,5=0.000000
L 3.97474301 -1.25428996 3.97474301 -1.32928996 0 P 0 ;1,3=20,5=0.000000
L 3.97474301 -1.32928996 4.01207697 -1.32928996 0 P 0 ;1,3=20,5=0.000000
L 4.04787677 -1.32928996 4.04787677 -1.25428996 0 P 0 ;1,3=20,5=0.000000
L 4.04787677 -1.25428996 4.06654291 -1.25428996 0 P 0 ;1,3=20,5=0.000000
L 4.06654291 -1.25428996 4.07400965 -1.25804154 0 P 0 ;1,3=20,5=0.000000
L 4.07400965 -1.25804154 4.07961014 -1.26304045 0 P 0 ;1,3=20,5=0.000000
L 4.07961014 -1.26304045 4.08427756 -1.27053878 0 P 0 ;1,3=20,5=0.000000
L 4.08427756 -1.27053878 4.08801004 -1.27929154 0 P 0 ;1,3=20,5=0.000000
L 4.08801004 -1.27929154 4.08894321 -1.29179114 0 P 0 ;1,3=20,5=0.000000
L 4.08894321 -1.29179114 4.08801004 -1.30429075 0 P 0 ;1,3=20,5=0.000000
L 4.08801004 -1.30429075 4.08427756 -1.31304124 0 P 0 ;1,3=20,5=0.000000
L 4.08427756 -1.31304124 4.07961014 -1.32054183 0 P 0 ;1,3=20,5=0.000000
L 4.07961014 -1.32054183 4.07400965 -1.32554085 0 P 0 ;1,3=20,5=0.000000
L 4.07400965 -1.32554085 4.06654291 -1.32928996 0 P 0 ;1,3=20,5=0.000000
L 4.06654291 -1.32928996 4.04787677 -1.32928996 0 P 0 ;1,3=20,5=0.000000
L 4.16207697 -1.32928996 4.12474301 -1.32928996 0 P 0 ;1,3=20,5=0.000000
L 4.12474301 -1.32928996 4.12474301 -1.25428996 0 P 0 ;1,3=20,5=0.000000
L 4.12474301 -1.25428996 4.16207697 -1.25428996 0 P 0 ;1,3=20,5=0.000000
L 4.14714341 -1.29053917 4.12474301 -1.29053917 0 P 0 ;1,3=20,5=0.000000
L 4.19974301 -1.32928996 4.19974301 -1.25428996 0 P 0 ;1,3=20,5=0.000000
L 4.19974301 -1.25428996 4.22307648 -1.25428996 0 P 0 ;1,3=20,5=0.000000
L 4.22307648 -1.25428996 4.23054331 -1.25804154 0 P 0 ;1,3=20,5=0.000000
L 4.23054331 -1.25804154 4.23521063 -1.26304045 0 P 0 ;1,3=20,5=0.000000
L 4.23521063 -1.26304045 4.23707697 -1.27304055 0 P 0 ;1,3=20,5=0.000000
L 4.23707697 -1.27304055 4.23521063 -1.28304075 0 P 0 ;1,3=20,5=0.000000
L 4.23521063 -1.28304075 4.22961014 -1.28928937 0 P 0 ;1,3=20,5=0.000000
L 4.22961014 -1.28928937 4.22307648 -1.29304085 0 P 0 ;1,3=20,5=0.000000
L 4.22307648 -1.29304085 4.19974301 -1.29304085 0 P 0 ;1,3=20,5=0.000000
L 4.22307648 -1.29304085 4.23707697 -1.32928996 0 P 0 ;1,3=20,5=0.000000
L 4.27474301 -1.32928996 4.27474301 -1.25428996 0 P 0 ;1,3=20,5=0.000000
L 4.27474301 -1.25428996 4.29714341 -1.25428996 0 P 0 ;1,3=20,5=0.000000
L 4.29714341 -1.25428996 4.30461014 -1.25804154 0 P 0 ;1,3=20,5=0.000000
L 4.30461014 -1.25804154 4.31021063 -1.26678967 0 P 0 ;1,3=20,5=0.000000
L 4.31021063 -1.26678967 4.31207697 -1.27678976 0 P 0 ;1,3=20,5=0.000000
L 4.31207697 -1.27678976 4.31021063 -1.28678996 0 P 0 ;1,3=20,5=0.000000
L 4.31021063 -1.28678996 4.30554331 -1.29429065 0 P 0 ;1,3=20,5=0.000000
L 4.30554331 -1.29429065 4.29714341 -1.29804213 0 P 0 ;1,3=20,5=0.000000
L 4.29714341 -1.29804213 4.27474301 -1.29804213 0 P 0 ;1,3=20,5=0.000000
L 4.34507569 -1.32928996 4.36840915 -1.25428996 0 P 0 ;1,3=20,5=0.000000
L 4.36840915 -1.25428996 4.39174429 -1.32928996 0 P 0 ;1,3=20,5=0.000000
L 4.38334272 -1.30304104 4.35347559 -1.30304104 0 P 0 ;1,3=20,5=0.000000
L 4.42380994 -1.31929213 4.43127667 -1.32554085 0 P 0 ;1,3=20,5=0.000000
L 4.43127667 -1.32554085 4.43967657 -1.32928996 0 P 0 ;1,3=20,5=0.000000
L 4.43967657 -1.32928996 4.44714341 -1.32928996 0 P 0 ;1,3=20,5=0.000000
L 4.44714341 -1.32928996 4.45461014 -1.32554085 0 P 0 ;1,3=20,5=0.000000
L 4.45461014 -1.32554085 4.46021063 -1.31929213 0 P 0 ;1,3=20,5=0.000000
L 4.46021063 -1.31929213 4.46301004 -1.31053947 0 P 0 ;1,3=20,5=0.000000
L 4.46301004 -1.31053947 4.4611438 -1.30179134 0 P 0 ;1,3=20,5=0.000000
L 4.4611438 -1.30179134 4.45647648 -1.29429065 0 P 0 ;1,3=20,5=0.000000
L 4.45647648 -1.29429065 4.44807648 -1.28928937 0 P 0 ;1,3=20,5=0.000000
L 4.44807648 -1.28928937 4.43687717 -1.28678996 0 P 0 ;1,3=20,5=0.000000
L 4.43687717 -1.28678996 4.4303435 -1.28179104 0 P 0 ;1,3=20,5=0.000000
L 4.4303435 -1.28179104 4.42754242 -1.27304055 0 P 0 ;1,3=20,5=0.000000
L 4.42754242 -1.27304055 4.42941043 -1.26429016 0 P 0 ;1,3=20,5=0.000000
L 4.42941043 -1.26429016 4.43407608 -1.25804154 0 P 0 ;1,3=20,5=0.000000
L 4.43407608 -1.25804154 4.44060974 -1.25428996 0 P 0 ;1,3=20,5=0.000000
L 4.44060974 -1.25428996 4.44714341 -1.25428996 0 P 0 ;1,3=20,5=0.000000
L 4.44714341 -1.25428996 4.45367707 -1.25678947 0 P 0 ;1,3=20,5=0.000000
L 4.45367707 -1.25678947 4.45927756 -1.26304045 0 P 0 ;1,3=20,5=0.000000
L 4.51840915 -1.25428996 4.51840915 -1.32928996 0 P 0 ;1,3=20,5=0.000000
L 4.4969436 -1.25428996 4.53987638 -1.25428996 0 P 0 ;1,3=20,5=0.000000
L 4.61207697 -1.32928996 4.57474301 -1.32928996 0 P 0 ;1,3=20,5=0.000000
L 4.57474301 -1.32928996 4.57474301 -1.25428996 0 P 0 ;1,3=20,5=0.000000
L 4.57474301 -1.25428996 4.61207697 -1.25428996 0 P 0 ;1,3=20,5=0.000000
L 4.59714341 -1.29053917 4.57474301 -1.29053917 0 P 0 ;1,3=20,5=0.000000
L 4.75087589 -1.28928937 4.75461014 -1.28554016 0 P 0 ;1,3=20,5=0.000000
L 4.75461014 -1.28554016 4.75740955 -1.27929154 0 P 0 ;1,3=20,5=0.000000
L 4.75740955 -1.27929154 4.75927756 -1.27053878 0 P 0 ;1,3=20,5=0.000000
L 4.75927756 -1.27053878 4.75740955 -1.26304045 0 P 0 ;1,3=20,5=0.000000
L 4.75740955 -1.26304045 4.75367707 -1.25804154 0 P 0 ;1,3=20,5=0.000000
L 4.75367707 -1.25804154 4.74714341 -1.25428996 0 P 0 ;1,3=20,5=0.000000
L 4.74714341 -1.25428996 4.7219436 -1.25428996 0 P 0 ;1,3=20,5=0.000000
L 4.7219436 -1.25428996 4.7219436 -1.32928996 0 P 0 ;1,3=20,5=0.000000
L 4.7219436 -1.32928996 4.7527439 -1.32928996 0 P 0 ;1,3=20,5=0.000000
L 4.7527439 -1.32928996 4.75927756 -1.32429104 0 P 0 ;1,3=20,5=0.000000
L 4.75927756 -1.32429104 4.76301004 -1.31679035 0 P 0 ;1,3=20,5=0.000000
L 4.76301004 -1.31679035 4.76487638 -1.30803996 0 P 0 ;1,3=20,5=0.000000
L 4.76487638 -1.30803996 4.76301004 -1.29929183 0 P 0 ;1,3=20,5=0.000000
L 4.76301004 -1.29929183 4.75740955 -1.29179114 0 P 0 ;1,3=20,5=0.000000
L 4.75740955 -1.29179114 4.75087589 -1.28928937 0 P 0 ;1,3=20,5=0.000000
L 4.75087589 -1.28928937 4.7219436 -1.28928937 0 P 0 ;1,3=20,5=0.000000
L 4.81840915 -1.32928996 4.81094232 -1.32804026 0 P 0 ;1,3=20,5=0.000000
L 4.81094232 -1.32804026 4.80441043 -1.32304134 0 P 0 ;1,3=20,5=0.000000
L 4.80441043 -1.32304134 4.79880994 -1.31554065 0 P 0 ;1,3=20,5=0.000000
L 4.79880994 -1.31554065 4.79507569 -1.30679026 0 P 0 ;1,3=20,5=0.000000
L 4.79507569 -1.30679026 4.79320935 -1.29679006 0 P 0 ;1,3=20,5=0.000000
L 4.79320935 -1.29679006 4.79320935 -1.28678996 0 P 0 ;1,3=20,5=0.000000
L 4.79320935 -1.28678996 4.79507569 -1.27678976 0 P 0 ;1,3=20,5=0.000000
L 4.79507569 -1.27678976 4.79880994 -1.26803937 0 P 0 ;1,3=20,5=0.000000
L 4.79880994 -1.26803937 4.80441043 -1.26054094 0 P 0 ;1,3=20,5=0.000000
L 4.80441043 -1.26054094 4.81094232 -1.25553976 0 P 0 ;1,3=20,5=0.000000
L 4.81094232 -1.25553976 4.81840915 -1.25428996 0 P 0 ;1,3=20,5=0.000000
L 4.81840915 -1.25428996 4.82587589 -1.25553976 0 P 0 ;1,3=20,5=0.000000
L 4.82587589 -1.25553976 4.83240955 -1.26054094 0 P 0 ;1,3=20,5=0.000000
L 4.83240955 -1.26054094 4.83801004 -1.26803937 0 P 0 ;1,3=20,5=0.000000
L 4.83801004 -1.26803937 4.84174429 -1.27678976 0 P 0 ;1,3=20,5=0.000000
L 4.84174429 -1.27678976 4.84361063 -1.28678996 0 P 0 ;1,3=20,5=0.000000
L 4.84361063 -1.28678996 4.84361063 -1.29679006 0 P 0 ;1,3=20,5=0.000000
L 4.84361063 -1.29679006 4.84174429 -1.30679026 0 P 0 ;1,3=20,5=0.000000
L 4.84174429 -1.30679026 4.83801004 -1.31554065 0 P 0 ;1,3=20,5=0.000000
L 4.83801004 -1.31554065 4.83240955 -1.32304134 0 P 0 ;1,3=20,5=0.000000
L 4.83240955 -1.32304134 4.82587589 -1.32804026 0 P 0 ;1,3=20,5=0.000000
L 4.82587589 -1.32804026 4.81840915 -1.32928996 0 P 0 ;1,3=20,5=0.000000
L 4.89340915 -1.25428996 4.89340915 -1.32928996 0 P 0 ;1,3=20,5=0.000000
L 4.8719436 -1.25428996 4.91487638 -1.25428996 0 P 0 ;1,3=20,5=0.000000
S P 0
OB 1.638 4.043 I
OS 1.638 4.019
OS 1.624 4.019
OS 1.624 4.043
OS 1.638 4.043
OE
SE
P 3.368 3.947 6 P 0 8 0
P 5.64 2.17 9 P 0 8 0

### steps/pcb/layers/spt/features
#
#Num Features
#
F 3061

#
#Units
#
U INCH

#
#Feature symbol names
#
$0 r5
$1 r6
$2 r10
$3 r19.7
$4 s1
$5 s20
$6 s31
$7 rect104x45 I
$8 rect106x8 I
$9 rect10x23 I
$10 rect10x24 I
$11 rect11x14 I
$12 rect12x15 I
$13 rect12x24 I
$14 rect12x38 I
$15 rect12x41 I
$16 rect12x45 I
$17 rect12x46 I
$18 rect12x49 I
$19 rect12x64 I
$20 rect138x116 I
$21 rect13x44 I
$22 rect140x50 I
$23 rect146x96 I
$24 rect14x11 I
$25 rect14x62 I
$26 rect15x12 I
$27 rect16x45 I
$28 rect17x24 I
$29 rect18x60 I
$30 rect20x18 I
$31 rect20x24 I
$32 rect20x47 I
$33 rect24x10 I
$34 rect24x12 I
$35 rect24x20 I
$36 rect24x28 I
$37 rect25x35 I
$38 rect27x10 I
$39 rect28x24 I
$40 rect30x34 I
$41 rect33x12 I
$42 rect33x17 I
$43 rect34x30 I
$44 rect35x33 I
$45 rect37x8 I
$46 rect38x13 I
$47 rect38x54 I
$48 rect39x41 I
$49 rect39x55 I
$50 rect39x57 I
$51 rect41x12 I
$52 rect41x87 I
$53 rect43x57 I
$54 rect45x104 I
$55 rect45x12 I
$56 rect45x16 I
$57 rect46x12 I
$58 rect47x12 I
$59 rect47x20 I
$60 rect49x12 I
$61 rect50x140 I
$62 rect53x16 I
$63 rect54x38 I
$64 rect55x33 I
$65 rect55x39 I
$66 rect55x47 I
$67 rect60x18 I
$68 rect62x14 I
$69 rect63x118 I
$70 rect64x12 I
$71 rect65x20 I
$72 rect71x10 I
$73 rect72x20 I
$74 rect75x59 I
$75 rect88x40 I
$76 rect88x56 I
$77 rect8x106 I
$78 rect8x53 I
$79 rect92x56 I
$80 rect94x130 I
$81 rect96x146 I
$82 sh041x021-l+1
$83 sh041x021-l+3
$84 sh041x021-l+5
$85 sh041x021-l+7
$86 sh041x021-r+1
$87 sh041x021-r+3
$88 sh041x021-r+5
$89 sh041x021-r+7
$90 sh052x046+1

#
#Feature attribute names
#
@0 .smd
@1 .nomenclature
@2 .geometry
@3 .string
@4 .pad_usage
@5 .string_angle

#
#Feature attribute text strings
#
&0 S049X012
&1 S028X024
&2 S046X012
&3 S020C_CST_V2
&4 S020X047
&5 S014X062
&6 S024X017
&7 S035X025
&8 S039X055
&9 S012X015
&10 S020SQ
&11 S012X064
&12 S030X034
&13 S040X088
&14 S038X054
&15 S041X012
&16 SH041X021-R
&17 S094X130
&18 SH052X046
&19 S001X001
&20 S062X014
&21 SH041X021-L
&22 S055X047
&23 S056X088
&24 S056X092
&25 S031SQ
&26 S050X140
&27 S072X020
&28 S033X035
&29 S018X020
&30 S018X060
&31 S038X012
&32 S057X039
&33 S012X049
&34 S012X046
&35 S014X011
&36 S027X010
&37 S010X023
&38 S033X055
&39 S011X014
&40 S033X012
&41 S039X041
&42 S008X037
&43 S016X053
&44 S045X104
&45 S013X038
&46 S020X065
&47 S116X138
&48 S008X106
&49 S010X024
&50 S020X024
&51 S024X012
&52 S013X044
&53 S045X016
&54 S053X008
&55 S096X146
&56 S047X012
&57 S063X118
&58 S010X071
&59 S033X017
&60 S057X043
&61 S045X012
&62 S041X087
&63 S059X075
&64 SOLDERPASTE_TOP
&65 SOLDERPASTE TOP
&66 P/N : R4006-B0001-02
&67 Date: 2022-02-25
&68 Layer:
&69 Rev : 01

#
#Layer features
#
P 4.2391 4.03136998 60 P 0 8 0;0,2=0,4=0
P 4.354 4.065 39 P 0 8 0;0,2=1,4=0
P 4.2406 4.05106004 57 P 0 8 0;0,2=2,4=0
P 4.354 4.115 39 P 0 8 0;0,2=1,4=0
P 4.65 2.299 36 P 0 8 0;0,2=1,4=0
P 4.48216998 2.04028002 3 P 0 8 0;0,2=3,4=0
P 4.62 2.419 36 P 0 8 0;0,2=1,4=0
P 4.4428 2.11901998 3 P 0 8 0;0,2=3,4=0
P 4.53 2.419 36 P 0 8 0;0,2=1,4=0
P 4.40343002 2.11901998 3 P 0 8 0;0,2=3,4=0
P 4.535 2.324 36 P 0 8 0;0,2=1,4=0
P 4.4428 2.15838996 3 P 0 8 0;0,2=3,4=0
P 4.485 2.419 36 P 0 8 0;0,2=1,4=0
P 4.40343002 2.15838996 3 P 0 8 0;0,2=3,4=0
P 3.76 2.426 36 P 0 8 0;0,2=1,4=0
P 3.6576 2.5135 32 P 0 8 0;0,2=4,4=0
P 3.705 2.426 36 P 0 8 0;0,2=1,4=0
P 2.996 0.57441004 39 P 0 8 0;0,2=1,4=0
P 2.997 0.621 39 P 0 8 0;0,2=1,4=0
P 3.6576 2.6265 32 P 0 8 0;0,2=4,4=0
P 4.20658002 2.07965 3 P 0 8 0;0,2=3,4=0
P 3.7324 2.6265 32 P 0 8 0;0,2=4,4=0
P 3.731 2.71 39 P 0 8 0;0,2=1,4=0
P 4.48216998 1.52846998 3 P 0 8 0;0,2=3,4=0
P 4.2406 3.93293996 57 P 0 8 0;0,2=2,4=0
P 4.354 3.865 39 P 0 8 0;0,2=1,4=0
P 3.2815 3.27661004 68 P 0 8 0;0,2=5,4=0
P 4.8855 0.91956998 68 P 0 8 0;0,2=5,4=0
P 4.736 0.965 39 P 0 8 0;0,2=1,4=0
P 4.736 0.915 39 P 0 8 0;0,2=1,4=0
P 4.20058996 3.4076 28 P 0 8 0;0,2=6,4=0
P 4.1695 3.24556998 68 P 0 8 0;0,2=5,4=0
P 4.015 3.291 39 P 0 8 0;0,2=1,4=0
P 4.015 3.239 39 P 0 8 0;0,2=1,4=0
P 4.00558996 3.4056 28 P 0 8 0;0,2=6,4=0
P 4.0355 3.76456998 68 P 0 8 0;0,2=5,4=0
P 3.881 3.758 39 P 0 8 0;0,2=1,4=0
P 3.881 3.81 39 P 0 8 0;0,2=1,4=0
P 4.08846998 1.60721004 3 P 0 8 0;0,2=3,4=0
P 4.205 0.879 36 P 0 8 0;0,2=1,4=0
P 4.314 0.82366004 37 P 0 8 0;0,2=7,4=0
P 3.88 0.75216998 65 P 0 8 0;0,2=8,4=0
P 3.77 0.874 36 P 0 8 0;0,2=1,4=0
P 0.49556998 2.166 12 P 0 8 0;0,2=9,4=0
P 0.51743002 2.68 12 P 0 8 0;0,2=9,4=0
P 0.52443002 1 12 P 0 8 0;0,2=9,4=0
P 0.48956998 1.57 12 P 0 8 0;0,2=9,4=0
P 4.63965 1.96153996 3 P 0 8 0;0,2=3,4=0
P 4.08846998 1.8828 3 P 0 8 0;0,2=3,4=0
P 4.48216998 1.41035 3 P 0 8 0;0,2=3,4=0
P 4.08846998 2.11901998 3 P 0 8 0;0,2=3,4=0
P 3.93098002 2.00091004 3 P 0 8 0;0,2=3,4=0
P 3.93098002 1.96153996 3 P 0 8 0;0,2=3,4=0
P 4.24595 2.04028002 3 P 0 8 0;0,2=3,4=0
P 3.97035 2.04028002 3 P 0 8 0;0,2=3,4=0
P 4.24595 2.00091004 3 P 0 8 0;0,2=3,4=0
P 4.28531998 2.07965 3 P 0 8 0;0,2=3,4=0
P 4.28531998 2.04028002 3 P 0 8 0;0,2=3,4=0
P 4.48216998 1.8828 3 P 0 8 0;0,2=3,4=0
P 4.71838996 2.07965 3 P 0 8 0;0,2=3,4=0
P 4.0491 2.00091004 3 P 0 8 0;0,2=3,4=0
P 4.48216998 1.84343002 3 P 0 8 0;0,2=3,4=0
P 4.67901998 2.04028002 3 P 0 8 0;0,2=3,4=0
P 4.60028002 1.92216998 3 P 0 8 0;0,2=3,4=0
P 4.60028002 1.96153996 3 P 0 8 0;0,2=3,4=0
P 4.28531998 2.00091004 3 P 0 8 0;0,2=3,4=0
P 4.60028002 1.8828 3 P 0 8 0;0,2=3,4=0
P 4.56091004 1.96153996 3 P 0 8 0;0,2=3,4=0
P 3.89161004 2.04028002 3 P 0 8 0;0,2=3,4=0
P 4.52153996 2.00091004 3 P 0 8 0;0,2=3,4=0
P 4.32468996 2.07965 3 P 0 8 0;0,2=3,4=0
P 4.08846998 2.07965 3 P 0 8 0;0,2=3,4=0
P 4.67901998 1.52846998 3 P 0 8 0;0,2=3,4=0
P 4.52153996 1.96153996 3 P 0 8 0;0,2=3,4=0
P 4.08846998 2.04028002 3 P 0 8 0;0,2=3,4=0
P 4.63965 1.52846998 3 P 0 8 0;0,2=3,4=0
P 3.97035 2.07965 3 P 0 8 0;0,2=3,4=0
P 4.60028002 1.56783996 3 P 0 8 0;0,2=3,4=0
P 4.00973002 2.07965 3 P 0 8 0;0,2=3,4=0
P 4.56091004 1.56783996 3 P 0 8 0;0,2=3,4=0
P 4.67901998 1.92216998 3 P 0 8 0;0,2=3,4=0
P 4.48216998 2.00091004 3 P 0 8 0;0,2=3,4=0
P 4.4428 2.00091004 3 P 0 8 0;0,2=3,4=0
P 4.40343002 1.96153996 3 P 0 8 0;0,2=3,4=0
P 4.4428 1.92216998 3 P 0 8 0;0,2=3,4=0
P 4.36406004 1.84343002 3 P 0 8 0;0,2=3,4=0
P 4.36406004 1.80406004 3 P 0 8 0;0,2=3,4=0
P 4.4428 1.96153996 3 P 0 8 0;0,2=3,4=0
P 4.12783996 1.92216998 3 P 0 8 0;0,2=3,4=0
P 4.0491 1.96153996 3 P 0 8 0;0,2=3,4=0
P 4.56091004 2.15838996 3 P 0 8 0;0,2=3,4=0
P 4.71838996 1.8828 3 P 0 8 0;0,2=3,4=0
P 4.52153996 2.11901998 3 P 0 8 0;0,2=3,4=0
P 4.12783996 2.00091004 3 P 0 8 0;0,2=3,4=0
P 4.48216998 2.11901998 3 P 0 8 0;0,2=3,4=0
P 4.00973002 1.92216998 3 P 0 8 0;0,2=3,4=0
P 4.0491 1.92216998 3 P 0 8 0;0,2=3,4=0
P 4.48216998 2.07965 3 P 0 8 0;0,2=3,4=0
P 4.16721004 2.00091004 3 P 0 8 0;0,2=3,4=0
P 4.60028002 2.15838996 3 P 0 8 0;0,2=3,4=0
P 3.93098002 1.92216998 3 P 0 8 0;0,2=3,4=0
P 3.93098002 1.8828 3 P 0 8 0;0,2=3,4=0
P 4.63965 2.15838996 3 P 0 8 0;0,2=3,4=0
P 3.89161004 1.92216998 3 P 0 8 0;0,2=3,4=0
P 4.63965 2.11901998 3 P 0 8 0;0,2=3,4=0
P 3.89161004 1.8828 3 P 0 8 0;0,2=3,4=0
P 4.0491 1.84343002 3 P 0 8 0;0,2=3,4=0
P 4.08846998 1.44973002 3 P 0 8 0;0,2=3,4=0
P 4.52153996 1.56783996 3 P 0 8 0;0,2=3,4=0
P 4.28531998 1.52846998 3 P 0 8 0;0,2=3,4=0
P 4.20658002 1.92216998 3 P 0 8 0;0,2=3,4=0
P 4.16721004 1.4891 3 P 0 8 0;0,2=3,4=0
P 4.20658002 1.4891 3 P 0 8 0;0,2=3,4=0
P 4.20658002 2.11901998 3 P 0 8 0;0,2=3,4=0
P 4.67901998 1.44973002 3 P 0 8 0;0,2=3,4=0
P 4.12783996 1.41035 3 P 0 8 0;0,2=3,4=0
P 4.63965 1.44973002 3 P 0 8 0;0,2=3,4=0
P 4.16721004 1.41035 3 P 0 8 0;0,2=3,4=0
P 4.60028002 1.44973002 3 P 0 8 0;0,2=3,4=0
P 4.12783996 1.44973002 3 P 0 8 0;0,2=3,4=0
P 4.56091004 1.44973002 3 P 0 8 0;0,2=3,4=0
P 4.16721004 1.44973002 3 P 0 8 0;0,2=3,4=0
P 4.20658002 1.44973002 3 P 0 8 0;0,2=3,4=0
P 4.24595 1.44973002 3 P 0 8 0;0,2=3,4=0
P 4.52153996 1.4891 3 P 0 8 0;0,2=3,4=0
P 4.24595 1.41035 3 P 0 8 0;0,2=3,4=0
P 4.48216998 1.4891 3 P 0 8 0;0,2=3,4=0
P 4.28531998 1.41035 3 P 0 8 0;0,2=3,4=0
P 4.60028002 1.4891 3 P 0 8 0;0,2=3,4=0
P 4.28531998 1.33161004 3 P 0 8 0;0,2=3,4=0
P 4.60028002 1.52846998 3 P 0 8 0;0,2=3,4=0
P 4.32468996 1.33161004 3 P 0 8 0;0,2=3,4=0
P 4.56091004 1.4891 3 P 0 8 0;0,2=3,4=0
P 4.32468996 1.37098002 3 P 0 8 0;0,2=3,4=0
P 4.52153996 1.52846998 3 P 0 8 0;0,2=3,4=0
P 4.32468996 1.41035 3 P 0 8 0;0,2=3,4=0
P 4.20658002 1.52846998 3 P 0 8 0;0,2=3,4=0
P 4.4428 1.52846998 3 P 0 8 0;0,2=3,4=0
P 4.24595 1.52846998 3 P 0 8 0;0,2=3,4=0
P 4.28531998 1.44973002 3 P 0 8 0;0,2=3,4=0
P 4.28531998 1.4891 3 P 0 8 0;0,2=3,4=0
P 4.36406004 1.41035 3 P 0 8 0;0,2=3,4=0
P 4.36406004 1.44973002 3 P 0 8 0;0,2=3,4=0
P 4.52153996 1.33161004 3 P 0 8 0;0,2=3,4=0
P 3.89161004 1.33161004 3 P 0 8 0;0,2=3,4=0
P 4.48216998 1.33161004 3 P 0 8 0;0,2=3,4=0
P 3.93098002 1.33161004 3 P 0 8 0;0,2=3,4=0
P 4.32468996 1.96153996 3 P 0 8 0;0,2=3,4=0
P 4.56091004 1.37098002 3 P 0 8 0;0,2=3,4=0
P 3.93098002 1.37098002 3 P 0 8 0;0,2=3,4=0
P 4.52153996 1.37098002 3 P 0 8 0;0,2=3,4=0
P 3.97035 1.37098002 3 P 0 8 0;0,2=3,4=0
P 4.4428 1.37098002 3 P 0 8 0;0,2=3,4=0
P 4.00973002 1.33161004 3 P 0 8 0;0,2=3,4=0
P 4.4428 1.41035 3 P 0 8 0;0,2=3,4=0
P 4.0491 1.33161004 3 P 0 8 0;0,2=3,4=0
P 4.63965 1.37098002 3 P 0 8 0;0,2=3,4=0
P 4.00973002 1.37098002 3 P 0 8 0;0,2=3,4=0
P 4.60028002 1.37098002 3 P 0 8 0;0,2=3,4=0
P 4.0491 1.37098002 3 P 0 8 0;0,2=3,4=0
P 4.67901998 1.84343002 3 P 0 8 0;0,2=3,4=0
P 4.4428 2.04028002 3 P 0 8 0;0,2=3,4=0
P 4.08846998 1.33161004 3 P 0 8 0;0,2=3,4=0
P 4.63965 1.80406004 3 P 0 8 0;0,2=3,4=0
P 4.40343002 2.04028002 3 P 0 8 0;0,2=3,4=0
P 4.12783996 1.33161004 3 P 0 8 0;0,2=3,4=0
P 4.56091004 1.41035 3 P 0 8 0;0,2=3,4=0
P 4.0491 1.41035 3 P 0 8 0;0,2=3,4=0
P 4.52153996 1.41035 3 P 0 8 0;0,2=3,4=0
P 4.08846998 1.41035 3 P 0 8 0;0,2=3,4=0
P 4.71838996 1.76468996 3 P 0 8 0;0,2=3,4=0
P 4.71838996 1.33161004 3 P 0 8 0;0,2=3,4=0
P 4.20658002 1.33161004 3 P 0 8 0;0,2=3,4=0
P 4.71838996 1.72531998 3 P 0 8 0;0,2=3,4=0
P 4.67901998 1.33161004 3 P 0 8 0;0,2=3,4=0
P 4.24595 1.33161004 3 P 0 8 0;0,2=3,4=0
P 4.12783996 1.37098002 3 P 0 8 0;0,2=3,4=0
P 4.16721004 1.37098002 3 P 0 8 0;0,2=3,4=0
P 4.67901998 1.41035 3 P 0 8 0;0,2=3,4=0
P 4.20658002 1.37098002 3 P 0 8 0;0,2=3,4=0
P 4.63965 1.41035 3 P 0 8 0;0,2=3,4=0
P 4.24595 1.37098002 3 P 0 8 0;0,2=3,4=0
P 4.71838996 2.15838996 3 P 0 8 0;0,2=3,4=0
P 4.71838996 2.11901998 3 P 0 8 0;0,2=3,4=0
P 4.56091004 2.07965 3 P 0 8 0;0,2=3,4=0
P 4.52153996 2.07965 3 P 0 8 0;0,2=3,4=0
P 4.56091004 1.84343002 3 P 0 8 0;0,2=3,4=0
P 4.63965 2.04028002 3 P 0 8 0;0,2=3,4=0
P 4.56091004 2.04028002 3 P 0 8 0;0,2=3,4=0
P 4.52153996 1.8828 3 P 0 8 0;0,2=3,4=0
P 4.56091004 2.00091004 3 P 0 8 0;0,2=3,4=0
P 4.24595 1.96153996 3 P 0 8 0;0,2=3,4=0
P 4.28531998 1.92216998 3 P 0 8 0;0,2=3,4=0
P 4.12783996 1.96153996 3 P 0 8 0;0,2=3,4=0
P 4.16721004 1.96153996 3 P 0 8 0;0,2=3,4=0
P 4.60028002 2.11901998 3 P 0 8 0;0,2=3,4=0
P 4.67901998 1.72531998 3 P 0 8 0;0,2=3,4=0
P 4.67901998 1.68595 3 P 0 8 0;0,2=3,4=0
P 1.59668996 3.17 5 P 0 8 0;0,2=10,4=0
P 0.72 3.5065 32 P 0 8 0;0,2=4,4=0
P 1.11316004 3.578 19 P 0 8 0;0,2=11,4=0
P 1.21158002 3.578 19 P 0 8 0;0,2=11,4=0
P 4.652 3.86 40 P 0 8 0;0,2=12,4=0
P 4.78656004 3.90826998 75 P 0 8 0;0,2=13,4=0
P 4.654 3.927 47 P 0 8 0;0,2=14,4=0
P 1.62033002 2.99531004 51 P 0 8 0;0,2=15,4=0
P 1.055 3.731 36 P 0 8 0;0,2=1,4=0
P 0.894 3.43758002 70 P 0 8 0;0,2=11,4=0
P 1.352 3.33916004 70 P 0 8 0;0,2=11,4=0
P 1.352 3.22105 70 P 0 8 0;0,2=11,4=0
P 1.62033002 3.03468996 51 P 0 8 0;0,2=15,4=0
P 1.62033002 3.05888002 86 P 0 8 0;0,2=16,4=0
P 1.455 3.138 43 P 0 8 0;0,2=12,4=0
P 1.46 3.073 63 P 0 8 0;0,2=14,4=0
P 1.51 3.164 36 P 0 8 0;0,2=1,4=0
P 1.53 3.046 36 P 0 8 0;0,2=1,4=0
P 1.15253002 3.12 19 P 0 8 0;0,2=11,4=0
P 0.894 3.22105 70 P 0 8 0;0,2=11,4=0
P 1.175 2.939 36 P 0 8 0;0,2=1,4=0
P 1.025 2.981 36 P 0 8 0;0,2=1,4=0
P 5.314 3.902 40 P 0 8 0;0,2=12,4=0
P 5.32 3.957 39 P 0 8 0;0,2=1,4=0
P 5.762 3.467 39 P 0 8 0;0,2=1,4=0
P 5.55091998 3.306 80 P 0 8 0;0,2=17,4=0
P 5.533 3.569 40 P 0 8 0;0,2=12,4=0
P 5.595 3.569 39 P 0 8 0;0,2=1,4=0
P 5.536 3.64025 90 P 0 8 0;0,2=18,4=0
P 5.55606998 3.63305 4 P 0 8 0;0,2=19,4=0
P 0.571 3.899 43 P 0 8 0;0,2=12,4=0
P 0.76221004 0.9475 25 P 0 8 0;0,2=20,4=0
P 0.7878 0.9475 25 P 0 8 0;0,2=20,4=0
P 0.81338996 0.9475 25 P 0 8 0;0,2=20,4=0
P 1.62033002 3.015 51 P 0 8 0;0,2=15,4=0
P 1.526 2.95 39 P 0 8 0;0,2=1,4=0
P 1.53 3.004 36 P 0 8 0;0,2=1,4=0
P 1.819 3.19 39 P 0 8 0;0,2=1,4=0
P 1.782 3.26 47 P 0 8 0;0,2=14,4=0
P 1.68331004 3.17 5 P 0 8 0;0,2=10,4=0
P 1.68331004 3.27 5 P 0 8 0;0,2=10,4=0
P 1.76 3.187 43 P 0 8 0;0,2=12,4=0
P 1.73966998 2.97111998 87 P 0 8 0;0,2=16,4=0
P 1.73543002 2.9 12 P 0 8 0;0,2=9,4=0
P 1.73966998 3.03468996 51 P 0 8 0;0,2=15,4=0
P 1.73966998 3.05888002 82 P 0 8 0;0,2=21,4=0
P 1.822 3.105 47 P 0 8 0;0,2=14,4=0
P 1.835 2.981 36 P 0 8 0;0,2=1,4=0
P 1.76 3.133 43 P 0 8 0;0,2=12,4=0
P 1.824 3.04 39 P 0 8 0;0,2=1,4=0
P 1.73966998 2.99531004 51 P 0 8 0;0,2=15,4=0
P 1.885 2.939 36 P 0 8 0;0,2=1,4=0
P 1.835 2.939 36 P 0 8 0;0,2=1,4=0
P 5.249 0.87 39 P 0 8 0;0,2=1,4=0
P 5.1245 0.89398002 68 P 0 8 0;0,2=5,4=0
P 4.4085 3.21998002 68 P 0 8 0;0,2=5,4=0
P 4.512 3.22 39 P 0 8 0;0,2=1,4=0
P 4.384 3.745 39 P 0 8 0;0,2=1,4=0
P 4.384 3.7 39 P 0 8 0;0,2=1,4=0
P 4.435 3.6185 49 P 0 8 0;0,2=8,4=0
P 4.2745 3.73898002 68 P 0 8 0;0,2=5,4=0
P 0.894 3.35883996 70 P 0 8 0;0,2=11,4=0
P 1.01473002 3.578 19 P 0 8 0;0,2=11,4=0
P 1.17221004 3.578 19 P 0 8 0;0,2=11,4=0
P 0.99505 3.12 19 P 0 8 0;0,2=11,4=0
P 0.97536004 3.12 19 P 0 8 0;0,2=11,4=0
P 0.894 3.20136004 70 P 0 8 0;0,2=11,4=0
P 0.894 3.24073002 70 P 0 8 0;0,2=11,4=0
P 0.894 3.26041998 70 P 0 8 0;0,2=11,4=0
P 0.589 3.29 39 P 0 8 0;0,2=1,4=0
P 0.595 3.554 36 P 0 8 0;0,2=1,4=0
P 1.25095 3.578 19 P 0 8 0;0,2=11,4=0
P 1.29831004 3.91846004 66 P 0 8 0;0,2=22,4=0
P 1.26956998 3.79 12 P 0 8 0;0,2=9,4=0
P 1.271 3.75 39 P 0 8 0;0,2=1,4=0
P 1.23126998 3.578 19 P 0 8 0;0,2=11,4=0
P 1.21168996 3.85153996 66 P 0 8 0;0,2=22,4=0
P 1.23543002 3.79 12 P 0 8 0;0,2=9,4=0
P 1.229 3.75 39 P 0 8 0;0,2=1,4=0
P 5.9945 1.57063002 76 P 0 8 0;0,2=23,4=0
P 6.14648002 1.57063002 79 P 0 8 0;0,2=24,4=0
P 5.9945 1.47063002 76 P 0 8 0;0,2=23,4=0
P 6.14648002 1.47063002 79 P 0 8 0;0,2=24,4=0
P 5.9945 1.67063002 76 P 0 8 0;0,2=23,4=0
P 6.14648002 1.67063002 79 P 0 8 0;0,2=24,4=0
P 5.9945 1.77063002 76 P 0 8 0;0,2=23,4=0
P 6.14648002 1.77063002 79 P 0 8 0;0,2=24,4=0
P 6.1437 4.13778996 6 P 0 8 0;0,2=25,4=0
P 1.025 2.939 36 P 0 8 0;0,2=1,4=0
P 1.075 2.939 36 P 0 8 0;0,2=1,4=0
P 4.40343002 1.92216998 3 P 0 8 0;0,2=3,4=0
P 1.125 2.939 36 P 0 8 0;0,2=1,4=0
P 4.40343002 1.8828 3 P 0 8 0;0,2=3,4=0
P 3.44256004 2.765 22 P 0 8 0;0,2=26,4=0
P 1.1737 0.7536 39 P 0 8 0;0,2=1,4=0
P 1.0705 0.7284 59 P 0 8 0;0,2=4,4=0
P 3.44256004 2.865 22 P 0 8 0;0,2=26,4=0
P 0.7878 0.7085 25 P 0 8 0;0,2=20,4=0
P 0.73661998 0.7085 25 P 0 8 0;0,2=20,4=0
P 1.13283996 3.578 19 P 0 8 0;0,2=11,4=0
P 1.105 3.689 36 P 0 8 0;0,2=1,4=0
P 1.15253002 3.578 19 P 0 8 0;0,2=11,4=0
P 1.155 3.689 36 P 0 8 0;0,2=1,4=0
P 0.894 3.45726998 70 P 0 8 0;0,2=11,4=0
P 0.894 3.47695 70 P 0 8 0;0,2=11,4=0
P 0.894 3.49663996 70 P 0 8 0;0,2=11,4=0
P 0.97536004 3.578 19 P 0 8 0;0,2=11,4=0
P 0.894 3.29978996 70 P 0 8 0;0,2=11,4=0
P 0.746 3.2 39 P 0 8 0;0,2=1,4=0
P 0.894 3.2801 70 P 0 8 0;0,2=11,4=0
P 0.894 3.31946998 70 P 0 8 0;0,2=11,4=0
P 0.746 3.245 39 P 0 8 0;0,2=1,4=0
P 1.27063996 3.12 19 P 0 8 0;0,2=11,4=0
P 1.352 3.26041998 70 P 0 8 0;0,2=11,4=0
P 1.075 2.981 36 P 0 8 0;0,2=1,4=0
P 1.07378996 3.12 19 P 0 8 0;0,2=11,4=0
P 1.175 2.981 36 P 0 8 0;0,2=1,4=0
P 1.125 2.981 36 P 0 8 0;0,2=1,4=0
P 1.09346998 3.12 19 P 0 8 0;0,2=11,4=0
P 1.105 3.731 36 P 0 8 0;0,2=1,4=0
P 0.6826 3.5065 32 P 0 8 0;0,2=4,4=0
P 1.155 3.731 36 P 0 8 0;0,2=1,4=0
P 0.7574 3.5065 32 P 0 8 0;0,2=4,4=0
P 1.055 3.689 36 P 0 8 0;0,2=1,4=0
P 4.34 3.496 36 P 0 8 0;0,2=1,4=0
P 4.398 3.5315 49 P 0 8 0;0,2=8,4=0
P 1.352 3.43758002 70 P 0 8 0;0,2=11,4=0
P 1.352 3.47695 70 P 0 8 0;0,2=11,4=0
P 1.352 3.45726998 70 P 0 8 0;0,2=11,4=0
P 1.0541 3.12 19 P 0 8 0;0,2=11,4=0
P 1.352 3.20136004 70 P 0 8 0;0,2=11,4=0
P 1.352 3.49663996 70 P 0 8 0;0,2=11,4=0
P 1.0541 3.578 19 P 0 8 0;0,2=11,4=0
P 4.2745 3.6622 68 P 0 8 0;0,2=5,4=0
P 4.2745 3.58543002 68 P 0 8 0;0,2=5,4=0
P 4.0355 3.61101998 68 P 0 8 0;0,2=5,4=0
P 4.0355 3.6878 68 P 0 8 0;0,2=5,4=0
P 4.1695 3.11761004 68 P 0 8 0;0,2=5,4=0
P 4.0355 3.63661004 68 P 0 8 0;0,2=5,4=0
P 4.4085 3.09201998 68 P 0 8 0;0,2=5,4=0
P 4.2745 3.61101998 68 P 0 8 0;0,2=5,4=0
P 4.4085 3.1688 68 P 0 8 0;0,2=5,4=0
P 4.2745 3.6878 68 P 0 8 0;0,2=5,4=0
P 4.1695 3.19438996 68 P 0 8 0;0,2=5,4=0
P 4.0355 3.71338996 68 P 0 8 0;0,2=5,4=0
P 4.694 0.915 39 P 0 8 0;0,2=1,4=0
P 0.894 3.37853002 70 P 0 8 0;0,2=11,4=0
P 3.973 3.239 39 P 0 8 0;0,2=1,4=0
P 0.894 3.39821004 70 P 0 8 0;0,2=11,4=0
P 0.894 3.4179 70 P 0 8 0;0,2=11,4=0
P 3.839 3.758 39 P 0 8 0;0,2=1,4=0
P 5.1245 0.76601998 68 P 0 8 0;0,2=5,4=0
P 4.8855 0.86838996 68 P 0 8 0;0,2=5,4=0
P 0.704 3.2 39 P 0 8 0;0,2=1,4=0
P 5.1245 0.8428 68 P 0 8 0;0,2=5,4=0
P 4.8855 0.79161004 68 P 0 8 0;0,2=5,4=0
P 0.704 3.245 39 P 0 8 0;0,2=1,4=0
P 4.2745 3.71338996 68 P 0 8 0;0,2=5,4=0
P 5.71056004 2.821 22 P 0 8 0;0,2=26,4=0
P 4.2745 3.63661004 68 P 0 8 0;0,2=5,4=0
P 5.71056004 2.721 22 P 0 8 0;0,2=26,4=0
P 4.0355 3.6622 68 P 0 8 0;0,2=5,4=0
P 5.71056004 3.021 22 P 0 8 0;0,2=26,4=0
P 4.0355 3.73898002 68 P 0 8 0;0,2=5,4=0
P 5.71056004 2.621 22 P 0 8 0;0,2=26,4=0
P 6.22356004 2.715 22 P 0 8 0;0,2=26,4=0
P 6.22356004 2.615 22 P 0 8 0;0,2=26,4=0
P 6.22356004 2.815 22 P 0 8 0;0,2=26,4=0
P 6.22356004 2.915 22 P 0 8 0;0,2=26,4=0
P 4.48216998 1.92216998 3 P 0 8 0;0,2=3,4=0
P 4.736 0.865 39 P 0 8 0;0,2=1,4=0
P 4.8855 0.89398002 68 P 0 8 0;0,2=5,4=0
P 4.36406004 1.96153996 3 P 0 8 0;0,2=3,4=0
P 4.736 0.785 39 P 0 8 0;0,2=1,4=0
P 4.8855 0.8172 68 P 0 8 0;0,2=5,4=0
P 4.67901998 1.80406004 3 P 0 8 0;0,2=3,4=0
P 4.71838996 1.80406004 3 P 0 8 0;0,2=3,4=0
P 4.694 0.965 39 P 0 8 0;0,2=1,4=0
P 4.12783996 1.8828 3 P 0 8 0;0,2=3,4=0
P 4.12783996 1.80406004 3 P 0 8 0;0,2=3,4=0
P 3.973 3.291 39 P 0 8 0;0,2=1,4=0
P 4.16721004 1.80406004 3 P 0 8 0;0,2=3,4=0
P 3.839 3.81 39 P 0 8 0;0,2=1,4=0
P 4.67901998 1.8828 3 P 0 8 0;0,2=3,4=0
P 4.34 3.454 36 P 0 8 0;0,2=1,4=0
P 4.28531998 2.11901998 3 P 0 8 0;0,2=3,4=0
P 4.15 2.51 36 P 0 8 0;0,2=1,4=0
P 4.209 2.51 36 P 0 8 0;0,2=1,4=0
P 4.32468996 2.11901998 3 P 0 8 0;0,2=3,4=0
P 4.093 2.51 36 P 0 8 0;0,2=1,4=0
P 4.24595 2.15838996 3 P 0 8 0;0,2=3,4=0
P 4.037 2.51 36 P 0 8 0;0,2=1,4=0
P 4.24595 2.11901998 3 P 0 8 0;0,2=3,4=0
P 3.801 2.51 36 P 0 8 0;0,2=1,4=0
P 4.12783996 2.07965 3 P 0 8 0;0,2=3,4=0
P 3.86 2.51 36 P 0 8 0;0,2=1,4=0
P 4.16721004 2.07965 3 P 0 8 0;0,2=3,4=0
P 3.919 2.51 36 P 0 8 0;0,2=1,4=0
P 4.16721004 2.15838996 3 P 0 8 0;0,2=3,4=0
P 4.20658002 2.15838996 3 P 0 8 0;0,2=3,4=0
P 3.978 2.51 36 P 0 8 0;0,2=1,4=0
P 4.62 2.461 36 P 0 8 0;0,2=1,4=0
P 4.14941004 3.4076 28 P 0 8 0;0,2=6,4=0
P 4.08 3.429 36 P 0 8 0;0,2=1,4=0
P 4.53 2.461 36 P 0 8 0;0,2=1,4=0
P 3.95441004 3.4056 28 P 0 8 0;0,2=6,4=0
P 3.87 3.424 36 P 0 8 0;0,2=1,4=0
P 4.575 2.419 36 P 0 8 0;0,2=1,4=0
P 4.4085 3.11761004 68 P 0 8 0;0,2=5,4=0
P 4.535 2.366 36 P 0 8 0;0,2=1,4=0
P 4.485 2.461 36 P 0 8 0;0,2=1,4=0
P 4.1695 3.1432 68 P 0 8 0;0,2=5,4=0
P 4.65 2.341 36 P 0 8 0;0,2=1,4=0
P 4.4085 3.19438996 68 P 0 8 0;0,2=5,4=0
P 4.1695 3.21998002 68 P 0 8 0;0,2=5,4=0
P 5.1245 0.79161004 68 P 0 8 0;0,2=5,4=0
P 5.249 0.76 39 P 0 8 0;0,2=1,4=0
P 4.71838996 1.96153996 3 P 0 8 0;0,2=3,4=0
P 5.249 0.82 39 P 0 8 0;0,2=1,4=0
P 5.1245 0.86838996 68 P 0 8 0;0,2=5,4=0
P 4.71838996 1.92216998 3 P 0 8 0;0,2=3,4=0
P 4.08 3.471 36 P 0 8 0;0,2=1,4=0
P 4.14941004 3.4824 28 P 0 8 0;0,2=6,4=0
P 3.87 3.466 36 P 0 8 0;0,2=1,4=0
P 3.95441004 3.4804 28 P 0 8 0;0,2=6,4=0
P 4.4085 3.06643002 68 P 0 8 0;0,2=5,4=0
P 4.1695 3.09201998 68 P 0 8 0;0,2=5,4=0
P 4.4085 3.1432 68 P 0 8 0;0,2=5,4=0
P 3.769 3.235 73 P 0 8 0;0,2=27,4=0
P 4.1695 3.1688 68 P 0 8 0;0,2=5,4=0
P 3.481 3.335 73 P 0 8 0;0,2=27,4=0
P 1.3085 0.658 39 P 0 8 0;0,2=1,4=0
P 1.3085 0.613 39 P 0 8 0;0,2=1,4=0
P 0.805 1.42243996 61 P 0 8 0;0,2=26,4=0
P 1.2157 0.6586 39 P 0 8 0;0,2=1,4=0
P 0.705 1.42243996 61 P 0 8 0;0,2=26,4=0
P 0.9575 0.7284 59 P 0 8 0;0,2=4,4=0
P 1.3087 0.708 39 P 0 8 0;0,2=1,4=0
P 1.3087 0.753 39 P 0 8 0;0,2=1,4=0
P 1.1737 0.7086 39 P 0 8 0;0,2=1,4=0
P 0.76221004 0.7085 25 P 0 8 0;0,2=20,4=0
P 0.705 1.62756004 61 P 0 8 0;0,2=26,4=0
P 0.805 1.62756004 61 P 0 8 0;0,2=26,4=0
P 0.06873996 3.30413996 44 P 0 8 0;0,2=28,4=0
P 0.38 3.231 36 P 0 8 0;0,2=1,4=0
P 0.43 3.231 36 P 0 8 0;0,2=1,4=0
P 0.08251998 3.2687 30 P 0 8 0;0,2=29,4=0
P 0.28 3.231 36 P 0 8 0;0,2=1,4=0
P 0.33 3.231 36 P 0 8 0;0,2=1,4=0
P 0.23 3.231 36 P 0 8 0;0,2=1,4=0
P 0.18 3.231 36 P 0 8 0;0,2=1,4=0
P 0.06873996 3.1998 44 P 0 8 0;0,2=28,4=0
P 0.74546998 1.975 39 P 0 8 0;0,2=1,4=0
P 0.74546998 1.93 39 P 0 8 0;0,2=1,4=0
P 0.06873996 2.16241004 44 P 0 8 0;0,2=28,4=0
P 0.74546998 1.885 39 P 0 8 0;0,2=1,4=0
P 0.74546998 1.84 39 P 0 8 0;0,2=1,4=0
P 0.08251998 2.12696998 30 P 0 8 0;0,2=29,4=0
P 0.74546998 1.795 39 P 0 8 0;0,2=1,4=0
P 0.74546998 1.75 39 P 0 8 0;0,2=1,4=0
P 0.06873996 2.05806998 44 P 0 8 0;0,2=28,4=0
P 0.377 2.70608002 36 P 0 8 0;0,2=1,4=0
P 0.422 2.70608002 36 P 0 8 0;0,2=1,4=0
P 0.06873996 2.73326998 44 P 0 8 0;0,2=28,4=0
P 0.287 2.70608002 36 P 0 8 0;0,2=1,4=0
P 0.332 2.70608002 36 P 0 8 0;0,2=1,4=0
P 0.08251998 2.69783002 30 P 0 8 0;0,2=29,4=0
P 0.197 2.70608002 36 P 0 8 0;0,2=1,4=0
P 0.242 2.70608002 36 P 0 8 0;0,2=1,4=0
P 0.06873996 2.62893002 44 P 0 8 0;0,2=28,4=0
P 0.779 1.25 39 P 0 8 0;0,2=1,4=0
P 0.779 1.3 39 P 0 8 0;0,2=1,4=0
P 0.06873996 1.02066998 44 P 0 8 0;0,2=28,4=0
P 0.779 1.2 39 P 0 8 0;0,2=1,4=0
P 0.779 1.15 39 P 0 8 0;0,2=1,4=0
P 0.08251998 0.98523002 30 P 0 8 0;0,2=29,4=0
P 0.779 1.1 39 P 0 8 0;0,2=1,4=0
P 0.779 1.05 39 P 0 8 0;0,2=1,4=0
P 0.06873996 0.91633002 44 P 0 8 0;0,2=28,4=0
P 0.371 1.56898002 36 P 0 8 0;0,2=1,4=0
P 0.416 1.56898002 36 P 0 8 0;0,2=1,4=0
P 0.06873996 1.59153996 44 P 0 8 0;0,2=28,4=0
P 0.08251998 1.5561 30 P 0 8 0;0,2=29,4=0
P 0.281 1.56898002 36 P 0 8 0;0,2=1,4=0
P 0.326 1.56898002 36 P 0 8 0;0,2=1,4=0
P 0.06873996 1.4872 44 P 0 8 0;0,2=28,4=0
P 0.191 1.56898002 36 P 0 8 0;0,2=1,4=0
P 0.236 1.56898002 36 P 0 8 0;0,2=1,4=0
P 3.0425 3.22543002 68 P 0 8 0;0,2=5,4=0
P 2.937 3.206 39 P 0 8 0;0,2=1,4=0
P 0.8594 2.4275 29 P 0 8 0;0,2=30,4=0
P 4.2391 4.01168996 60 P 0 8 0;0,2=0,4=0
P 4.354 4.015 39 P 0 8 0;0,2=1,4=0
P 4.2391 3.95263002 60 P 0 8 0;0,2=0,4=0
P 4.354 3.915 39 P 0 8 0;0,2=1,4=0
P 4.396 4.065 39 P 0 8 0;0,2=1,4=0
P 2.895 3.259 39 P 0 8 0;0,2=1,4=0
P 1.3505 0.658 39 P 0 8 0;0,2=1,4=0
P 4.396 4.115 39 P 0 8 0;0,2=1,4=0
P 2.896 3.332 39 P 0 8 0;0,2=1,4=0
P 1.3507 0.753 39 P 0 8 0;0,2=1,4=0
P 4.63965 2.00091004 3 P 0 8 0;0,2=3,4=0
P 4.60028002 2.04028002 3 P 0 8 0;0,2=3,4=0
P 4.60028002 2.07965 3 P 0 8 0;0,2=3,4=0
P 0.8338 2.2465 29 P 0 8 0;0,2=30,4=0
P 0.64248002 2.664 39 P 0 8 0;0,2=1,4=0
P 0.64248002 2.709 39 P 0 8 0;0,2=1,4=0
P 0.80648002 2.831 36 P 0 8 0;0,2=1,4=0
P 0.756 2.79 39 P 0 8 0;0,2=1,4=0
P 0.8082 2.2465 29 P 0 8 0;0,2=30,4=0
P 6.02558996 4.13778996 6 P 0 8 0;0,2=25,4=0
P 5.90748002 4.13778996 6 P 0 8 0;0,2=25,4=0
P 0.78746998 1.84 39 P 0 8 0;0,2=1,4=0
P 4.08846998 2.00091004 3 P 0 8 0;0,2=3,4=0
P 4.00973002 2.04028002 3 P 0 8 0;0,2=3,4=0
P 0.78746998 1.975 39 P 0 8 0;0,2=1,4=0
P 4.0491 2.04028002 3 P 0 8 0;0,2=3,4=0
P 0.78746998 1.795 39 P 0 8 0;0,2=1,4=0
P 3.97035 2.00091004 3 P 0 8 0;0,2=3,4=0
P 0.287 2.66408002 36 P 0 8 0;0,2=1,4=0
P 0.422 2.66408002 36 P 0 8 0;0,2=1,4=0
P 3.97035 1.96153996 3 P 0 8 0;0,2=3,4=0
P 0.242 2.66408002 36 P 0 8 0;0,2=1,4=0
P 4.00973002 1.96153996 3 P 0 8 0;0,2=3,4=0
P 0.821 1.15 39 P 0 8 0;0,2=1,4=0
P 4.0491 1.80406004 3 P 0 8 0;0,2=3,4=0
P 0.821 1.25 39 P 0 8 0;0,2=1,4=0
P 3.97035 1.8828 3 P 0 8 0;0,2=3,4=0
P 0.821 1.1 39 P 0 8 0;0,2=1,4=0
P 3.97035 1.84343002 3 P 0 8 0;0,2=3,4=0
P 4.08846998 1.92216998 3 P 0 8 0;0,2=3,4=0
P 0.281 1.52698002 36 P 0 8 0;0,2=1,4=0
P 4.08846998 1.84343002 3 P 0 8 0;0,2=3,4=0
P 0.371 1.52698002 36 P 0 8 0;0,2=1,4=0
P 4.08846998 1.80406004 3 P 0 8 0;0,2=3,4=0
P 0.236 1.52698002 36 P 0 8 0;0,2=1,4=0
P 0.28 3.189 36 P 0 8 0;0,2=1,4=0
P 3.89161004 2.00091004 3 P 0 8 0;0,2=3,4=0
P 0.38 3.189 36 P 0 8 0;0,2=1,4=0
P 3.89161004 2.07965 3 P 0 8 0;0,2=3,4=0
P 0.23 3.189 36 P 0 8 0;0,2=1,4=0
P 3.93098002 2.07965 3 P 0 8 0;0,2=3,4=0
P 0.55708002 1.92086998 14 P 0 8 0;0,2=31,4=0
P 0.53 2.049 36 P 0 8 0;0,2=1,4=0
P 0.55708002 2.49173996 14 P 0 8 0;0,2=31,4=0
P 0.53 2.584 36 P 0 8 0;0,2=1,4=0
P 0.455 1.781 36 P 0 8 0;0,2=1,4=0
P 0.2725 2.0965 50 P 0 8 0;0,2=32,4=0
P 0.46451998 2.233 36 P 0 8 0;0,2=1,4=0
P 0.2725 2.1835 50 P 0 8 0;0,2=32,4=0
P 0.2725 0.9565 50 P 0 8 0;0,2=32,4=0
P 0.455 1.0839 36 P 0 8 0;0,2=1,4=0
P 0.2725 1.0435 50 P 0 8 0;0,2=32,4=0
P 0.455 1.739 36 P 0 8 0;0,2=1,4=0
P 0.455 1.686 36 P 0 8 0;0,2=1,4=0
P 0.51771998 1.78778996 14 P 0 8 0;0,2=31,4=0
P 0.5374 1.78778996 14 P 0 8 0;0,2=31,4=0
P 0.46451998 2.275 36 P 0 8 0;0,2=1,4=0
P 0.51771998 2.35866004 14 P 0 8 0;0,2=31,4=0
P 0.5374 2.35866004 14 P 0 8 0;0,2=31,4=0
P 0.452 2.326 36 P 0 8 0;0,2=1,4=0
P 0.5374 0.64606004 14 P 0 8 0;0,2=31,4=0
P 0.51771998 0.64606004 14 P 0 8 0;0,2=31,4=0
P 0.443 0.647 36 P 0 8 0;0,2=1,4=0
P 0.5374 1.21691998 14 P 0 8 0;0,2=31,4=0
P 0.51771998 1.21691998 14 P 0 8 0;0,2=31,4=0
P 0.455 1.178 36 P 0 8 0;0,2=1,4=0
P 0.455 1.1259 36 P 0 8 0;0,2=1,4=0
P 0.5374 1.92086998 14 P 0 8 0;0,2=31,4=0
P 0.48 2.049 36 P 0 8 0;0,2=1,4=0
P 0.5374 2.49173996 14 P 0 8 0;0,2=31,4=0
P 0.478 2.569 36 P 0 8 0;0,2=1,4=0
P 0.485 0.884 36 P 0 8 0;0,2=1,4=0
P 0.5374 0.77913996 14 P 0 8 0;0,2=31,4=0
P 0.48 1.444 36 P 0 8 0;0,2=1,4=0
P 0.5374 1.35 14 P 0 8 0;0,2=31,4=0
P 6.2655 1.0066 67 P 0 8 0;0,2=30,4=0
P 6.379 0.965 39 P 0 8 0;0,2=1,4=0
P 6.2655 1.0322 67 P 0 8 0;0,2=30,4=0
P 6.379 1.02 39 P 0 8 0;0,2=1,4=0
P 6.379 1.08 39 P 0 8 0;0,2=1,4=0
P 6.2655 1.0578 67 P 0 8 0;0,2=30,4=0
P 2.0966 3.0845 29 P 0 8 0;0,2=30,4=0
P 2.083 2.973 36 P 0 8 0;0,2=1,4=0
P 2.1222 3.0845 29 P 0 8 0;0,2=30,4=0
P 2.128 2.973 36 P 0 8 0;0,2=1,4=0
P 2.1478 3.0845 29 P 0 8 0;0,2=30,4=0
P 2.173 2.973 36 P 0 8 0;0,2=1,4=0
P 5.956 1.08 39 P 0 8 0;0,2=1,4=0
P 6.0845 1.0834 67 P 0 8 0;0,2=30,4=0
P 2.1734 3.2655 29 P 0 8 0;0,2=30,4=0
P 2.2628 3.287 36 P 0 8 0;0,2=1,4=0
P 5.956 0.965 39 P 0 8 0;0,2=1,4=0
P 6.0845 1.0322 67 P 0 8 0;0,2=30,4=0
P 4.32468996 2.00091004 3 P 0 8 0;0,2=3,4=0
P 4.32468996 2.15838996 3 P 0 8 0;0,2=3,4=0
P 1.959 3.247 36 P 0 8 0;0,2=1,4=0
P 2.1222 3.2655 29 P 0 8 0;0,2=30,4=0
P 4.36406004 2.15838996 3 P 0 8 0;0,2=3,4=0
P 6.01843996 2.815 22 P 0 8 0;0,2=26,4=0
P 6.01843996 2.615 22 P 0 8 0;0,2=26,4=0
P 4.985 3.504 36 P 0 8 0;0,2=1,4=0
P 6.01843996 2.915 22 P 0 8 0;0,2=26,4=0
P 4.885 3.504 36 P 0 8 0;0,2=1,4=0
P 6.01843996 2.715 22 P 0 8 0;0,2=26,4=0
P 0.53 2.091 36 P 0 8 0;0,2=1,4=0
P 4.60028002 1.68595 3 P 0 8 0;0,2=3,4=0
P 0.48 2.091 36 P 0 8 0;0,2=1,4=0
P 4.67901998 2.07965 3 P 0 8 0;0,2=3,4=0
P 4.56091004 1.68595 3 P 0 8 0;0,2=3,4=0
P 0.53 2.626 36 P 0 8 0;0,2=1,4=0
P 4.67901998 2.11901998 3 P 0 8 0;0,2=3,4=0
P 0.478 2.611 36 P 0 8 0;0,2=1,4=0
P 4.60028002 1.76468996 3 P 0 8 0;0,2=3,4=0
P 0.535 0.926 36 P 0 8 0;0,2=1,4=0
P 0.485 0.926 36 P 0 8 0;0,2=1,4=0
P 4.63965 1.76468996 3 P 0 8 0;0,2=3,4=0
P 0.53 1.486 36 P 0 8 0;0,2=1,4=0
P 4.60028002 1.72531998 3 P 0 8 0;0,2=3,4=0
P 4.63965 1.72531998 3 P 0 8 0;0,2=3,4=0
P 0.48 1.486 36 P 0 8 0;0,2=1,4=0
P 0.9575 0.6536 59 P 0 8 0;0,2=4,4=0
P 1.1737 0.6586 39 P 0 8 0;0,2=1,4=0
P 6.02558996 4.27558002 6 P 0 8 0;0,2=25,4=0
P 4.16721004 1.84343002 3 P 0 8 0;0,2=3,4=0
P 0.58 0.884 36 P 0 8 0;0,2=1,4=0
P 0.57676004 0.77913996 14 P 0 8 0;0,2=31,4=0
P 4.20658002 1.84343002 3 P 0 8 0;0,2=3,4=0
P 0.55708002 0.64606004 14 P 0 8 0;0,2=31,4=0
P 4.0489 3.95263002 60 P 0 8 0;0,2=0,4=0
P 0.78746998 1.885 39 P 0 8 0;0,2=1,4=0
P 4.0489 3.97231004 60 P 0 8 0;0,2=0,4=0
P 0.78746998 1.93 39 P 0 8 0;0,2=1,4=0
P 4.0474 3.93293996 57 P 0 8 0;0,2=2,4=0
P 0.78746998 1.75 39 P 0 8 0;0,2=1,4=0
P 0.58 1.444 36 P 0 8 0;0,2=1,4=0
P 0.57676004 1.35 14 P 0 8 0;0,2=31,4=0
P 4.20658002 1.8828 3 P 0 8 0;0,2=3,4=0
P 0.55708002 1.21691998 14 P 0 8 0;0,2=31,4=0
P 0.505 1.1259 36 P 0 8 0;0,2=1,4=0
P 4.16721004 1.8828 3 P 0 8 0;0,2=3,4=0
P 4.0489 4.03136998 60 P 0 8 0;0,2=0,4=0
P 0.332 2.66408002 36 P 0 8 0;0,2=1,4=0
P 4.0474 4.05106004 57 P 0 8 0;0,2=2,4=0
P 0.377 2.66408002 36 P 0 8 0;0,2=1,4=0
P 4.0489 4.01168996 60 P 0 8 0;0,2=0,4=0
P 0.197 2.66408002 36 P 0 8 0;0,2=1,4=0
P 0.57676004 1.92086998 14 P 0 8 0;0,2=31,4=0
P 0.575 2.049 36 P 0 8 0;0,2=1,4=0
P 4.32468996 1.80406004 3 P 0 8 0;0,2=3,4=0
P 4.28531998 1.80406004 3 P 0 8 0;0,2=3,4=0
P 0.556 1.65 39 P 0 8 0;0,2=1,4=0
P 0.55708002 1.78778996 14 P 0 8 0;0,2=31,4=0
P 4.10463002 4.0871 18 P 0 8 0;0,2=33,4=0
P 0.821 1.2 39 P 0 8 0;0,2=1,4=0
P 4.12431004 4.0871 18 P 0 8 0;0,2=33,4=0
P 0.821 1.3 39 P 0 8 0;0,2=1,4=0
P 4.08493996 4.0886 17 P 0 8 0;0,2=34,4=0
P 0.821 1.05 39 P 0 8 0;0,2=1,4=0
P 4.24595 1.80406004 3 P 0 8 0;0,2=3,4=0
P 0.57676004 2.49173996 14 P 0 8 0;0,2=31,4=0
P 0.578 2.569 36 P 0 8 0;0,2=1,4=0
P 0.51451998 2.275 36 P 0 8 0;0,2=1,4=0
P 0.55708002 2.35866004 14 P 0 8 0;0,2=31,4=0
P 4.24595 1.84343002 3 P 0 8 0;0,2=3,4=0
P 4.18336998 4.0871 18 P 0 8 0;0,2=33,4=0
P 0.326 1.52698002 36 P 0 8 0;0,2=1,4=0
P 4.20306004 4.0886 17 P 0 8 0;0,2=34,4=0
P 0.416 1.52698002 36 P 0 8 0;0,2=1,4=0
P 4.16368996 4.0871 18 P 0 8 0;0,2=33,4=0
P 0.191 1.52698002 36 P 0 8 0;0,2=1,4=0
P 4.10463002 3.8969 18 P 0 8 0;0,2=33,4=0
P 0.33 3.189 36 P 0 8 0;0,2=1,4=0
P 4.08493996 3.8954 17 P 0 8 0;0,2=34,4=0
P 0.43 3.189 36 P 0 8 0;0,2=1,4=0
P 4.12431004 3.8969 18 P 0 8 0;0,2=33,4=0
P 0.18 3.189 36 P 0 8 0;0,2=1,4=0
P 0.89848002 2.632 40 P 0 8 0;0,2=12,4=0
P 0.76948002 2.525 36 P 0 8 0;0,2=1,4=0
P 0.64248002 2.614 39 P 0 8 0;0,2=1,4=0
P 0.80648002 2.789 36 P 0 8 0;0,2=1,4=0
P 0.81998996 2.68068996 24 P 0 8 0;0,2=35,4=0
P 0.909 2.728 39 P 0 8 0;0,2=1,4=0
P 0.90848002 2.683 39 P 0 8 0;0,2=1,4=0
P 0.68448002 2.709 39 P 0 8 0;0,2=1,4=0
P 0.7826 2.2465 29 P 0 8 0;0,2=30,4=0
P 0.714 2.294 36 P 0 8 0;0,2=1,4=0
P 3.435 2.511 36 P 0 8 0;0,2=1,4=0
P 3.491 2.509 43 P 0 8 0;0,2=12,4=0
P 3.38483996 2.511 36 P 0 8 0;0,2=1,4=0
P 3.45151998 2.3829 38 P 0 8 0;0,2=36,4=0
P 3.39983996 2.40503996 9 P 0 8 0;0,2=37,4=0
P 3.45151998 2.34353002 38 P 0 8 0;0,2=36,4=0
P 3.57 2.33243002 64 P 0 8 0;0,2=38,4=0
P 3.63673002 2.34643002 26 P 0 8 0;0,2=9,4=0
P 3.285 2.511 36 P 0 8 0;0,2=1,4=0
P 3.36046998 2.40503996 9 P 0 8 0;0,2=37,4=0
P 3.201 2.569 39 P 0 8 0;0,2=1,4=0
P 3.32848002 2.40258002 38 P 0 8 0;0,2=36,4=0
P 3.39983996 2.22296004 9 P 0 8 0;0,2=37,4=0
P 3.32848002 2.32383996 38 P 0 8 0;0,2=36,4=0
P 3.201 2.479 39 P 0 8 0;0,2=1,4=0
P 3.201 2.434 39 P 0 8 0;0,2=1,4=0
P 3.201 2.524 39 P 0 8 0;0,2=1,4=0
P 3.32848002 2.34353002 38 P 0 8 0;0,2=36,4=0
P 0.835 2.566 36 P 0 8 0;0,2=1,4=0
P 0.79931998 2.63048996 11 P 0 8 0;0,2=39,4=0
P 0.76948002 2.567 36 P 0 8 0;0,2=1,4=0
P 0.77963996 2.63048996 11 P 0 8 0;0,2=39,4=0
P 0.68448002 2.614 39 P 0 8 0;0,2=1,4=0
P 0.75896998 2.64131004 24 P 0 8 0;0,2=35,4=0
P 0.661 2.79 39 P 0 8 0;0,2=1,4=0
P 0.75896998 2.68068996 24 P 0 8 0;0,2=35,4=0
P 0.79931998 2.69151004 11 P 0 8 0;0,2=39,4=0
P 6.01953002 2.14381998 15 P 0 8 0;0,2=15,4=0
P 6.033 2.324 40 P 0 8 0;0,2=12,4=0
P 6.029 2.27 39 P 0 8 0;0,2=1,4=0
P 6.029 2.225 39 P 0 8 0;0,2=1,4=0
P 4.41975 2.92521004 41 P 0 8 0;0,2=40,4=0
P 4.524 2.995 39 P 0 8 0;0,2=1,4=0
P 6.1437 4.27558002 6 P 0 8 0;0,2=25,4=0
P 0.804 2.15103996 48 P 0 8 0;0,2=41,4=0
P 5.99983996 2.14381998 15 P 0 8 0;0,2=15,4=0
P 5.94153002 2.33 39 P 0 8 0;0,2=1,4=0
P 5.94153002 2.28401998 39 P 0 8 0;0,2=1,4=0
P 5.94153002 2.239 39 P 0 8 0;0,2=1,4=0
P 5.99983996 2.04418002 15 P 0 8 0;0,2=15,4=0
P 6.01901998 1.95065 36 P 0 8 0;0,2=1,4=0
P 3.45151998 2.22541998 38 P 0 8 0;0,2=36,4=0
P 3.41953002 2.22296004 9 P 0 8 0;0,2=37,4=0
P 4.32468996 1.92216998 3 P 0 8 0;0,2=3,4=0
P 3.554 1.74548996 36 P 0 8 0;0,2=1,4=0
P 4.40343002 1.52846998 3 P 0 8 0;0,2=3,4=0
P 4.60028002 1.64658002 3 P 0 8 0;0,2=3,4=0
P 4.36406004 1.4891 3 P 0 8 0;0,2=3,4=0
P 4.32468996 1.52846998 3 P 0 8 0;0,2=3,4=0
P 4.63965 1.60721004 3 P 0 8 0;0,2=3,4=0
P 4.32468996 1.4891 3 P 0 8 0;0,2=3,4=0
P 4.40343002 1.37098002 3 P 0 8 0;0,2=3,4=0
P 4.36406004 1.37098002 3 P 0 8 0;0,2=3,4=0
P 4.71838996 1.60721004 3 P 0 8 0;0,2=3,4=0
P 4.40343002 1.4891 3 P 0 8 0;0,2=3,4=0
P 4.56091004 1.64658002 3 P 0 8 0;0,2=3,4=0
P 4.40343002 1.44973002 3 P 0 8 0;0,2=3,4=0
P 4.4428 1.33161004 3 P 0 8 0;0,2=3,4=0
P 4.40343002 1.33161004 3 P 0 8 0;0,2=3,4=0
P 6.02558996 4.21653996 6 P 0 8 0;0,2=25,4=0
P 3.89161004 1.80406004 3 P 0 8 0;0,2=3,4=0
P 6.1437 4.21653996 6 P 0 8 0;0,2=25,4=0
P 3.89161004 1.84343002 3 P 0 8 0;0,2=3,4=0
P 4.16721004 2.04028002 3 P 0 8 0;0,2=3,4=0
P 5.89953002 2.33 39 P 0 8 0;0,2=1,4=0
P 4.52153996 1.92216998 3 P 0 8 0;0,2=3,4=0
P 4.24595 1.92216998 3 P 0 8 0;0,2=3,4=0
P 1.9977 0.632 36 P 0 8 0;0,2=1,4=0
P 3.159 2.299 39 P 0 8 0;0,2=1,4=0
P 4.20658002 1.96153996 3 P 0 8 0;0,2=3,4=0
P 4.28531998 1.8828 3 P 0 8 0;0,2=3,4=0
P 6.01901998 1.90865 36 P 0 8 0;0,2=1,4=0
P 4.20658002 2.04028002 3 P 0 8 0;0,2=3,4=0
P 4.32468996 1.8828 3 P 0 8 0;0,2=3,4=0
P 4.884 1.675 39 P 0 8 0;0,2=1,4=0
P 4.884 1.63 39 P 0 8 0;0,2=1,4=0
P 4.67901998 1.64658002 3 P 0 8 0;0,2=3,4=0
P 3.166 1.695 39 P 0 8 0;0,2=1,4=0
P 3.166 1.645 39 P 0 8 0;0,2=1,4=0
P 4.71838996 1.68595 3 P 0 8 0;0,2=3,4=0
P 4.56091004 1.80406004 3 P 0 8 0;0,2=3,4=0
P 4.63965 1.84343002 3 P 0 8 0;0,2=3,4=0
P 4.835 3.504 36 P 0 8 0;0,2=1,4=0
P 4.60028002 1.84343002 3 P 0 8 0;0,2=3,4=0
P 3.159 2.209 39 P 0 8 0;0,2=1,4=0
P 3.159 2.254 39 P 0 8 0;0,2=1,4=0
P 4.28531998 1.84343002 3 P 0 8 0;0,2=3,4=0
P 1.425 3.851 39 P 0 8 0;0,2=1,4=0
P 6.01843996 3.015 22 P 0 8 0;0,2=26,4=0
P 4.52153996 1.76468996 3 P 0 8 0;0,2=3,4=0
P 4.566 2.995 39 P 0 8 0;0,2=1,4=0
P 3.58206998 1.92336004 45 P 0 8 0;0,2=42,4=0
P 6.30728996 2.20183996 32 P 0 8 0;0,2=4,4=0
P 6.4105 2.11023996 62 P 0 8 0;0,2=43,4=0
P 6.23248996 2.20183996 32 P 0 8 0;0,2=4,4=0
P 6.4105 2.08465 62 P 0 8 0;0,2=43,4=0
P 3.58206998 1.93911004 45 P 0 8 0;0,2=42,4=0
P 3.201 2.164 39 P 0 8 0;0,2=1,4=0
P 3.296 2.165 39 P 0 8 0;0,2=1,4=0
P 3.38016004 2.22296004 9 P 0 8 0;0,2=37,4=0
P 3.36046998 2.22296004 9 P 0 8 0;0,2=37,4=0
P 3.32848002 2.22541998 38 P 0 8 0;0,2=36,4=0
P 4.41975 2.90553002 41 P 0 8 0;0,2=40,4=0
P 4.524 2.945 39 P 0 8 0;0,2=1,4=0
P 4.41975 2.84646998 41 P 0 8 0;0,2=40,4=0
P 4.524 2.845 39 P 0 8 0;0,2=1,4=0
P 5.956 1.125 39 P 0 8 0;0,2=1,4=0
P 1.959 3.289 36 P 0 8 0;0,2=1,4=0
P 3.98 3.4056 28 P 0 8 0;0,2=6,4=0
P 4.175 3.4076 28 P 0 8 0;0,2=6,4=0
P 3.481 3.235 73 P 0 8 0;0,2=27,4=0
P 3.582 2.856 36 P 0 8 0;0,2=1,4=0
P 3.582 2.803 36 P 0 8 0;0,2=1,4=0
P 3.689 2.71 39 P 0 8 0;0,2=1,4=0
P 3.546 2.555 36 P 0 8 0;0,2=1,4=0
P 3.491 2.563 43 P 0 8 0;0,2=12,4=0
P 3.335 2.553 36 P 0 8 0;0,2=1,4=0
P 3.201 2.209 39 P 0 8 0;0,2=1,4=0
P 3.254 2.165 39 P 0 8 0;0,2=1,4=0
P 4.926 2.115 39 P 0 8 0;0,2=1,4=0
P 3.50595 1.89186998 45 P 0 8 0;0,2=42,4=0
P 4.63965 1.68595 3 P 0 8 0;0,2=3,4=0
P 3.76 2.384 36 P 0 8 0;0,2=1,4=0
P 4.00973002 2.00091004 3 P 0 8 0;0,2=3,4=0
P 4.32468996 1.84343002 3 P 0 8 0;0,2=3,4=0
P 4.0491 1.8828 3 P 0 8 0;0,2=3,4=0
P 3.89161004 1.96153996 3 P 0 8 0;0,2=3,4=0
P 3.93098002 1.84343002 3 P 0 8 0;0,2=3,4=0
P 4.08846998 1.76468996 3 P 0 8 0;0,2=3,4=0
P 4.20658002 1.80406004 3 P 0 8 0;0,2=3,4=0
P 4.29225 2.82678996 41 P 0 8 0;0,2=40,4=0
P 4.29225 2.84646998 41 P 0 8 0;0,2=40,4=0
P 4.29225 2.86616004 41 P 0 8 0;0,2=40,4=0
P 4.29225 2.88583996 41 P 0 8 0;0,2=40,4=0
P 4.29225 2.90553002 41 P 0 8 0;0,2=40,4=0
P 4.29225 2.92521004 41 P 0 8 0;0,2=40,4=0
P 4.575 2.461 36 P 0 8 0;0,2=1,4=0
P 4.209 2.552 36 P 0 8 0;0,2=1,4=0
P 4.15 2.552 36 P 0 8 0;0,2=1,4=0
P 4.093 2.552 36 P 0 8 0;0,2=1,4=0
P 4.037 2.552 36 P 0 8 0;0,2=1,4=0
P 3.978 2.552 36 P 0 8 0;0,2=1,4=0
P 3.919 2.552 36 P 0 8 0;0,2=1,4=0
P 3.801 2.552 36 P 0 8 0;0,2=1,4=0
P 3.86 2.552 36 P 0 8 0;0,2=1,4=0
P 4.187 2.792 39 P 0 8 0;0,2=1,4=0
P 4.2 2.855 47 P 0 8 0;0,2=14,4=0
P 4.2 2.936 47 P 0 8 0;0,2=14,4=0
P 4.395 2.461 36 P 0 8 0;0,2=1,4=0
P 4.74 2.4365 7 P 0 8 0;0,2=44,4=0
P 4.48216998 1.76468996 3 P 0 8 0;0,2=3,4=0
P 4.60028002 1.80406004 3 P 0 8 0;0,2=3,4=0
P 4.16721004 1.92216998 3 P 0 8 0;0,2=3,4=0
P 4.28531998 1.96153996 3 P 0 8 0;0,2=3,4=0
P 4.40343002 2.00091004 3 P 0 8 0;0,2=3,4=0
P 4.4428 1.8828 3 P 0 8 0;0,2=3,4=0
P 4.56091004 1.92216998 3 P 0 8 0;0,2=3,4=0
P 4.71838996 1.84343002 3 P 0 8 0;0,2=3,4=0
P 4.67901998 1.96153996 3 P 0 8 0;0,2=3,4=0
P 3.97035 2.11901998 3 P 0 8 0;0,2=3,4=0
P 4.08846998 2.15838996 3 P 0 8 0;0,2=3,4=0
P 4.12783996 2.04028002 3 P 0 8 0;0,2=3,4=0
P 4.24595 2.07965 3 P 0 8 0;0,2=3,4=0
P 4.36406004 2.11901998 3 P 0 8 0;0,2=3,4=0
P 4.48216998 2.15838996 3 P 0 8 0;0,2=3,4=0
P 4.52153996 2.04028002 3 P 0 8 0;0,2=3,4=0
P 4.63965 2.07965 3 P 0 8 0;0,2=3,4=0
P 3.695 2.5135 32 P 0 8 0;0,2=4,4=0
P 3.7324 2.5135 32 P 0 8 0;0,2=4,4=0
P 5.001 1.335 39 P 0 8 0;0,2=1,4=0
P 5.001 1.385 39 P 0 8 0;0,2=1,4=0
P 4.926 1.765 39 P 0 8 0;0,2=1,4=0
P 4.384 3.79 39 P 0 8 0;0,2=1,4=0
P 4.2745 3.76456998 68 P 0 8 0;0,2=5,4=0
P 4.935 3.504 36 P 0 8 0;0,2=1,4=0
P 6.2655 1.0834 67 P 0 8 0;0,2=30,4=0
P 6.379 1.135 39 P 0 8 0;0,2=1,4=0
P 5.9945 1.27063002 76 P 0 8 0;0,2=23,4=0
P 6.421 0.965 39 P 0 8 0;0,2=1,4=0
P 6.421 1.02 39 P 0 8 0;0,2=1,4=0
P 6.421 1.08 39 P 0 8 0;0,2=1,4=0
P 6.087 2.324 40 P 0 8 0;0,2=12,4=0
P 6.141 2.32 36 P 0 8 0;0,2=1,4=0
P 5.89953002 2.239 39 P 0 8 0;0,2=1,4=0
P 5.96901998 1.90865 36 P 0 8 0;0,2=1,4=0
P 4.2391 3.97231004 60 P 0 8 0;0,2=0,4=0
P 4.396 3.865 39 P 0 8 0;0,2=1,4=0
P 4.354 3.965 39 P 0 8 0;0,2=1,4=0
P 4.53 3.849 36 P 0 8 0;0,2=1,4=0
P 4.598 3.86 40 P 0 8 0;0,2=12,4=0
P 4.4085 3.24556998 68 P 0 8 0;0,2=5,4=0
P 4.509 3.27 39 P 0 8 0;0,2=1,4=0
P 4.426 3.7 39 P 0 8 0;0,2=1,4=0
P 6.14648002 1.27063002 79 P 0 8 0;0,2=24,4=0
P 4.694 0.865 39 P 0 8 0;0,2=1,4=0
P 4.694 0.785 39 P 0 8 0;0,2=1,4=0
P 5.1245 0.91956998 68 P 0 8 0;0,2=5,4=0
P 5.249 0.92 39 P 0 8 0;0,2=1,4=0
P 5.291 0.82 39 P 0 8 0;0,2=1,4=0
P 5.291 0.76 39 P 0 8 0;0,2=1,4=0
P 2.848 0.63058996 46 P 0 8 0;0,2=45,4=0
P 2.955 0.621 39 P 0 8 0;0,2=1,4=0
P 2.9552 0.6678 39 P 0 8 0;0,2=1,4=0
P 2.0477 0.632 36 P 0 8 0;0,2=1,4=0
P 3.124 1.645 39 P 0 8 0;0,2=1,4=0
P 1.455 3.192 43 P 0 8 0;0,2=12,4=0
P 2.218 2.973 36 P 0 8 0;0,2=1,4=0
P 3.159 2.434 39 P 0 8 0;0,2=1,4=0
P 3.159 2.389 39 P 0 8 0;0,2=1,4=0
P 2.173 2.931 36 P 0 8 0;0,2=1,4=0
P 2.083 2.931 36 P 0 8 0;0,2=1,4=0
P 2.128 2.931 36 P 0 8 0;0,2=1,4=0
P 2.1734 3.0845 29 P 0 8 0;0,2=30,4=0
P 0.08251998 3.23523996 30 P 0 8 0;0,2=29,4=0
P 0.578 2.611 36 P 0 8 0;0,2=1,4=0
P 0.57676004 2.35866004 14 P 0 8 0;0,2=31,4=0
P 0.64 2.271 36 P 0 8 0;0,2=1,4=0
P 0.08251998 2.66436998 30 P 0 8 0;0,2=29,4=0
P 0.51451998 2.233 36 P 0 8 0;0,2=1,4=0
P 0.575 2.091 36 P 0 8 0;0,2=1,4=0
P 0.08251998 2.09351004 30 P 0 8 0;0,2=29,4=0
P 0.57676004 1.78778996 14 P 0 8 0;0,2=31,4=0
P 0.606 1.68945 36 P 0 8 0;0,2=1,4=0
P 0.514 1.65 39 P 0 8 0;0,2=1,4=0
P 0.58 1.486 36 P 0 8 0;0,2=1,4=0
P 0.08251998 1.52263996 30 P 0 8 0;0,2=29,4=0
P 0.57676004 1.21691998 14 P 0 8 0;0,2=31,4=0
P 0.625 1.126 36 P 0 8 0;0,2=1,4=0
P 0.58 0.926 36 P 0 8 0;0,2=1,4=0
P 0.505 1.0839 36 P 0 8 0;0,2=1,4=0
P 0.08251998 0.95176998 30 P 0 8 0;0,2=29,4=0
P 0.81338996 0.7085 25 P 0 8 0;0,2=20,4=0
P 1.2157 0.7536 39 P 0 8 0;0,2=1,4=0
P 1.2157 0.7086 39 P 0 8 0;0,2=1,4=0
P 1.0705 0.6536 59 P 0 8 0;0,2=4,4=0
P 1.1737 0.6136 39 P 0 8 0;0,2=1,4=0
P 0.57676004 0.64606004 14 P 0 8 0;0,2=31,4=0
P 1.548 0.6212 36 P 0 8 0;0,2=1,4=0
P 1.6622 0.59 71 P 0 8 0;0,2=46,4=0
P 5.914 0.965 39 P 0 8 0;0,2=1,4=0
P 5.914 1.025 39 P 0 8 0;0,2=1,4=0
P 4.67901998 1.56783996 3 P 0 8 0;0,2=3,4=0
P 4.56091004 1.52846998 3 P 0 8 0;0,2=3,4=0
P 4.16721004 1.52846998 3 P 0 8 0;0,2=3,4=0
P 4.71838996 1.44973002 3 P 0 8 0;0,2=3,4=0
P 4.60028002 1.41035 3 P 0 8 0;0,2=3,4=0
P 4.48216998 1.37098002 3 P 0 8 0;0,2=3,4=0
P 4.4428 1.4891 3 P 0 8 0;0,2=3,4=0
P 4.36406004 1.33161004 3 P 0 8 0;0,2=3,4=0
P 4.32468996 1.44973002 3 P 0 8 0;0,2=3,4=0
P 4.20658002 1.41035 3 P 0 8 0;0,2=3,4=0
P 4.08846998 1.37098002 3 P 0 8 0;0,2=3,4=0
P 3.97035 1.33161004 3 P 0 8 0;0,2=3,4=0
P 4.999 1.264 47 P 0 8 0;0,2=14,4=0
P 4.53 1.139 36 P 0 8 0;0,2=1,4=0
P 4.585 1.139 36 P 0 8 0;0,2=1,4=0
P 3.732 1.06 47 P 0 8 0;0,2=14,4=0
P 5.404 0.69 39 P 0 8 0;0,2=1,4=0
P 5.56533002 0.69868996 51 P 0 8 0;0,2=15,4=0
P 5.527 0.792 39 P 0 8 0;0,2=1,4=0
P 5.484 0.863 47 P 0 8 0;0,2=14,4=0
P 5.56533002 0.72288002 86 P 0 8 0;0,2=16,4=0
P 5.04833002 2.68731004 51 P 0 8 0;0,2=15,4=0
P 5.04833002 2.66311998 83 P 0 8 0;0,2=21,4=0
P 4.96 2.594 36 P 0 8 0;0,2=1,4=0
P 4.933 2.52 43 P 0 8 0;0,2=12,4=0
P 5.014 2.534 47 P 0 8 0;0,2=14,4=0
P 5.042 2.597 39 P 0 8 0;0,2=1,4=0
P 5.04833002 2.75088002 86 P 0 8 0;0,2=16,4=0
P 4.97343002 2.777 12 P 0 8 0;0,2=9,4=0
P 5.16766998 2.72668996 51 P 0 8 0;0,2=15,4=0
P 5.26956998 2.725 12 P 0 8 0;0,2=9,4=0
P 5.315 2.769 36 P 0 8 0;0,2=1,4=0
P 5.27 2.769 36 P 0 8 0;0,2=1,4=0
P 3.682 2.205 40 P 0 8 0;0,2=12,4=0
P 4.40343002 1.76468996 3 P 0 8 0;0,2=3,4=0
P 4.4428 1.72531998 3 P 0 8 0;0,2=3,4=0
P 4.32468996 1.76468996 3 P 0 8 0;0,2=3,4=0
P 4.24595 1.76468996 3 P 0 8 0;0,2=3,4=0
P 4.24595 1.68595 3 P 0 8 0;0,2=3,4=0
P 4.16721004 1.76468996 3 P 0 8 0;0,2=3,4=0
P 4.0491 1.76468996 3 P 0 8 0;0,2=3,4=0
P 5.315 2.811 36 P 0 8 0;0,2=1,4=0
P 0.95248002 2.632 40 P 0 8 0;0,2=12,4=0
P 0.949 2.58048002 39 P 0 8 0;0,2=1,4=0
P 3.628 2.205 40 P 0 8 0;0,2=12,4=0
P 5.16766998 2.68731004 51 P 0 8 0;0,2=15,4=0
P 5.16766998 2.66311998 87 P 0 8 0;0,2=16,4=0
P 5.278 2.611 36 P 0 8 0;0,2=1,4=0
P 5.204 2.592 39 P 0 8 0;0,2=1,4=0
P 5.228 2.521 47 P 0 8 0;0,2=14,4=0
P 5.16766998 2.707 51 P 0 8 0;0,2=15,4=0
P 5.278 2.653 36 P 0 8 0;0,2=1,4=0
P 5.328 2.653 36 P 0 8 0;0,2=1,4=0
P 5.04833002 2.72668996 51 P 0 8 0;0,2=15,4=0
P 4.889 2.686 36 P 0 8 0;0,2=1,4=0
P 4.961 2.686 36 P 0 8 0;0,2=1,4=0
P 4.96 2.636 36 P 0 8 0;0,2=1,4=0
P 3.708 3.099 40 P 0 8 0;0,2=12,4=0
P 3.797 3.011 36 P 0 8 0;0,2=1,4=0
P 3.732 3.018 63 P 0 8 0;0,2=14,4=0
P 3.89231004 3.00466998 15 P 0 8 0;0,2=15,4=0
P 3.86811998 3.00466998 84 P 0 8 0;0,2=21,4=0
P 3.95588002 3.00466998 88 P 0 8 0;0,2=16,4=0
P 3.982 3.07956998 26 P 0 8 0;0,2=9,4=0
P 3.926 2.68 39 P 0 8 0;0,2=1,4=0
P 3.93168996 2.88533002 15 P 0 8 0;0,2=15,4=0
P 3.94156998 2.774 12 P 0 8 0;0,2=9,4=0
P 3.926 2.725 39 P 0 8 0;0,2=1,4=0
P 3.968 2.725 39 P 0 8 0;0,2=1,4=0
P 4.889 2.728 36 P 0 8 0;0,2=1,4=0
P 3.816 2.775 39 P 0 8 0;0,2=1,4=0
P 3.89231004 2.88533002 15 P 0 8 0;0,2=15,4=0
P 3.797 2.849 36 P 0 8 0;0,2=1,4=0
P 3.86811998 2.88533002 89 P 0 8 0;0,2=16,4=0
P 3.729 2.804 63 P 0 8 0;0,2=14,4=0
P 3.858 2.68 39 P 0 8 0;0,2=1,4=0
P 3.912 2.88533002 15 P 0 8 0;0,2=15,4=0
P 3.858 2.775 39 P 0 8 0;0,2=1,4=0
P 3.858 2.725 39 P 0 8 0;0,2=1,4=0
P 3.835 3.092 39 P 0 8 0;0,2=1,4=0
P 3.93168996 3.00466998 15 P 0 8 0;0,2=15,4=0
P 3.891 3.092 39 P 0 8 0;0,2=1,4=0
P 5.597 1.94528996 20 P 0 8 0;0,2=47,4=0
P 5.5622 2.13138002 77 P 0 8 0;0,2=48,4=0
P 5.5878 2.13138002 77 P 0 8 0;0,2=48,4=0
P 5.56516004 2.21996004 10 P 0 8 0;0,2=49,4=0
P 5.6 2.324 36 P 0 8 0;0,2=1,4=0
P 5.62913002 2.21996004 31 P 0 8 0;0,2=50,4=0
P 5.729 2.245 39 P 0 8 0;0,2=1,4=0
P 5.52086998 2.21996004 31 P 0 8 0;0,2=50,4=0
P 5.51 2.32956998 26 P 0 8 0;0,2=9,4=0
P 5.465 2.324 36 P 0 8 0;0,2=1,4=0
P 4.48216998 1.68595 3 P 0 8 0;0,2=3,4=0
P 4.40343002 1.68595 3 P 0 8 0;0,2=3,4=0
P 4.36406004 1.72531998 3 P 0 8 0;0,2=3,4=0
P 4.28531998 1.72531998 3 P 0 8 0;0,2=3,4=0
P 4.16721004 1.68595 3 P 0 8 0;0,2=3,4=0
P 4.20658002 1.72531998 3 P 0 8 0;0,2=3,4=0
P 4.48216998 1.60721004 3 P 0 8 0;0,2=3,4=0
P 4.4428 1.64658002 3 P 0 8 0;0,2=3,4=0
P 4.4428 1.56783996 3 P 0 8 0;0,2=3,4=0
P 4.36406004 1.56783996 3 P 0 8 0;0,2=3,4=0
P 4.40343002 1.60721004 3 P 0 8 0;0,2=3,4=0
P 4.32468996 1.60721004 3 P 0 8 0;0,2=3,4=0
P 4.28531998 1.56783996 3 P 0 8 0;0,2=3,4=0
P 4.24595 1.60721004 3 P 0 8 0;0,2=3,4=0
P 4.16721004 1.60721004 3 P 0 8 0;0,2=3,4=0
P 4.20658002 1.64658002 3 P 0 8 0;0,2=3,4=0
P 4.20658002 1.56783996 3 P 0 8 0;0,2=3,4=0
P 5.183 1.725 40 P 0 8 0;0,2=12,4=0
P 5.1925 1.345 54 P 0 8 0;0,2=44,4=0
P 5.207 1.24 47 P 0 8 0;0,2=14,4=0
P 5.1925 1.47 54 P 0 8 0;0,2=44,4=0
P 5.1925 1.595 54 P 0 8 0;0,2=44,4=0
P 5.465 2.366 36 P 0 8 0;0,2=1,4=0
P 3.793 3.092 39 P 0 8 0;0,2=1,4=0
P 4.00973002 1.68595 3 P 0 8 0;0,2=3,4=0
P 4.08846998 1.56783996 3 P 0 8 0;0,2=3,4=0
P 4.08846998 1.64658002 3 P 0 8 0;0,2=3,4=0
P 4.0491 1.60721004 3 P 0 8 0;0,2=3,4=0
P 4.00973002 1.52846998 3 P 0 8 0;0,2=3,4=0
P 3.672 1.47 40 P 0 8 0;0,2=12,4=0
P 3.705 1.582 63 P 0 8 0;0,2=14,4=0
P 3.618 1.47 40 P 0 8 0;0,2=12,4=0
P 3.575 1.579 36 P 0 8 0;0,2=1,4=0
P 3.515 1.582 63 P 0 8 0;0,2=14,4=0
P 5.237 1.725 40 P 0 8 0;0,2=12,4=0
P 5.597 1.73071998 20 P 0 8 0;0,2=47,4=0
P 5.41 1.794 36 P 0 8 0;0,2=1,4=0
P 5.657 1.61 47 P 0 8 0;0,2=14,4=0
P 5.39 1.663 63 P 0 8 0;0,2=14,4=0
P 5.35 1.787 63 P 0 8 0;0,2=14,4=0
P 5.654 2.4 39 P 0 8 0;0,2=1,4=0
P 5.60453002 2.21996004 10 P 0 8 0;0,2=49,4=0
P 5.695 2.33456998 26 P 0 8 0;0,2=9,4=0
P 5.754 2.324 36 P 0 8 0;0,2=1,4=0
P 5.58483996 2.21996004 10 P 0 8 0;0,2=49,4=0
P 5.64 2.32956998 26 P 0 8 0;0,2=9,4=0
P 5.51003996 2.1924 34 P 0 8 0;0,2=51,4=0
P 5.63996004 2.1924 34 P 0 8 0;0,2=51,4=0
P 5.771 2.245 39 P 0 8 0;0,2=1,4=0
P 5.6 2.366 36 P 0 8 0;0,2=1,4=0
P 5.64 2.35043002 26 P 0 8 0;0,2=9,4=0
P 5.55568996 3.83456004 21 P 0 8 0;0,2=52,4=0
P 5.559 3.96 39 P 0 8 0;0,2=1,4=0
P 5.559 3.915 39 P 0 8 0;0,2=1,4=0
P 5.395 2.229 43 P 0 8 0;0,2=12,4=0
P 5.76 2.153 63 P 0 8 0;0,2=14,4=0
P 5.62913002 2.16878002 56 P 0 8 0;0,2=53,4=0
P 5.7 2.151 36 P 0 8 0;0,2=1,4=0
P 5.385 2.123 63 P 0 8 0;0,2=14,4=0
P 5.52086998 2.16878002 56 P 0 8 0;0,2=53,4=0
P 5.45 2.131 36 P 0 8 0;0,2=1,4=0
P 5.555 2.324 36 P 0 8 0;0,2=1,4=0
P 5.54546998 2.21996004 10 P 0 8 0;0,2=49,4=0
P 5.696 2.4 39 P 0 8 0;0,2=1,4=0
P 5.754 2.366 36 P 0 8 0;0,2=1,4=0
P 5.695 2.35543002 26 P 0 8 0;0,2=9,4=0
P 3.869 0.97 39 P 0 8 0;0,2=1,4=0
P 3.811 0.97 39 P 0 8 0;0,2=1,4=0
P 3.77 0.916 36 P 0 8 0;0,2=1,4=0
P 3.88 0.89783002 65 P 0 8 0;0,2=8,4=0
P 4.205 0.921 36 P 0 8 0;0,2=1,4=0
P 4.314 0.90633996 37 P 0 8 0;0,2=7,4=0
P 5.446 0.69 39 P 0 8 0;0,2=1,4=0
P 5.56533002 0.679 51 P 0 8 0;0,2=15,4=0
P 5.46043002 0.635 12 P 0 8 0;0,2=9,4=0
P 5.56533002 0.65931004 51 P 0 8 0;0,2=15,4=0
P 5.68466998 0.63511998 87 P 0 8 0;0,2=16,4=0
P 5.75956998 0.609 12 P 0 8 0;0,2=9,4=0
P 5.775 0.796 36 P 0 8 0;0,2=1,4=0
P 5.7 0.933 43 P 0 8 0;0,2=12,4=0
P 5.691 0.792 39 P 0 8 0;0,2=1,4=0
P 5.698 0.859 47 P 0 8 0;0,2=14,4=0
P 5.68466998 0.69868996 51 P 0 8 0;0,2=15,4=0
P 5.68466998 0.72288002 82 P 0 8 0;0,2=21,4=0
P 5.775 0.754 36 P 0 8 0;0,2=1,4=0
P 5.68466998 0.65931004 51 P 0 8 0;0,2=15,4=0
P 5.772 0.7 36 P 0 8 0;0,2=1,4=0
P 5.43503996 4.13778996 6 P 0 8 0;0,2=25,4=0
P 5.55315 4.13778996 6 P 0 8 0;0,2=25,4=0
P 5.78936998 4.13778996 6 P 0 8 0;0,2=25,4=0
P 5.67126004 4.13778996 6 P 0 8 0;0,2=25,4=0
P 5.283 4.20953002 6 P 0 8 0;0,2=25,4=0
P 3.769 3.335 73 P 0 8 0;0,2=27,4=0
P 3.481 3.285 73 P 0 8 0;0,2=27,4=0
P 3.769 3.285 73 P 0 8 0;0,2=27,4=0
P 3.481 3.385 73 P 0 8 0;0,2=27,4=0
P 4.71838996 2.00091004 3 P 0 8 0;0,2=3,4=0
P 4.884 1.975 39 P 0 8 0;0,2=1,4=0
P 4.884 2.025 39 P 0 8 0;0,2=1,4=0
P 4.67901998 2.00091004 3 P 0 8 0;0,2=3,4=0
P 4.36406004 1.8828 3 P 0 8 0;0,2=3,4=0
P 4.40343002 2.07965 3 P 0 8 0;0,2=3,4=0
P 3.52656998 4.121 12 P 0 8 0;0,2=9,4=0
P 3.41796004 4.06613002 35 P 0 8 0;0,2=50,4=0
P 2.937 3.259 39 P 0 8 0;0,2=1,4=0
P 3.0425 3.25101998 68 P 0 8 0;0,2=5,4=0
P 3.0425 3.27661004 68 P 0 8 0;0,2=5,4=0
P 2.938 3.332 39 P 0 8 0;0,2=1,4=0
P 4.52153996 1.80406004 3 P 0 8 0;0,2=3,4=0
P 4.52153996 2.15838996 3 P 0 8 0;0,2=3,4=0
P 1.6622 0.64 71 P 0 8 0;0,2=46,4=0
P 1.8832 0.64 71 P 0 8 0;0,2=46,4=0
P 4.08846998 1.68595 3 P 0 8 0;0,2=3,4=0
P 4.0491 1.68595 3 P 0 8 0;0,2=3,4=0
P 4.414 0.90633996 37 P 0 8 0;0,2=7,4=0
P 4.414 1.031 36 P 0 8 0;0,2=1,4=0
P 4.418 0.973 39 P 0 8 0;0,2=1,4=0
P 4.369 1.031 36 P 0 8 0;0,2=1,4=0
P 4.364 0.90633996 37 P 0 8 0;0,2=7,4=0
P 4.364 0.973 39 P 0 8 0;0,2=1,4=0
P 4.055 1.029 36 P 0 8 0;0,2=1,4=0
P 4.08 0.89783002 65 P 0 8 0;0,2=8,4=0
P 4.059 0.97 39 P 0 8 0;0,2=1,4=0
P 4.01 1.029 36 P 0 8 0;0,2=1,4=0
P 3.98 0.89783002 65 P 0 8 0;0,2=8,4=0
P 4.006 0.97 39 P 0 8 0;0,2=1,4=0
P 4.414 1.073 36 P 0 8 0;0,2=1,4=0
P 4.4165 1.123 39 P 0 8 0;0,2=1,4=0
P 4.4428 1.44973002 3 P 0 8 0;0,2=3,4=0
P 4.369 1.073 36 P 0 8 0;0,2=1,4=0
P 4.3665 1.123 39 P 0 8 0;0,2=1,4=0
P 4.48216998 1.44973002 3 P 0 8 0;0,2=3,4=0
P 4.055 1.071 36 P 0 8 0;0,2=1,4=0
P 4.08846998 1.52846998 3 P 0 8 0;0,2=3,4=0
P 4.01 1.071 36 P 0 8 0;0,2=1,4=0
P 4.0491 1.52846998 3 P 0 8 0;0,2=3,4=0
P 4.884 2.115 39 P 0 8 0;0,2=1,4=0
P 4.884 2.07 39 P 0 8 0;0,2=1,4=0
P 4.36406004 1.76468996 3 P 0 8 0;0,2=3,4=0
P 4.67901998 1.4891 3 P 0 8 0;0,2=3,4=0
P 3.259 2.106 36 P 0 8 0;0,2=1,4=0
P 3.21 2.11 39 P 0 8 0;0,2=1,4=0
P 4.71838996 1.4891 3 P 0 8 0;0,2=3,4=0
P 3.259 2.064 36 P 0 8 0;0,2=1,4=0
P 3.21 2.06 39 P 0 8 0;0,2=1,4=0
P 4.71838996 1.41035 3 P 0 8 0;0,2=3,4=0
P 3.259 2.011 36 P 0 8 0;0,2=1,4=0
P 3.21 2.015 39 P 0 8 0;0,2=1,4=0
P 4.71838996 1.37098002 3 P 0 8 0;0,2=3,4=0
P 3.259 1.969 36 P 0 8 0;0,2=1,4=0
P 3.21 1.965 39 P 0 8 0;0,2=1,4=0
P 4.56091004 1.8828 3 P 0 8 0;0,2=3,4=0
P 4.785 3.504 36 P 0 8 0;0,2=1,4=0
P 4.63965 1.92216998 3 P 0 8 0;0,2=3,4=0
P 3.93098002 1.72531998 3 P 0 8 0;0,2=3,4=0
P 3.97035 1.60721004 3 P 0 8 0;0,2=3,4=0
P 3.93098002 1.56783996 3 P 0 8 0;0,2=3,4=0
P 3.93098002 1.64658002 3 P 0 8 0;0,2=3,4=0
P 3.97035 1.44973002 3 P 0 8 0;0,2=3,4=0
P 3.93098002 1.4891 3 P 0 8 0;0,2=3,4=0
P 4.52153996 1.64658002 3 P 0 8 0;0,2=3,4=0
P 4.959 1.43 39 P 0 8 0;0,2=1,4=0
P 4.959 1.385 39 P 0 8 0;0,2=1,4=0
P 4.52153996 1.68595 3 P 0 8 0;0,2=3,4=0
P 4.52153996 1.72531998 3 P 0 8 0;0,2=3,4=0
P 4.884 1.72 39 P 0 8 0;0,2=1,4=0
P 4.884 1.765 39 P 0 8 0;0,2=1,4=0
P 4.53 1.181 36 P 0 8 0;0,2=1,4=0
P 4.60028002 1.33161004 3 P 0 8 0;0,2=3,4=0
P 3.165 1.8 39 P 0 8 0;0,2=1,4=0
P 4.585 1.181 36 P 0 8 0;0,2=1,4=0
P 4.63965 1.33161004 3 P 0 8 0;0,2=3,4=0
P 3.165 1.75 39 P 0 8 0;0,2=1,4=0
P 4.12783996 1.72531998 3 P 0 8 0;0,2=3,4=0
P 4.44 2.419 36 P 0 8 0;0,2=1,4=0
P 4.395 2.419 36 P 0 8 0;0,2=1,4=0
P 4.36406004 2.00091004 3 P 0 8 0;0,2=3,4=0
P 4.36406004 2.04028002 3 P 0 8 0;0,2=3,4=0
P 4.36406004 2.07965 3 P 0 8 0;0,2=3,4=0
P 4.52153996 1.60721004 3 P 0 8 0;0,2=3,4=0
P 4.959 1.335 39 P 0 8 0;0,2=1,4=0
P 4.28531998 1.76468996 3 P 0 8 0;0,2=3,4=0
P 0.1975 1.0435 50 P 0 8 0;0,2=32,4=0
P 0.1975 2.1835 50 P 0 8 0;0,2=32,4=0
P 3.554 1.78748996 36 P 0 8 0;0,2=1,4=0
P 3.53613996 1.88543002 78 P 0 8 0;0,2=54,4=0
P 6.26988996 2.20183996 32 P 0 8 0;0,2=4,4=0
P 6.4105 2.05906004 62 P 0 8 0;0,2=43,4=0
P 6.289 2.01273996 36 P 0 8 0;0,2=1,4=0
P 6.225 2.03673996 63 P 0 8 0;0,2=14,4=0
P 1.84386998 3.976 81 P 0 8 0;0,2=55,4=0
P 1.66961998 3.9532 8 P 0 8 0;0,2=48,4=0
P 1.66961998 3.9788 8 P 0 8 0;0,2=48,4=0
P 1.477 3.991 39 P 0 8 0;0,2=1,4=0
P 1.58103996 3.95616004 33 P 0 8 0;0,2=49,4=0
P 1.556 4.12 36 P 0 8 0;0,2=1,4=0
P 1.58103996 4.02013002 35 P 0 8 0;0,2=50,4=0
P 1.467 3.851 39 P 0 8 0;0,2=1,4=0
P 1.58103996 3.91186998 35 P 0 8 0;0,2=50,4=0
P 1.47143002 3.901 12 P 0 8 0;0,2=9,4=0
P 1.477 4.142 39 P 0 8 0;0,2=1,4=0
P 1.46643002 4.086 12 P 0 8 0;0,2=9,4=0
P 1.58103996 3.99553002 33 P 0 8 0;0,2=49,4=0
P 1.47143002 4.031 12 P 0 8 0;0,2=9,4=0
P 1.58103996 3.97583996 33 P 0 8 0;0,2=49,4=0
P 1.6086 3.90103996 13 P 0 8 0;0,2=51,4=0
P 1.6086 4.03096004 13 P 0 8 0;0,2=51,4=0
P 1.556 4.162 36 P 0 8 0;0,2=1,4=0
P 1.45056998 4.031 12 P 0 8 0;0,2=9,4=0
P 1.435 3.991 39 P 0 8 0;0,2=1,4=0
P 5.131 3.775 39 P 0 8 0;0,2=1,4=0
P 5.12 3.853 43 P 0 8 0;0,2=12,4=0
P 1.59668996 3.27 5 P 0 8 0;0,2=10,4=0
P 2.176 3.887 36 P 0 8 0;0,2=1,4=0
P 2.236 3.894 63 P 0 8 0;0,2=14,4=0
P 2.261 4.038 63 P 0 8 0;0,2=14,4=0
P 2.186 4.038 63 P 0 8 0;0,2=14,4=0
P 1.385 4.126 36 P 0 8 0;0,2=1,4=0
P 2.07813002 3.976 81 P 0 8 0;0,2=55,4=0
P 3.32938002 4.0248 8 P 0 8 0;0,2=48,4=0
P 3.32938002 3.9992 8 P 0 8 0;0,2=48,4=0
P 3.05 3.98213002 23 P 0 8 0;0,2=55,4=0
P 3.41796004 4.02183996 33 P 0 8 0;0,2=49,4=0
P 3.522 3.987 39 P 0 8 0;0,2=1,4=0
P 3.443 3.858 36 P 0 8 0;0,2=1,4=0
P 3.41796004 3.95786998 35 P 0 8 0;0,2=50,4=0
P 3.536 3.78 39 P 0 8 0;0,2=1,4=0
P 3.522 3.833 39 P 0 8 0;0,2=1,4=0
P 3.41796004 3.98246998 33 P 0 8 0;0,2=49,4=0
P 3.52756998 3.892 12 P 0 8 0;0,2=9,4=0
P 3.41796004 4.04153002 33 P 0 8 0;0,2=49,4=0
P 3.522 4.077 39 P 0 8 0;0,2=1,4=0
P 3.522 4.032 39 P 0 8 0;0,2=1,4=0
P 3.41796004 4.00216004 33 P 0 8 0;0,2=49,4=0
P 3.52756998 3.947 12 P 0 8 0;0,2=9,4=0
P 3.3904 4.07696004 13 P 0 8 0;0,2=51,4=0
P 3.564 3.987 39 P 0 8 0;0,2=1,4=0
P 3.54843002 3.947 12 P 0 8 0;0,2=9,4=0
P 3.443 3.816 36 P 0 8 0;0,2=1,4=0
P 3.494 3.78 39 P 0 8 0;0,2=1,4=0
P 3.3904 3.94703996 13 P 0 8 0;0,2=51,4=0
P 5.59271004 3.71731004 58 P 0 8 0;0,2=56,4=0
P 5.71056998 3.712 12 P 0 8 0;0,2=9,4=0
P 5.59271004 3.75668996 58 P 0 8 0;0,2=56,4=0
P 5.72 3.807 39 P 0 8 0;0,2=1,4=0
P 5.51631004 3.83456004 21 P 0 8 0;0,2=52,4=0
P 5.50643002 3.967 39 P 0 8 0;0,2=1,4=0
P 5.50643002 3.912 12 P 0 8 0;0,2=9,4=0
P 5.362 3.957 39 P 0 8 0;0,2=1,4=0
P 5.59271004 3.737 58 P 0 8 0;0,2=56,4=0
P 5.72 3.757 39 P 0 8 0;0,2=1,4=0
P 5.59271004 3.79606004 58 P 0 8 0;0,2=56,4=0
P 5.72 3.857 39 P 0 8 0;0,2=1,4=0
P 5.59271004 3.81573996 58 P 0 8 0;0,2=56,4=0
P 5.72 3.907 39 P 0 8 0;0,2=1,4=0
P 0.873 3.736 69 P 0 8 0;0,2=57,4=0
P 5.59271004 3.65826004 58 P 0 8 0;0,2=56,4=0
P 5.72 3.467 39 P 0 8 0;0,2=1,4=0
P 5.72 3.517 39 P 0 8 0;0,2=1,4=0
P 5.72 3.567 39 P 0 8 0;0,2=1,4=0
P 5.47928996 3.81573996 58 P 0 8 0;0,2=56,4=0
P 5.364 3.827 47 P 0 8 0;0,2=14,4=0
P 5.368 3.902 40 P 0 8 0;0,2=12,4=0
P 3.552 4.197 39 P 0 8 0;0,2=1,4=0
P 3.465 4.202 40 P 0 8 0;0,2=12,4=0
P 5.601 3.96 39 P 0 8 0;0,2=1,4=0
P 5.762 3.907 39 P 0 8 0;0,2=1,4=0
P 1.445 3.746 36 P 0 8 0;0,2=1,4=0
P 1.534 3.776 40 P 0 8 0;0,2=12,4=0
P 5.331 2.28 36 P 0 8 0;0,2=1,4=0
P 5.395 2.283 43 P 0 8 0;0,2=12,4=0
P 5.47928996 3.79606004 58 P 0 8 0;0,2=56,4=0
P 5.47928996 3.77636998 58 P 0 8 0;0,2=56,4=0
P 5.47928996 3.75668996 58 P 0 8 0;0,2=56,4=0
P 5.47928996 3.737 58 P 0 8 0;0,2=56,4=0
P 5.47928996 3.71731004 58 P 0 8 0;0,2=56,4=0
P 5.47928996 3.69763002 58 P 0 8 0;0,2=56,4=0
P 5.47928996 3.67793996 58 P 0 8 0;0,2=56,4=0
P 5.47928996 3.65826004 58 P 0 8 0;0,2=56,4=0
P 5.336 3.672 63 P 0 8 0;0,2=14,4=0
P 5.254 3.672 63 P 0 8 0;0,2=14,4=0
P 5.479 3.569 40 P 0 8 0;0,2=12,4=0
P 1.588 3.776 40 P 0 8 0;0,2=12,4=0
P 1.65 4.091 39 P 0 8 0;0,2=1,4=0
P 1.648 4.151 47 P 0 8 0;0,2=14,4=0
P 1.63221998 4.02013002 27 P 0 8 0;0,2=53,4=0
P 1.63221998 3.91186998 27 P 0 8 0;0,2=53,4=0
P 1.67 3.841 39 P 0 8 0;0,2=1,4=0
P 1.678 3.776 47 P 0 8 0;0,2=14,4=0
P 3.411 4.202 40 P 0 8 0;0,2=12,4=0
P 3.329 4.137 39 P 0 8 0;0,2=1,4=0
P 3.321 4.202 47 P 0 8 0;0,2=14,4=0
P 3.36678002 4.06613002 27 P 0 8 0;0,2=53,4=0
P 3.36678002 3.95786998 27 P 0 8 0;0,2=53,4=0
P 3.349 3.887 39 P 0 8 0;0,2=1,4=0
P 3.351 3.827 47 P 0 8 0;0,2=14,4=0
P 3.564 3.833 39 P 0 8 0;0,2=1,4=0
P 3.54843002 3.892 12 P 0 8 0;0,2=9,4=0
P 3.623 3.878 36 P 0 8 0;0,2=1,4=0
P 1.435 4.142 39 P 0 8 0;0,2=1,4=0
P 1.385 4.084 36 P 0 8 0;0,2=1,4=0
P 1.44556998 4.086 12 P 0 8 0;0,2=9,4=0
P 1.8832 0.59 71 P 0 8 0;0,2=46,4=0
P 2.0477 0.59 36 P 0 8 0;0,2=1,4=0
P 1.9977 0.59 36 P 0 8 0;0,2=1,4=0
P 5.59271004 3.67793996 58 P 0 8 0;0,2=56,4=0
P 5.72 3.617 39 P 0 8 0;0,2=1,4=0
P 5.59271004 3.69763002 58 P 0 8 0;0,2=56,4=0
P 5.72 3.667 39 P 0 8 0;0,2=1,4=0
P 5.50543996 2.721 22 P 0 8 0;0,2=26,4=0
P 0.53 1.444 36 P 0 8 0;0,2=1,4=0
P 0.55708002 1.35 14 P 0 8 0;0,2=31,4=0
P 0.535 0.884 36 P 0 8 0;0,2=1,4=0
P 0.55708002 0.77913996 14 P 0 8 0;0,2=31,4=0
P 3.55188996 1.88543002 78 P 0 8 0;0,2=54,4=0
P 3.604 1.78748996 36 P 0 8 0;0,2=1,4=0
P 1.58103996 3.93646998 33 P 0 8 0;0,2=49,4=0
P 1.477 3.946 39 P 0 8 0;0,2=1,4=0
P 1.6622 0.69 71 P 0 8 0;0,2=46,4=0
P 1.8832 0.69 71 P 0 8 0;0,2=46,4=0
P 3.161 1.895 39 P 0 8 0;0,2=1,4=0
P 3.50595 1.90761998 45 P 0 8 0;0,2=42,4=0
P 3.161 1.85 39 P 0 8 0;0,2=1,4=0
P 3.50595 1.92336004 45 P 0 8 0;0,2=42,4=0
P 5.50543996 2.821 22 P 0 8 0;0,2=26,4=0
P 5.71056004 2.921 22 P 0 8 0;0,2=26,4=0
P 5.50543996 2.921 22 P 0 8 0;0,2=26,4=0
P 1.6622 0.74 71 P 0 8 0;0,2=46,4=0
P 5.12 3.907 43 P 0 8 0;0,2=12,4=0
P 4.91548996 3.90826998 75 P 0 8 0;0,2=13,4=0
P 5.05 3.903 63 P 0 8 0;0,2=14,4=0
P 2.92733996 1.88963002 72 P 0 8 0;0,2=58,4=0
P 2.105 0.594 36 P 0 8 0;0,2=1,4=0
P 2.15 0.594 36 P 0 8 0;0,2=1,4=0
P 0.715 2.402 36 P 0 8 0;0,2=1,4=0
P 0.7826 2.4275 29 P 0 8 0;0,2=30,4=0
P 3.255 3.664 36 P 0 8 0;0,2=1,4=0
P 3.623 3.836 36 P 0 8 0;0,2=1,4=0
P 3.48 3.652 63 P 0 8 0;0,2=14,4=0
P 3.4 3.652 63 P 0 8 0;0,2=14,4=0
P 3.05 3.74786998 23 P 0 8 0;0,2=55,4=0
P 3.32 3.652 63 P 0 8 0;0,2=14,4=0
P 3.654 3.099 40 P 0 8 0;0,2=12,4=0
P 3.662 3.018 36 P 0 8 0;0,2=1,4=0
P 5.27 2.811 36 P 0 8 0;0,2=1,4=0
P 4.41975 2.82428996 42 P 0 8 0;0,2=59,4=0
P 4.41975 2.86616004 41 P 0 8 0;0,2=40,4=0
P 4.455 2.738 63 P 0 8 0;0,2=14,4=0
P 4.39 2.741 36 P 0 8 0;0,2=1,4=0
P 3.968 2.68 39 P 0 8 0;0,2=1,4=0
P 4.524 2.895 39 P 0 8 0;0,2=1,4=0
P 4.933 2.466 43 P 0 8 0;0,2=12,4=0
P 5.014 2.474 39 P 0 8 0;0,2=1,4=0
P 5.64 0.986 36 P 0 8 0;0,2=1,4=0
P 5.7 0.987 43 P 0 8 0;0,2=12,4=0
P 5.575 0.998 63 P 0 8 0;0,2=14,4=0
P 2.595 0.605 39 P 0 8 0;0,2=1,4=0
P 0.571 3.845 43 P 0 8 0;0,2=12,4=0
P 0.693 3.736 69 P 0 8 0;0,2=57,4=0
P 3.63673002 2.39156998 26 P 0 8 0;0,2=9,4=0
P 3.45151998 2.36321004 38 P 0 8 0;0,2=36,4=0
P 3.57 2.38556998 64 P 0 8 0;0,2=38,4=0
P 3.0425 3.3022 68 P 0 8 0;0,2=5,4=0
P 3.2815 3.25101998 68 P 0 8 0;0,2=5,4=0
P 3.2815 3.22543002 68 P 0 8 0;0,2=5,4=0
P 2.51121998 0.584 36 P 0 8 0;0,2=1,4=0
P 5.78936998 4.27558002 6 P 0 8 0;0,2=25,4=0
P 5.43503996 4.27558002 6 P 0 8 0;0,2=25,4=0
P 5.55315 4.27558002 6 P 0 8 0;0,2=25,4=0
P 5.67126004 4.27558002 6 P 0 8 0;0,2=25,4=0
P 3.2815 3.35338996 68 P 0 8 0;0,2=5,4=0
P 5.91901998 1.90865 36 P 0 8 0;0,2=1,4=0
P 3.2815 3.37898002 68 P 0 8 0;0,2=5,4=0
P 6.06901998 1.90865 36 P 0 8 0;0,2=1,4=0
P 5.98016004 2.04418002 15 P 0 8 0;0,2=15,4=0
P 5.96901998 1.95065 36 P 0 8 0;0,2=1,4=0
P 5.762 3.667 39 P 0 8 0;0,2=1,4=0
P 3.705 1.648 63 P 0 8 0;0,2=14,4=0
P 3.515 1.648 63 P 0 8 0;0,2=14,4=0
P 3.575 1.621 36 P 0 8 0;0,2=1,4=0
P 2.105 0.636 36 P 0 8 0;0,2=1,4=0
P 2.15 0.636 36 P 0 8 0;0,2=1,4=0
P 2.754 0.57941004 46 P 0 8 0;0,2=45,4=0
P 2.595 0.655 39 P 0 8 0;0,2=1,4=0
P 2.9972 0.6678 39 P 0 8 0;0,2=1,4=0
P 3.798 1.06 47 P 0 8 0;0,2=14,4=0
P 4.101 0.97 39 P 0 8 0;0,2=1,4=0
P 4.08 0.75216998 65 P 0 8 0;0,2=8,4=0
P 3.769 0.97 39 P 0 8 0;0,2=1,4=0
P 3.964 0.97 39 P 0 8 0;0,2=1,4=0
P 3.911 0.97 39 P 0 8 0;0,2=1,4=0
P 3.604 1.74548996 36 P 0 8 0;0,2=1,4=0
P 5.9945 1.37063002 76 P 0 8 0;0,2=23,4=0
P 6.14648002 1.37063002 79 P 0 8 0;0,2=24,4=0
P 6.0845 1.0066 67 P 0 8 0;0,2=30,4=0
P 1.29831004 3.85153996 66 P 0 8 0;0,2=22,4=0
P 1.21168996 3.91846004 66 P 0 8 0;0,2=22,4=0
P 0.452 2.368 36 P 0 8 0;0,2=1,4=0
P 5.29043002 2.725 12 P 0 8 0;0,2=9,4=0
P 5.96046998 2.14381998 15 P 0 8 0;0,2=15,4=0
P 5.98016004 2.14381998 15 P 0 8 0;0,2=15,4=0
P 1.62033002 2.97111998 83 P 0 8 0;0,2=21,4=0
P 5.16766998 2.75088002 82 P 0 8 0;0,2=21,4=0
P 5.59271004 3.77636998 58 P 0 8 0;0,2=56,4=0
P 4.0489 3.992 60 P 0 8 0;0,2=0,4=0
P 4.144 3.8969 18 P 0 8 0;0,2=33,4=0
P 4.144 4.0871 18 P 0 8 0;0,2=33,4=0
P 4.41975 2.88583996 41 P 0 8 0;0,2=40,4=0
P 1.484 2.95 39 P 0 8 0;0,2=1,4=0
P 1.46 3.007 63 P 0 8 0;0,2=14,4=0
P 2.0966 3.2655 29 P 0 8 0;0,2=30,4=0
P 1.51 3.206 36 P 0 8 0;0,2=1,4=0
P 1.848 3.26 47 P 0 8 0;0,2=14,4=0
P 1.888 3.105 47 P 0 8 0;0,2=14,4=0
P 1.861 3.19 39 P 0 8 0;0,2=1,4=0
P 1.885 2.981 36 P 0 8 0;0,2=1,4=0
P 1.866 3.04 39 P 0 8 0;0,2=1,4=0
P 1.71456998 2.9 12 P 0 8 0;0,2=9,4=0
P 4.551 3.27 39 P 0 8 0;0,2=1,4=0
P 4.4585 1.123 39 P 0 8 0;0,2=1,4=0
P 4.3245 1.123 39 P 0 8 0;0,2=1,4=0
P 3.695 2.6265 32 P 0 8 0;0,2=4,4=0
P 3.705 2.384 36 P 0 8 0;0,2=1,4=0
P 2.895 3.206 39 P 0 8 0;0,2=1,4=0
P 0.455 1.22 36 P 0 8 0;0,2=1,4=0
P 0.2055 0.9565 53 P 0 8 0;0,2=60,4=0
P 0.2055 2.0965 53 P 0 8 0;0,2=60,4=0
P 0.455 1.644 36 P 0 8 0;0,2=1,4=0
P 1.25095 3.12 19 P 0 8 0;0,2=11,4=0
P 0.894 3.33916004 70 P 0 8 0;0,2=11,4=0
P 1.445 3.704 36 P 0 8 0;0,2=1,4=0
P 0.631 3.29 39 P 0 8 0;0,2=1,4=0
P 0.72 3.3935 32 P 0 8 0;0,2=4,4=0
P 0.595 3.596 36 P 0 8 0;0,2=1,4=0
P 1.352 3.24073002 70 P 0 8 0;0,2=11,4=0
P 4.426 3.745 39 P 0 8 0;0,2=1,4=0
P 4.472 3.5315 49 P 0 8 0;0,2=8,4=0
P 4.735 3.504 36 P 0 8 0;0,2=1,4=0
P 0.606 1.64745 36 P 0 8 0;0,2=1,4=0
P 5.291 0.87 39 P 0 8 0;0,2=1,4=0
P 5.291 0.92 39 P 0 8 0;0,2=1,4=0
P 6.26988996 2.31483996 32 P 0 8 0;0,2=4,4=0
P 4.426 3.79 39 P 0 8 0;0,2=1,4=0
P 3.769 3.385 73 P 0 8 0;0,2=27,4=0
P 6.22356004 3.015 22 P 0 8 0;0,2=26,4=0
P 0.51043002 1.57 12 P 0 8 0;0,2=9,4=0
P 1.01473002 3.12 19 P 0 8 0;0,2=11,4=0
P 1.21456998 3.79 12 P 0 8 0;0,2=9,4=0
P 1.29043002 3.79 12 P 0 8 0;0,2=9,4=0
P 1.27063996 3.578 19 P 0 8 0;0,2=11,4=0
P 6.4105 2.16141998 62 P 0 8 0;0,2=43,4=0
P 4.8855 0.74043002 68 P 0 8 0;0,2=5,4=0
P 5.2975 1.345 54 P 0 8 0;0,2=44,4=0
P 5.273 1.24 47 P 0 8 0;0,2=14,4=0
P 6.421 1.135 39 P 0 8 0;0,2=1,4=0
P 4.554 3.22 39 P 0 8 0;0,2=1,4=0
P 4.175 3.4824 28 P 0 8 0;0,2=6,4=0
P 3.98 3.4804 28 P 0 8 0;0,2=6,4=0
P 4.1695 3.06643002 68 P 0 8 0;0,2=5,4=0
P 4.0355 3.58543002 68 P 0 8 0;0,2=5,4=0
P 5.637 3.569 39 P 0 8 0;0,2=1,4=0
P 5.29108002 3.306 80 P 0 8 0;0,2=17,4=0
P 5.762 3.617 39 P 0 8 0;0,2=1,4=0
P 5.73143002 3.712 12 P 0 8 0;0,2=9,4=0
P 5.762 3.807 39 P 0 8 0;0,2=1,4=0
P 5.762 3.757 39 P 0 8 0;0,2=1,4=0
P 5.762 3.857 39 P 0 8 0;0,2=1,4=0
P 5.601 3.915 39 P 0 8 0;0,2=1,4=0
P 5.48556998 3.912 12 P 0 8 0;0,2=9,4=0
P 5.298 3.827 47 P 0 8 0;0,2=14,4=0
P 5.254 3.738 63 P 0 8 0;0,2=14,4=0
P 5.336 3.738 63 P 0 8 0;0,2=14,4=0
P 5.43503996 4.07875 6 P 0 8 0;0,2=25,4=0
P 5.55315 4.07875 6 P 0 8 0;0,2=25,4=0
P 5.67126004 4.07875 6 P 0 8 0;0,2=25,4=0
P 5.78936998 4.07875 6 P 0 8 0;0,2=25,4=0
P 5.90748002 4.07875 6 P 0 8 0;0,2=25,4=0
P 6.1437 4.07875 6 P 0 8 0;0,2=25,4=0
P 6.02558996 4.07875 6 P 0 8 0;0,2=25,4=0
P 1.1919 3.578 19 P 0 8 0;0,2=11,4=0
P 1.09346998 3.578 19 P 0 8 0;0,2=11,4=0
P 1.07378996 3.578 19 P 0 8 0;0,2=11,4=0
P 0.99505 3.578 19 P 0 8 0;0,2=11,4=0
P 0.73661998 0.9475 25 P 0 8 0;0,2=20,4=0
P 0.49656998 2.68 12 P 0 8 0;0,2=9,4=0
P 0.51771998 2.49173996 14 P 0 8 0;0,2=31,4=0
P 0.64 2.229 36 P 0 8 0;0,2=1,4=0
P 0.51643002 2.166 12 P 0 8 0;0,2=9,4=0
P 0.51771998 1.92086998 14 P 0 8 0;0,2=31,4=0
P 0.51771998 1.35 14 P 0 8 0;0,2=31,4=0
P 0.443 0.689 36 P 0 8 0;0,2=1,4=0
P 0.625 1.084 36 P 0 8 0;0,2=1,4=0
P 0.51771998 0.77913996 14 P 0 8 0;0,2=31,4=0
P 3.816 2.68 39 P 0 8 0;0,2=1,4=0
P 4.566 2.845 39 P 0 8 0;0,2=1,4=0
P 0.835 2.524 36 P 0 8 0;0,2=1,4=0
P 0.619 2.79 39 P 0 8 0;0,2=1,4=0
P 5.41 1.836 36 P 0 8 0;0,2=1,4=0
P 5.35 1.853 63 P 0 8 0;0,2=14,4=0
P 5.723 1.61 47 P 0 8 0;0,2=14,4=0
P 5.39 1.597 63 P 0 8 0;0,2=14,4=0
P 0.951 2.728 39 P 0 8 0;0,2=1,4=0
P 0.95048002 2.683 39 P 0 8 0;0,2=1,4=0
P 2.261 4.104 63 P 0 8 0;0,2=14,4=0
P 2.186 4.104 63 P 0 8 0;0,2=14,4=0
P 1.692 4.091 39 P 0 8 0;0,2=1,4=0
P 1.714 4.151 47 P 0 8 0;0,2=14,4=0
P 1.70111998 4.02013002 16 P 0 8 0;0,2=61,4=0
P 1.67946004 4.02013002 16 P 0 8 0;0,2=61,4=0
P 1.65781004 4.02013002 16 P 0 8 0;0,2=61,4=0
P 2.176 3.845 36 P 0 8 0;0,2=1,4=0
P 2.236 3.828 63 P 0 8 0;0,2=14,4=0
P 1.65781004 3.91186998 16 P 0 8 0;0,2=61,4=0
P 1.67946004 3.91186998 16 P 0 8 0;0,2=61,4=0
P 1.70111998 3.91186998 16 P 0 8 0;0,2=61,4=0
P 1.744 3.776 47 P 0 8 0;0,2=14,4=0
P 1.712 3.841 39 P 0 8 0;0,2=1,4=0
P 0.9575 0.691 59 P 0 8 0;0,2=4,4=0
P 0.86206998 2.091 52 P 0 8 0;0,2=62,4=0
P 1.2157 0.6136 39 P 0 8 0;0,2=1,4=0
P 0.81998996 2.661 24 P 0 8 0;0,2=35,4=0
P 0.715 2.444 36 P 0 8 0;0,2=1,4=0
P 0.714 2.252 36 P 0 8 0;0,2=1,4=0
P 0.74593002 2.091 52 P 0 8 0;0,2=62,4=0
P 0.81998996 2.64131004 24 P 0 8 0;0,2=35,4=0
P 0.907 2.58048002 39 P 0 8 0;0,2=1,4=0
P 0.8594 2.2465 29 P 0 8 0;0,2=30,4=0
P 1.435 3.946 39 P 0 8 0;0,2=1,4=0
P 1.45056998 3.901 12 P 0 8 0;0,2=9,4=0
P 1.8832 0.74 71 P 0 8 0;0,2=46,4=0
P 1.548 0.6632 36 P 0 8 0;0,2=1,4=0
P 2.218 2.931 36 P 0 8 0;0,2=1,4=0
P 4.455 2.672 63 P 0 8 0;0,2=14,4=0
P 4.39 2.699 36 P 0 8 0;0,2=1,4=0
P 5.76 2.087 63 P 0 8 0;0,2=14,4=0
P 3.48 3.718 63 P 0 8 0;0,2=14,4=0
P 3.4 3.718 63 P 0 8 0;0,2=14,4=0
P 3.255 3.706 36 P 0 8 0;0,2=1,4=0
P 3.32 3.718 63 P 0 8 0;0,2=14,4=0
P 4.56091004 1.72531998 3 P 0 8 0;0,2=3,4=0
P 5.089 3.775 39 P 0 8 0;0,2=1,4=0
P 5.05 3.837 63 P 0 8 0;0,2=14,4=0
P 4.588 3.927 47 P 0 8 0;0,2=14,4=0
P 4.53 3.891 36 P 0 8 0;0,2=1,4=0
P 3.23743996 2.865 22 P 0 8 0;0,2=26,4=0
P 3.23743996 2.765 22 P 0 8 0;0,2=26,4=0
P 3.95588002 2.88533002 85 P 0 8 0;0,2=21,4=0
P 6.071 2.225 39 P 0 8 0;0,2=1,4=0
P 6.071 2.27 39 P 0 8 0;0,2=1,4=0
P 6.141 2.278 36 P 0 8 0;0,2=1,4=0
P 5.78043002 0.609 12 P 0 8 0;0,2=9,4=0
P 5.772 0.658 36 P 0 8 0;0,2=1,4=0
P 5.43956998 0.635 12 P 0 8 0;0,2=9,4=0
P 5.56533002 0.63511998 83 P 0 8 0;0,2=21,4=0
P 5.575 0.932 63 P 0 8 0;0,2=14,4=0
P 4.933 1.264 47 P 0 8 0;0,2=14,4=0
P 5.001 1.43 39 P 0 8 0;0,2=1,4=0
P 4.44 2.461 36 P 0 8 0;0,2=1,4=0
P 5.2975 1.595 54 P 0 8 0;0,2=44,4=0
P 5.2975 1.47 54 P 0 8 0;0,2=44,4=0
P 5.64 0.944 36 P 0 8 0;0,2=1,4=0
P 5.632 0.859 47 P 0 8 0;0,2=14,4=0
P 5.649 0.792 39 P 0 8 0;0,2=1,4=0
P 5.55 0.863 47 P 0 8 0;0,2=14,4=0
P 5.569 0.792 39 P 0 8 0;0,2=1,4=0
P 4.414 0.82366004 37 P 0 8 0;0,2=7,4=0
P 4.46 0.973 39 P 0 8 0;0,2=1,4=0
P 4.322 0.973 39 P 0 8 0;0,2=1,4=0
P 4.71838996 1.64658002 3 P 0 8 0;0,2=3,4=0
P 2.76986004 1.79121004 72 P 0 8 0;0,2=58,4=0
P 2.76986004 1.85026004 72 P 0 8 0;0,2=58,4=0
P 3.63673002 2.41243002 26 P 0 8 0;0,2=9,4=0
P 3.63673002 2.32556998 26 P 0 8 0;0,2=9,4=0
P 3.45151998 2.32383996 38 P 0 8 0;0,2=36,4=0
P 3.41953002 2.40503996 9 P 0 8 0;0,2=37,4=0
P 3.159 2.344 39 P 0 8 0;0,2=1,4=0
P 3.159 2.164 39 P 0 8 0;0,2=1,4=0
P 2.92733996 1.86995 72 P 0 8 0;0,2=58,4=0
P 3.50595 1.93911004 45 P 0 8 0;0,2=42,4=0
P 4.28531998 2.15838996 3 P 0 8 0;0,2=3,4=0
P 5.385 2.057 63 P 0 8 0;0,2=14,4=0
P 5.056 2.474 39 P 0 8 0;0,2=1,4=0
P 4.56091004 1.33161004 3 P 0 8 0;0,2=3,4=0
P 4.67901998 1.37098002 3 P 0 8 0;0,2=3,4=0
P 4.52153996 1.44973002 3 P 0 8 0;0,2=3,4=0
P 4.40343002 1.56783996 3 P 0 8 0;0,2=3,4=0
P 4.40343002 1.41035 3 P 0 8 0;0,2=3,4=0
P 4.36406004 1.60721004 3 P 0 8 0;0,2=3,4=0
P 4.36406004 1.52846998 3 P 0 8 0;0,2=3,4=0
P 4.36406004 1.64658002 3 P 0 8 0;0,2=3,4=0
P 4.32468996 1.56783996 3 P 0 8 0;0,2=3,4=0
P 4.32468996 1.68595 3 P 0 8 0;0,2=3,4=0
P 4.32468996 1.64658002 3 P 0 8 0;0,2=3,4=0
P 4.28531998 1.60721004 3 P 0 8 0;0,2=3,4=0
P 4.28531998 1.37098002 3 P 0 8 0;0,2=3,4=0
P 4.28531998 1.64658002 3 P 0 8 0;0,2=3,4=0
P 4.28531998 1.68595 3 P 0 8 0;0,2=3,4=0
P 4.24595 1.56783996 3 P 0 8 0;0,2=3,4=0
P 4.24595 1.4891 3 P 0 8 0;0,2=3,4=0
P 4.24595 1.64658002 3 P 0 8 0;0,2=3,4=0
P 4.20658002 1.60721004 3 P 0 8 0;0,2=3,4=0
P 4.16721004 1.56783996 3 P 0 8 0;0,2=3,4=0
P 4.16721004 1.33161004 3 P 0 8 0;0,2=3,4=0
P 4.12783996 1.56783996 3 P 0 8 0;0,2=3,4=0
P 4.12783996 1.52846998 3 P 0 8 0;0,2=3,4=0
P 4.12783996 1.4891 3 P 0 8 0;0,2=3,4=0
P 4.08846998 1.4891 3 P 0 8 0;0,2=3,4=0
P 4.0491 1.4891 3 P 0 8 0;0,2=3,4=0
P 4.0491 1.44973002 3 P 0 8 0;0,2=3,4=0
P 4.00973002 1.44973002 3 P 0 8 0;0,2=3,4=0
P 4.00973002 1.41035 3 P 0 8 0;0,2=3,4=0
P 3.97035 1.41035 3 P 0 8 0;0,2=3,4=0
P 3.89161004 2.15838996 3 P 0 8 0;0,2=3,4=0
P 3.93098002 2.04028002 3 P 0 8 0;0,2=3,4=0
P 3.97035 1.92216998 3 P 0 8 0;0,2=3,4=0
P 4.12783996 1.84343002 3 P 0 8 0;0,2=3,4=0
P 4.00973002 1.80406004 3 P 0 8 0;0,2=3,4=0
P 4.20658002 1.76468996 3 P 0 8 0;0,2=3,4=0
P 4.12783996 1.76468996 3 P 0 8 0;0,2=3,4=0
P 4.00973002 1.76468996 3 P 0 8 0;0,2=3,4=0
P 3.89161004 1.76468996 3 P 0 8 0;0,2=3,4=0
P 3.97035 1.76468996 3 P 0 8 0;0,2=3,4=0
P 3.93098002 1.76468996 3 P 0 8 0;0,2=3,4=0
P 4.24595 1.72531998 3 P 0 8 0;0,2=3,4=0
P 4.16721004 1.72531998 3 P 0 8 0;0,2=3,4=0
P 4.08846998 1.72531998 3 P 0 8 0;0,2=3,4=0
P 4.0491 1.72531998 3 P 0 8 0;0,2=3,4=0
P 3.89161004 1.72531998 3 P 0 8 0;0,2=3,4=0
P 4.20658002 1.68595 3 P 0 8 0;0,2=3,4=0
P 4.12783996 1.68595 3 P 0 8 0;0,2=3,4=0
P 3.97035 1.68595 3 P 0 8 0;0,2=3,4=0
P 3.89161004 1.64658002 3 P 0 8 0;0,2=3,4=0
P 4.16721004 1.64658002 3 P 0 8 0;0,2=3,4=0
P 4.12783996 1.64658002 3 P 0 8 0;0,2=3,4=0
P 4.0491 1.64658002 3 P 0 8 0;0,2=3,4=0
P 4.12783996 1.60721004 3 P 0 8 0;0,2=3,4=0
P 4.00973002 1.60721004 3 P 0 8 0;0,2=3,4=0
P 3.89161004 1.56783996 3 P 0 8 0;0,2=3,4=0
P 4.0491 1.56783996 3 P 0 8 0;0,2=3,4=0
P 3.97035 1.52846998 3 P 0 8 0;0,2=3,4=0
P 3.89161004 1.4891 3 P 0 8 0;0,2=3,4=0
P 3.89161004 1.41035 3 P 0 8 0;0,2=3,4=0
P 3.93098002 1.41035 3 P 0 8 0;0,2=3,4=0
P 3.89161004 1.37098002 3 P 0 8 0;0,2=3,4=0
P 4.67901998 2.15838996 3 P 0 8 0;0,2=3,4=0
P 4.56091004 2.11901998 3 P 0 8 0;0,2=3,4=0
P 4.48216998 1.96153996 3 P 0 8 0;0,2=3,4=0
P 4.4428 2.07965 3 P 0 8 0;0,2=3,4=0
P 4.36406004 1.92216998 3 P 0 8 0;0,2=3,4=0
P 4.32468996 2.04028002 3 P 0 8 0;0,2=3,4=0
P 4.24595 1.8828 3 P 0 8 0;0,2=3,4=0
P 4.20658002 2.00091004 3 P 0 8 0;0,2=3,4=0
P 4.16721004 2.11901998 3 P 0 8 0;0,2=3,4=0
P 4.08846998 1.96153996 3 P 0 8 0;0,2=3,4=0
P 4.0491 2.07965 3 P 0 8 0;0,2=3,4=0
P 4.71838996 2.04028002 3 P 0 8 0;0,2=3,4=0
P 4.60028002 2.00091004 3 P 0 8 0;0,2=3,4=0
P 4.63965 1.8828 3 P 0 8 0;0,2=3,4=0
P 4.52153996 1.84343002 3 P 0 8 0;0,2=3,4=0
P 4.40343002 1.80406004 3 P 0 8 0;0,2=3,4=0
P 4.67901998 1.76468996 3 P 0 8 0;0,2=3,4=0
P 4.4428 1.76468996 3 P 0 8 0;0,2=3,4=0
P 4.48216998 1.72531998 3 P 0 8 0;0,2=3,4=0
P 4.40343002 1.72531998 3 P 0 8 0;0,2=3,4=0
P 4.32468996 1.72531998 3 P 0 8 0;0,2=3,4=0
P 4.4428 1.68595 3 P 0 8 0;0,2=3,4=0
P 4.36406004 1.68595 3 P 0 8 0;0,2=3,4=0
P 4.48216998 1.64658002 3 P 0 8 0;0,2=3,4=0
P 4.40343002 1.64658002 3 P 0 8 0;0,2=3,4=0
P 4.60028002 1.60721004 3 P 0 8 0;0,2=3,4=0
P 4.4428 1.60721004 3 P 0 8 0;0,2=3,4=0
P 4.48216998 1.56783996 3 P 0 8 0;0,2=3,4=0
P 4.63965 1.4891 3 P 0 8 0;0,2=3,4=0
P 4.134 2.936 47 P 0 8 0;0,2=14,4=0
P 4.134 2.855 47 P 0 8 0;0,2=14,4=0
P 4.145 2.792 39 P 0 8 0;0,2=1,4=0
P 3.287 4.137 39 P 0 8 0;0,2=1,4=0
P 3.255 4.202 47 P 0 8 0;0,2=14,4=0
P 3.34118996 4.06613002 16 P 0 8 0;0,2=61,4=0
P 3.31953996 4.06613002 16 P 0 8 0;0,2=61,4=0
P 3.29788002 4.06613002 16 P 0 8 0;0,2=61,4=0
P 3.29788002 3.95786998 16 P 0 8 0;0,2=61,4=0
P 3.31953996 3.95786998 16 P 0 8 0;0,2=61,4=0
P 3.34118996 3.95786998 16 P 0 8 0;0,2=61,4=0
P 3.307 3.887 39 P 0 8 0;0,2=1,4=0
P 3.285 3.827 47 P 0 8 0;0,2=14,4=0
P 3.662 2.976 36 P 0 8 0;0,2=1,4=0
P 3.797 2.969 36 P 0 8 0;0,2=1,4=0
P 3.797 2.891 36 P 0 8 0;0,2=1,4=0
P 3.732 2.952 63 P 0 8 0;0,2=14,4=0
P 3.729 2.87 63 P 0 8 0;0,2=14,4=0
P 3.594 4.197 39 P 0 8 0;0,2=1,4=0
P 3.582 2.898 36 P 0 8 0;0,2=1,4=0
P 3.816 2.725 39 P 0 8 0;0,2=1,4=0
P 3.582 2.761 36 P 0 8 0;0,2=1,4=0
P 4.95256998 2.777 12 P 0 8 0;0,2=9,4=0
P 4.961 2.728 36 P 0 8 0;0,2=1,4=0
P 3.982 3.10043002 26 P 0 8 0;0,2=9,4=0
P 3.96243002 2.774 12 P 0 8 0;0,2=9,4=0
P 3.933 3.092 39 P 0 8 0;0,2=1,4=0
P 3.564 4.032 39 P 0 8 0;0,2=1,4=0
P 3.54743002 4.121 12 P 0 8 0;0,2=9,4=0
P 3.564 4.077 39 P 0 8 0;0,2=1,4=0
P 4.396 3.915 39 P 0 8 0;0,2=1,4=0
P 4.396 3.965 39 P 0 8 0;0,2=1,4=0
P 4.396 4.015 39 P 0 8 0;0,2=1,4=0
P 4.78656004 3.67205 75 P 0 8 0;0,2=13,4=0
P 3.159 2.569 39 P 0 8 0;0,2=1,4=0
P 5.50543996 2.621 22 P 0 8 0;0,2=26,4=0
P 5.328 2.611 36 P 0 8 0;0,2=1,4=0
P 5.50543996 3.021 22 P 0 8 0;0,2=26,4=0
P 5.283 4.15048996 6 P 0 8 0;0,2=25,4=0
P 5.162 2.592 39 P 0 8 0;0,2=1,4=0
P 5.084 2.597 39 P 0 8 0;0,2=1,4=0
P 5.08 2.534 47 P 0 8 0;0,2=14,4=0
P 5.331 2.238 36 P 0 8 0;0,2=1,4=0
P 5.52086998 2.14318996 55 P 0 8 0;0,2=61,4=0
P 5.52086998 2.12153996 55 P 0 8 0;0,2=61,4=0
P 5.52086998 2.09988002 55 P 0 8 0;0,2=61,4=0
P 5.45 2.089 36 P 0 8 0;0,2=1,4=0
P 5.7 2.109 36 P 0 8 0;0,2=1,4=0
P 5.62913002 2.09988002 55 P 0 8 0;0,2=61,4=0
P 5.62913002 2.12153996 55 P 0 8 0;0,2=61,4=0
P 5.62913002 2.14318996 55 P 0 8 0;0,2=61,4=0
P 6.51581998 2.07086998 74 P 0 8 0;0,2=63,4=0
P 6.51581998 2.14961004 74 P 0 8 0;0,2=63,4=0
P 6.289 1.97073996 36 P 0 8 0;0,2=1,4=0
P 6.225 1.97073996 63 P 0 8 0;0,2=14,4=0
P 5.51 2.35043002 26 P 0 8 0;0,2=9,4=0
P 5.555 2.366 36 P 0 8 0;0,2=1,4=0
P 5.89953002 2.28401998 39 P 0 8 0;0,2=1,4=0
P 5.162 2.521 47 P 0 8 0;0,2=14,4=0
P 3.546 2.513 36 P 0 8 0;0,2=1,4=0
P 4.74 2.5415 7 P 0 8 0;0,2=44,4=0
P 3.285 2.553 36 P 0 8 0;0,2=1,4=0
P 3.38483996 2.553 36 P 0 8 0;0,2=1,4=0
P 3.435 2.553 36 P 0 8 0;0,2=1,4=0
P 3.2815 3.40456998 68 P 0 8 0;0,2=5,4=0
P 3.159 2.524 39 P 0 8 0;0,2=1,4=0
P 3.159 2.479 39 P 0 8 0;0,2=1,4=0
P 4.926 1.72 39 P 0 8 0;0,2=1,4=0
P 4.926 1.675 39 P 0 8 0;0,2=1,4=0
P 4.566 2.895 39 P 0 8 0;0,2=1,4=0
P 4.566 2.945 39 P 0 8 0;0,2=1,4=0
P 0.50356998 1 12 P 0 8 0;0,2=9,4=0
P 1.03441998 3.578 19 P 0 8 0;0,2=11,4=0
P 5.46443002 3.967 39 P 0 8 0;0,2=1,4=0
P 5.762 3.517 39 P 0 8 0;0,2=1,4=0
P 5.762 3.567 39 P 0 8 0;0,2=1,4=0
P 4.2391 3.992 60 P 0 8 0;0,2=0,4=0
P 5.96046998 2.04418002 15 P 0 8 0;0,2=15,4=0
P 5.91901998 1.95065 36 P 0 8 0;0,2=1,4=0
P 6.01953002 2.04418002 15 P 0 8 0;0,2=15,4=0
P 6.06901998 1.95065 36 P 0 8 0;0,2=1,4=0
P 3.119 1.895 39 P 0 8 0;0,2=1,4=0
P 2.92733996 1.929 72 P 0 8 0;0,2=58,4=0
P 3.119 1.85 39 P 0 8 0;0,2=1,4=0
P 2.92733996 1.90931998 72 P 0 8 0;0,2=58,4=0
P 4.926 1.975 39 P 0 8 0;0,2=1,4=0
P 4.926 2.025 39 P 0 8 0;0,2=1,4=0
P 3.123 1.8 39 P 0 8 0;0,2=1,4=0
P 2.76986004 1.77151998 72 P 0 8 0;0,2=58,4=0
P 3.123 1.75 39 P 0 8 0;0,2=1,4=0
P 2.76986004 1.75183996 72 P 0 8 0;0,2=58,4=0
P 3.168 2.11 39 P 0 8 0;0,2=1,4=0
P 2.76986004 1.929 72 P 0 8 0;0,2=58,4=0
P 3.168 2.06 39 P 0 8 0;0,2=1,4=0
P 2.76986004 1.90931998 72 P 0 8 0;0,2=58,4=0
P 2.76986004 1.88963002 72 P 0 8 0;0,2=58,4=0
P 3.168 2.015 39 P 0 8 0;0,2=1,4=0
P 2.76986004 1.86995 72 P 0 8 0;0,2=58,4=0
P 3.168 1.965 39 P 0 8 0;0,2=1,4=0
P 4.926 1.63 39 P 0 8 0;0,2=1,4=0
P 0.68448002 2.664 39 P 0 8 0;0,2=1,4=0
P 0.75896998 2.661 24 P 0 8 0;0,2=35,4=0
P 0.714 2.79 39 P 0 8 0;0,2=1,4=0
P 0.77963996 2.69151004 11 P 0 8 0;0,2=39,4=0
P 3.201 2.389 39 P 0 8 0;0,2=1,4=0
P 3.201 2.299 39 P 0 8 0;0,2=1,4=0
P 3.201 2.344 39 P 0 8 0;0,2=1,4=0
P 3.32848002 2.30416004 38 P 0 8 0;0,2=36,4=0
P 3.201 2.254 39 P 0 8 0;0,2=1,4=0
P 3.32848002 2.2451 38 P 0 8 0;0,2=36,4=0
P 3.335 2.511 36 P 0 8 0;0,2=1,4=0
P 3.38016004 2.40503996 9 P 0 8 0;0,2=37,4=0
P 2.637 0.655 39 P 0 8 0;0,2=1,4=0
P 2.754 0.605 46 P 0 8 0;0,2=45,4=0
P 2.637 0.605 39 P 0 8 0;0,2=1,4=0
P 4.8855 0.8428 68 P 0 8 0;0,2=5,4=0
P 4.8855 0.76601998 68 P 0 8 0;0,2=5,4=0
P 4.40343002 1.84343002 3 P 0 8 0;0,2=3,4=0
P 3.58206998 1.89186998 45 P 0 8 0;0,2=42,4=0
P 4.4428 1.84343002 3 P 0 8 0;0,2=3,4=0
P 3.58206998 1.90761998 45 P 0 8 0;0,2=42,4=0
P 3.124 1.695 39 P 0 8 0;0,2=1,4=0
P 2.92733996 1.75183996 72 P 0 8 0;0,2=58,4=0
P 2.2628 3.245 36 P 0 8 0;0,2=1,4=0
P 3.2815 3.3022 68 P 0 8 0;0,2=5,4=0
P 5.914 1.125 39 P 0 8 0;0,2=1,4=0
P 5.914 1.08 39 P 0 8 0;0,2=1,4=0
P 6.0845 1.0578 67 P 0 8 0;0,2=30,4=0
P 2.1478 3.2655 29 P 0 8 0;0,2=30,4=0
P 3.2815 3.3278 68 P 0 8 0;0,2=5,4=0
P 5.956 1.025 39 P 0 8 0;0,2=1,4=0
P 5.43503996 4.21653996 6 P 0 8 0;0,2=25,4=0
P 4.00973002 1.8828 3 P 0 8 0;0,2=3,4=0
P 5.55315 4.21653996 6 P 0 8 0;0,2=25,4=0
P 4.00973002 1.84343002 3 P 0 8 0;0,2=3,4=0
P 5.67126004 4.21653996 6 P 0 8 0;0,2=25,4=0
P 3.97035 1.80406004 3 P 0 8 0;0,2=3,4=0
P 5.78936998 4.21653996 6 P 0 8 0;0,2=25,4=0
P 3.93098002 1.80406004 3 P 0 8 0;0,2=3,4=0
P 4.12783996 2.11901998 3 P 0 8 0;0,2=3,4=0
P 4.63965 1.64658002 3 P 0 8 0;0,2=3,4=0
P 4.12783996 2.15838996 3 P 0 8 0;0,2=3,4=0
P 4.0491 2.11901998 3 P 0 8 0;0,2=3,4=0
P 4.63965 1.56783996 3 P 0 8 0;0,2=3,4=0
P 4.00973002 2.11901998 3 P 0 8 0;0,2=3,4=0
P 4.67901998 1.60721004 3 P 0 8 0;0,2=3,4=0
P 4.0491 2.15838996 3 P 0 8 0;0,2=3,4=0
P 4.00973002 2.15838996 3 P 0 8 0;0,2=3,4=0
P 3.93098002 2.11901998 3 P 0 8 0;0,2=3,4=0
P 4.56091004 1.60721004 3 P 0 8 0;0,2=3,4=0
P 3.89161004 2.11901998 3 P 0 8 0;0,2=3,4=0
P 4.71838996 1.56783996 3 P 0 8 0;0,2=3,4=0
P 3.97035 2.15838996 3 P 0 8 0;0,2=3,4=0
P 4.71838996 1.52846998 3 P 0 8 0;0,2=3,4=0
P 3.93098002 2.15838996 3 P 0 8 0;0,2=3,4=0
P 0.8338 2.4275 29 P 0 8 0;0,2=30,4=0
P 3.0425 3.40456998 68 P 0 8 0;0,2=5,4=0
P 0.8082 2.4275 29 P 0 8 0;0,2=30,4=0
P 3.0425 3.37898002 68 P 0 8 0;0,2=5,4=0
P 4.985 3.546 36 P 0 8 0;0,2=1,4=0
P 4.91548996 3.82953002 75 P 0 8 0;0,2=13,4=0
P 4.935 3.546 36 P 0 8 0;0,2=1,4=0
P 4.885 3.546 36 P 0 8 0;0,2=1,4=0
P 4.91548996 3.75078996 75 P 0 8 0;0,2=13,4=0
P 4.785 3.546 36 P 0 8 0;0,2=1,4=0
P 4.735 3.546 36 P 0 8 0;0,2=1,4=0
P 4.78656004 3.82953002 75 P 0 8 0;0,2=13,4=0
P 4.91548996 3.67205 75 P 0 8 0;0,2=13,4=0
P 4.835 3.546 36 P 0 8 0;0,2=1,4=0
P 4.78656004 3.75078996 75 P 0 8 0;0,2=13,4=0
P 4.48216998 1.80406004 3 P 0 8 0;0,2=3,4=0
P 4.4428 1.80406004 3 P 0 8 0;0,2=3,4=0
P 4.56091004 1.76468996 3 P 0 8 0;0,2=3,4=0
P 5.1245 0.74043002 68 P 0 8 0;0,2=5,4=0
P 1.3505 0.613 39 P 0 8 0;0,2=1,4=0
P 5.1245 0.8172 68 P 0 8 0;0,2=5,4=0
P 1.3507 0.708 39 P 0 8 0;0,2=1,4=0
P 4.00973002 1.64658002 3 P 0 8 0;0,2=3,4=0
P 3.97035 1.64658002 3 P 0 8 0;0,2=3,4=0
P 3.93098002 1.68595 3 P 0 8 0;0,2=3,4=0
P 3.89161004 1.68595 3 P 0 8 0;0,2=3,4=0
P 4.00973002 1.72531998 3 P 0 8 0;0,2=3,4=0
P 3.97035 1.72531998 3 P 0 8 0;0,2=3,4=0
P 3.93098002 1.60721004 3 P 0 8 0;0,2=3,4=0
P 3.89161004 1.60721004 3 P 0 8 0;0,2=3,4=0
P 4.00973002 1.56783996 3 P 0 8 0;0,2=3,4=0
P 3.97035 1.56783996 3 P 0 8 0;0,2=3,4=0
P 3.93098002 1.52846998 3 P 0 8 0;0,2=3,4=0
P 3.89161004 1.52846998 3 P 0 8 0;0,2=3,4=0
P 4.00973002 1.4891 3 P 0 8 0;0,2=3,4=0
P 3.97035 1.4891 3 P 0 8 0;0,2=3,4=0
P 3.93098002 1.44973002 3 P 0 8 0;0,2=3,4=0
P 3.89161004 1.44973002 3 P 0 8 0;0,2=3,4=0
P 2.51121998 0.626 36 P 0 8 0;0,2=1,4=0
P 3.0425 3.35338996 68 P 0 8 0;0,2=5,4=0
P 3.0425 3.3278 68 P 0 8 0;0,2=5,4=0
P 2.848 0.57941004 46 P 0 8 0;0,2=45,4=0
P 2.954 0.57441004 39 P 0 8 0;0,2=1,4=0
P 4.926 2.07 39 P 0 8 0;0,2=1,4=0
P 6.4105 2.13583002 62 P 0 8 0;0,2=43,4=0
P 0.7574 3.3935 32 P 0 8 0;0,2=4,4=0
P 0.6826 3.3935 32 P 0 8 0;0,2=4,4=0
P 6.23248996 2.31483996 32 P 0 8 0;0,2=4,4=0
P 6.30728996 2.31483996 32 P 0 8 0;0,2=4,4=0
P 3.55188996 1.94555 78 P 0 8 0;0,2=54,4=0
P 3.53613996 1.94555 78 P 0 8 0;0,2=54,4=0
P 2.754 0.63058996 46 P 0 8 0;0,2=45,4=0
P 3.98 0.75216998 65 P 0 8 0;0,2=8,4=0
P 4.364 0.82366004 37 P 0 8 0;0,2=7,4=0
P 5.68466998 0.679 51 P 0 8 0;0,2=15,4=0
P 5.04833002 2.707 51 P 0 8 0;0,2=15,4=0
P 3.912 3.00466998 15 P 0 8 0;0,2=15,4=0
P 2.92733996 1.77151998 72 P 0 8 0;0,2=58,4=0
P 2.92733996 1.79121004 72 P 0 8 0;0,2=58,4=0
P 2.92733996 1.81088996 72 P 0 8 0;0,2=58,4=0
P 2.76986004 1.81088996 72 P 0 8 0;0,2=58,4=0
P 2.92733996 1.83058002 72 P 0 8 0;0,2=58,4=0
P 2.76986004 1.83058002 72 P 0 8 0;0,2=58,4=0
P 2.92733996 1.85026004 72 P 0 8 0;0,2=58,4=0
P 3.45151998 2.30416004 38 P 0 8 0;0,2=36,4=0
P 3.45151998 2.28446998 38 P 0 8 0;0,2=36,4=0
P 3.45151998 2.26478996 38 P 0 8 0;0,2=36,4=0
P 3.45151998 2.2451 38 P 0 8 0;0,2=36,4=0
P 3.32848002 2.26478996 38 P 0 8 0;0,2=36,4=0
P 3.32848002 2.28446998 38 P 0 8 0;0,2=36,4=0
P 3.32848002 2.36321004 38 P 0 8 0;0,2=36,4=0
P 3.32848002 2.3829 38 P 0 8 0;0,2=36,4=0
P 3.45151998 2.40258002 38 P 0 8 0;0,2=36,4=0
P 4.20306004 3.8954 17 P 0 8 0;0,2=34,4=0
P 4.18336998 3.8969 18 P 0 8 0;0,2=33,4=0
P 4.16368996 3.8969 18 P 0 8 0;0,2=33,4=0
P 4.20058996 3.4824 28 P 0 8 0;0,2=6,4=0
P 4.00558996 3.4804 28 P 0 8 0;0,2=6,4=0
P 1.73966998 3.015 51 P 0 8 0;0,2=15,4=0
P 1.03441998 3.12 19 P 0 8 0;0,2=11,4=0
P 1.352 3.4179 70 P 0 8 0;0,2=11,4=0
P 1.352 3.39821004 70 P 0 8 0;0,2=11,4=0
P 1.352 3.37853002 70 P 0 8 0;0,2=11,4=0
P 1.352 3.35883996 70 P 0 8 0;0,2=11,4=0
P 1.352 3.31946998 70 P 0 8 0;0,2=11,4=0
P 1.352 3.29978996 70 P 0 8 0;0,2=11,4=0
P 1.352 3.2801 70 P 0 8 0;0,2=11,4=0
P 1.23126998 3.12 19 P 0 8 0;0,2=11,4=0
P 1.21158002 3.12 19 P 0 8 0;0,2=11,4=0
P 1.1919 3.12 19 P 0 8 0;0,2=11,4=0
P 1.17221004 3.12 19 P 0 8 0;0,2=11,4=0
P 1.13283996 3.12 19 P 0 8 0;0,2=11,4=0
P 1.11316004 3.12 19 P 0 8 0;0,2=11,4=0
L 3.8089999 -1.31933563 3.817 -1.32600089 1 P 0 ;1,3=64,5=0.000000
L 3.817 -1.32600089 3.8259999 -1.33 1 P 0 ;1,3=64,5=0.000000
L 3.8259999 -1.33 3.834 -1.33 1 P 0 ;1,3=64,5=0.000000
L 3.834 -1.33 3.8420001 -1.32600089 1 P 0 ;1,3=64,5=0.000000
L 3.8420001 -1.32600089 3.84800069 -1.31933563 1 P 0 ;1,3=64,5=0.000000
L 3.84800069 -1.31933563 3.851 -1.30999941 1 P 0 ;1,3=64,5=0.000000
L 3.851 -1.30999941 3.84900049 -1.30066811 1 P 0 ;1,3=64,5=0.000000
L 3.84900049 -1.30066811 3.8439997 -1.29266732 1 P 0 ;1,3=64,5=0.000000
L 3.8439997 -1.29266732 3.8349998 -1.28733278 1 P 0 ;1,3=64,5=0.000000
L 3.8349998 -1.28733278 3.82300049 -1.28466663 1 P 0 ;1,3=64,5=0.000000
L 3.82300049 -1.28466663 3.8160002 -1.27933445 1 P 0 ;1,3=64,5=0.000000
L 3.8160002 -1.27933445 3.81299902 -1.27000069 1 P 0 ;1,3=64,5=0.000000
L 3.81299902 -1.27000069 3.81500039 -1.26066683 1 P 0 ;1,3=64,5=0.000000
L 3.81500039 -1.26066683 3.81999931 -1.25400167 1 P 0 ;1,3=64,5=0.000000
L 3.81999931 -1.25400167 3.8269997 -1.25 1 P 0 ;1,3=64,5=0.000000
L 3.8269997 -1.25 3.834 -1.25 1 P 0 ;1,3=64,5=0.000000
L 3.834 -1.25 3.84100039 -1.25266614 1 P 0 ;1,3=64,5=0.000000
L 3.84100039 -1.25266614 3.84700089 -1.25933386 1 P 0 ;1,3=64,5=0.000000
L 3.90999902 -1.33 3.90199892 -1.32866703 1 P 0 ;1,3=64,5=0.000000
L 3.90199892 -1.32866703 3.89500039 -1.32333484 1 P 0 ;1,3=64,5=0.000000
L 3.89500039 -1.32333484 3.8889999 -1.31533406 1 P 0 ;1,3=64,5=0.000000
L 3.8889999 -1.31533406 3.88499892 -1.3060003 1 P 0 ;1,3=64,5=0.000000
L 3.88499892 -1.3060003 3.88299931 -1.29533346 1 P 0 ;1,3=64,5=0.000000
L 3.88299931 -1.29533346 3.88299931 -1.28466663 1 P 0 ;1,3=64,5=0.000000
L 3.88299931 -1.28466663 3.88499892 -1.2739998 1 P 0 ;1,3=64,5=0.000000
L 3.88499892 -1.2739998 3.8889999 -1.26466604 1 P 0 ;1,3=64,5=0.000000
L 3.8889999 -1.26466604 3.89500039 -1.25666772 1 P 0 ;1,3=64,5=0.000000
L 3.89500039 -1.25666772 3.90199892 -1.25133307 1 P 0 ;1,3=64,5=0.000000
L 3.90199892 -1.25133307 3.90999902 -1.25 1 P 0 ;1,3=64,5=0.000000
L 3.90999902 -1.25 3.91799911 -1.25133307 1 P 0 ;1,3=64,5=0.000000
L 3.91799911 -1.25133307 3.92499951 -1.25666772 1 P 0 ;1,3=64,5=0.000000
L 3.92499951 -1.25666772 3.931 -1.26466604 1 P 0 ;1,3=64,5=0.000000
L 3.931 -1.26466604 3.93500098 -1.2739998 1 P 0 ;1,3=64,5=0.000000
L 3.93500098 -1.2739998 3.93700059 -1.28466663 1 P 0 ;1,3=64,5=0.000000
L 3.93700059 -1.28466663 3.93700059 -1.29533346 1 P 0 ;1,3=64,5=0.000000
L 3.93700059 -1.29533346 3.93500098 -1.3060003 1 P 0 ;1,3=64,5=0.000000
L 3.93500098 -1.3060003 3.931 -1.31533406 1 P 0 ;1,3=64,5=0.000000
L 3.931 -1.31533406 3.92499951 -1.32333484 1 P 0 ;1,3=64,5=0.000000
L 3.92499951 -1.32333484 3.91799911 -1.32866703 1 P 0 ;1,3=64,5=0.000000
L 3.91799911 -1.32866703 3.90999902 -1.33 1 P 0 ;1,3=64,5=0.000000
L 3.96999961 -1.25 3.96999961 -1.33 1 P 0 ;1,3=64,5=0.000000
L 3.96999961 -1.33 4.0100003 -1.33 1 P 0 ;1,3=64,5=0.000000
L 4.0480001 -1.33 4.0480001 -1.25 1 P 0 ;1,3=64,5=0.000000
L 4.0480001 -1.25 4.06799951 -1.25 1 P 0 ;1,3=64,5=0.000000
L 4.06799951 -1.25 4.07599961 -1.25400167 1 P 0 ;1,3=64,5=0.000000
L 4.07599961 -1.25400167 4.0820001 -1.25933386 1 P 0 ;1,3=64,5=0.000000
L 4.0820001 -1.25933386 4.08700089 -1.26733209 1 P 0 ;1,3=64,5=0.000000
L 4.08700089 -1.26733209 4.091 -1.27666831 1 P 0 ;1,3=64,5=0.000000
L 4.091 -1.27666831 4.0919998 -1.29000128 1 P 0 ;1,3=64,5=0.000000
L 4.0919998 -1.29000128 4.091 -1.30333415 1 P 0 ;1,3=64,5=0.000000
L 4.091 -1.30333415 4.08700089 -1.31266801 1 P 0 ;1,3=64,5=0.000000
L 4.08700089 -1.31266801 4.0820001 -1.3206687 1 P 0 ;1,3=64,5=0.000000
L 4.0820001 -1.3206687 4.07599961 -1.32600089 1 P 0 ;1,3=64,5=0.000000
L 4.07599961 -1.32600089 4.06799951 -1.33 1 P 0 ;1,3=64,5=0.000000
L 4.06799951 -1.33 4.0480001 -1.33 1 P 0 ;1,3=64,5=0.000000
L 4.1700003 -1.33 4.12999961 -1.33 1 P 0 ;1,3=64,5=0.000000
L 4.12999961 -1.33 4.12999961 -1.25 1 P 0 ;1,3=64,5=0.000000
L 4.12999961 -1.25 4.1700003 -1.25 1 P 0 ;1,3=64,5=0.000000
L 4.154 -1.28866575 4.12999961 -1.28866575 1 P 0 ;1,3=64,5=0.000000
L 4.20999961 -1.33 4.20999961 -1.25 1 P 0 ;1,3=64,5=0.000000
L 4.20999961 -1.25 4.2349998 -1.25 1 P 0 ;1,3=64,5=0.000000
L 4.2349998 -1.25 4.2429999 -1.25400167 1 P 0 ;1,3=64,5=0.000000
L 4.2429999 -1.25400167 4.24800069 -1.25933386 1 P 0 ;1,3=64,5=0.000000
L 4.24800069 -1.25933386 4.2500003 -1.27000069 1 P 0 ;1,3=64,5=0.000000
L 4.2500003 -1.27000069 4.24800069 -1.28066752 1 P 0 ;1,3=64,5=0.000000
L 4.24800069 -1.28066752 4.2420001 -1.28733278 1 P 0 ;1,3=64,5=0.000000
L 4.2420001 -1.28733278 4.2349998 -1.29133435 1 P 0 ;1,3=64,5=0.000000
L 4.2349998 -1.29133435 4.20999961 -1.29133435 1 P 0 ;1,3=64,5=0.000000
L 4.2349998 -1.29133435 4.2500003 -1.33 1 P 0 ;1,3=64,5=0.000000
L 4.28999961 -1.33 4.28999961 -1.25 1 P 0 ;1,3=64,5=0.000000
L 4.28999961 -1.25 4.314 -1.25 1 P 0 ;1,3=64,5=0.000000
L 4.314 -1.25 4.3220001 -1.25400167 1 P 0 ;1,3=64,5=0.000000
L 4.3220001 -1.25400167 4.32800069 -1.26333297 1 P 0 ;1,3=64,5=0.000000
L 4.32800069 -1.26333297 4.3300003 -1.2739998 1 P 0 ;1,3=64,5=0.000000
L 4.3300003 -1.2739998 4.32800069 -1.28466663 1 P 0 ;1,3=64,5=0.000000
L 4.32800069 -1.28466663 4.3229999 -1.29266732 1 P 0 ;1,3=64,5=0.000000
L 4.3229999 -1.29266732 4.314 -1.296669 1 P 0 ;1,3=64,5=0.000000
L 4.314 -1.296669 4.28999961 -1.296669 1 P 0 ;1,3=64,5=0.000000
L 4.36499892 -1.33 4.38999902 -1.25 1 P 0 ;1,3=64,5=0.000000
L 4.38999902 -1.25 4.41500098 -1.33 1 P 0 ;1,3=64,5=0.000000
L 4.40599931 -1.30200118 4.37399882 -1.30200118 1 P 0 ;1,3=64,5=0.000000
L 4.4489999 -1.31933563 4.457 -1.32600089 1 P 0 ;1,3=64,5=0.000000
L 4.457 -1.32600089 4.4659999 -1.33 1 P 0 ;1,3=64,5=0.000000
L 4.4659999 -1.33 4.474 -1.33 1 P 0 ;1,3=64,5=0.000000
L 4.474 -1.33 4.4820001 -1.32600089 1 P 0 ;1,3=64,5=0.000000
L 4.4820001 -1.32600089 4.48800069 -1.31933563 1 P 0 ;1,3=64,5=0.000000
L 4.48800069 -1.31933563 4.491 -1.30999941 1 P 0 ;1,3=64,5=0.000000
L 4.491 -1.30999941 4.48900049 -1.30066811 1 P 0 ;1,3=64,5=0.000000
L 4.48900049 -1.30066811 4.4839997 -1.29266732 1 P 0 ;1,3=64,5=0.000000
L 4.4839997 -1.29266732 4.4749998 -1.28733278 1 P 0 ;1,3=64,5=0.000000
L 4.4749998 -1.28733278 4.46300049 -1.28466663 1 P 0 ;1,3=64,5=0.000000
L 4.46300049 -1.28466663 4.4560002 -1.27933445 1 P 0 ;1,3=64,5=0.000000
L 4.4560002 -1.27933445 4.45299902 -1.27000069 1 P 0 ;1,3=64,5=0.000000
L 4.45299902 -1.27000069 4.45500039 -1.26066683 1 P 0 ;1,3=64,5=0.000000
L 4.45500039 -1.26066683 4.45999931 -1.25400167 1 P 0 ;1,3=64,5=0.000000
L 4.45999931 -1.25400167 4.4669997 -1.25 1 P 0 ;1,3=64,5=0.000000
L 4.4669997 -1.25 4.474 -1.25 1 P 0 ;1,3=64,5=0.000000
L 4.474 -1.25 4.48100039 -1.25266614 1 P 0 ;1,3=64,5=0.000000
L 4.48100039 -1.25266614 4.48700089 -1.25933386 1 P 0 ;1,3=64,5=0.000000
L 4.54999902 -1.25 4.54999902 -1.33 1 P 0 ;1,3=64,5=0.000000
L 4.5270003 -1.25 4.57299961 -1.25 1 P 0 ;1,3=64,5=0.000000
L 4.6500003 -1.33 4.60999961 -1.33 1 P 0 ;1,3=64,5=0.000000
L 4.60999961 -1.33 4.60999961 -1.25 1 P 0 ;1,3=64,5=0.000000
L 4.60999961 -1.25 4.6500003 -1.25 1 P 0 ;1,3=64,5=0.000000
L 4.634 -1.28866575 4.60999961 -1.28866575 1 P 0 ;1,3=64,5=0.000000
L 4.68 -1.35666585 4.74 -1.35666585 1 P 0 ;1,3=64,5=0.000000
L 4.78999902 -1.25 4.78999902 -1.33 1 P 0 ;1,3=64,5=0.000000
L 4.7670003 -1.25 4.81299961 -1.25 1 P 0 ;1,3=64,5=0.000000
L 4.86999902 -1.33 4.86199892 -1.32866703 1 P 0 ;1,3=64,5=0.000000
L 4.86199892 -1.32866703 4.85500039 -1.32333484 1 P 0 ;1,3=64,5=0.000000
L 4.85500039 -1.32333484 4.8489999 -1.31533406 1 P 0 ;1,3=64,5=0.000000
L 4.8489999 -1.31533406 4.84499892 -1.3060003 1 P 0 ;1,3=64,5=0.000000
L 4.84499892 -1.3060003 4.84299931 -1.29533346 1 P 0 ;1,3=64,5=0.000000
L 4.84299931 -1.29533346 4.84299931 -1.28466663 1 P 0 ;1,3=64,5=0.000000
L 4.84299931 -1.28466663 4.84499892 -1.2739998 1 P 0 ;1,3=64,5=0.000000
L 4.84499892 -1.2739998 4.8489999 -1.26466604 1 P 0 ;1,3=64,5=0.000000
L 4.8489999 -1.26466604 4.85500039 -1.25666772 1 P 0 ;1,3=64,5=0.000000
L 4.85500039 -1.25666772 4.86199892 -1.25133307 1 P 0 ;1,3=64,5=0.000000
L 4.86199892 -1.25133307 4.86999902 -1.25 1 P 0 ;1,3=64,5=0.000000
L 4.86999902 -1.25 4.87799911 -1.25133307 1 P 0 ;1,3=64,5=0.000000
L 4.87799911 -1.25133307 4.88499951 -1.25666772 1 P 0 ;1,3=64,5=0.000000
L 4.88499951 -1.25666772 4.891 -1.26466604 1 P 0 ;1,3=64,5=0.000000
L 4.891 -1.26466604 4.89500098 -1.2739998 1 P 0 ;1,3=64,5=0.000000
L 4.89500098 -1.2739998 4.89700059 -1.28466663 1 P 0 ;1,3=64,5=0.000000
L 4.89700059 -1.28466663 4.89700059 -1.29533346 1 P 0 ;1,3=64,5=0.000000
L 4.89700059 -1.29533346 4.89500098 -1.3060003 1 P 0 ;1,3=64,5=0.000000
L 4.89500098 -1.3060003 4.891 -1.31533406 1 P 0 ;1,3=64,5=0.000000
L 4.891 -1.31533406 4.88499951 -1.32333484 1 P 0 ;1,3=64,5=0.000000
L 4.88499951 -1.32333484 4.87799911 -1.32866703 1 P 0 ;1,3=64,5=0.000000
L 4.87799911 -1.32866703 4.86999902 -1.33 1 P 0 ;1,3=64,5=0.000000
L 4.92999961 -1.33 4.92999961 -1.25 1 P 0 ;1,3=64,5=0.000000
L 4.92999961 -1.25 4.954 -1.25 1 P 0 ;1,3=64,5=0.000000
L 4.954 -1.25 4.9620001 -1.25400167 1 P 0 ;1,3=64,5=0.000000
L 4.9620001 -1.25400167 4.96800069 -1.26333297 1 P 0 ;1,3=64,5=0.000000
L 4.96800069 -1.26333297 4.9700003 -1.2739998 1 P 0 ;1,3=64,5=0.000000
L 4.9700003 -1.2739998 4.96800069 -1.28466663 1 P 0 ;1,3=64,5=0.000000
L 4.96800069 -1.28466663 4.9629999 -1.29266732 1 P 0 ;1,3=64,5=0.000000
L 4.9629999 -1.29266732 4.954 -1.296669 1 P 0 ;1,3=64,5=0.000000
L 4.954 -1.296669 4.92999961 -1.296669 1 P 0 ;1,3=64,5=0.000000
S P 0
OB 0.4707 3.4315 I
OC 0.4707 3.4315 0.4587 3.4315 Y
OE
SE
S P 0
OB 0.452980019685 3.4008 I
OC 0.452980019685 3.4008 0.440980019685 3.4008 Y
OE
SE
S P 0
OB 0.41753996063 3.4008 I
OC 0.41753996063 3.4008 0.40553996063 3.4008 Y
OE
SE
S P 0
OB 0.43526003937 3.4315 I
OC 0.43526003937 3.4315 0.42326003937 3.4315 Y
OE
SE
S P 0
OB 0.399819980315 3.4315 I
OC 0.399819980315 3.4315 0.387819980315 3.4315 Y
OE
SE
S P 0
OB 0.3821 3.4008 I
OC 0.3821 3.4008 0.3701 3.4008 Y
OE
SE
S P 0
OB 0.364380019685 3.4315 I
OC 0.364380019685 3.4315 0.352380019685 3.4315 Y
OE
SE
S P 0
OB 0.34666003937 3.4008 I
OC 0.34666003937 3.4008 0.33466003937 3.4008 Y
OE
SE
S P 0
OB 0.32893996063 3.4315 I
OC 0.32893996063 3.4315 0.31693996063 3.4315 Y
OE
SE
S P 0
OB 0.311219980315 3.4008 I
OC 0.311219980315 3.4008 0.299219980315 3.4008 Y
OE
SE
S P 0
OB 0.2935 3.4315 I
OC 0.2935 3.4315 0.2815 3.4315 Y
OE
SE
S P 0
OB 0.275780019685 3.4008 I
OC 0.275780019685 3.4008 0.263780019685 3.4008 Y
OE
SE
S P 0
OB 0.25806003937 3.4315 I
OC 0.25806003937 3.4315 0.24606003937 3.4315 Y
OE
SE
S P 0
OB 0.24033996063 3.4008 I
OC 0.24033996063 3.4008 0.22833996063 3.4008 Y
OE
SE
S P 0
OB 0.41705 3.49826003937 I
OC 0.41705 3.53326003937 0.41705 3.51576003937 Y
OS 0.45705 3.53326003937
OC 0.45705 3.49826003937 0.45705 3.51576003937 Y
OS 0.41705 3.49826003937
OE
SE
S P 0
OB 0.41705 3.29905 I
OC 0.41705 3.33405 0.41705 3.31655 Y
OS 0.45705 3.33405
OC 0.45705 3.29905 0.45705 3.31655 Y
OS 0.41705 3.29905
OE
SE
S P 0
OB 0.228069980315 3.34235 I
OC 0.228069980315 3.37735 0.228069980315 3.35985 Y
OS 0.268069980315 3.37735
OC 0.268069980315 3.34235 0.268069980315 3.35985 Y
OS 0.228069980315 3.34235
OE
SE
S P 0
OB 0.228069980315 3.45495 I
OC 0.228069980315 3.48995 0.228069980315 3.47245 Y
OS 0.268069980315 3.48995
OC 0.268069980315 3.45495 0.268069980315 3.47245 Y
OS 0.228069980315 3.45495
OE
SE
L 3.16 -0.655 3.16 -1.58 2 P 0 
L 1.36 -0.655 1.36 -1.58 2 P 0 
L 1.36 -1.58 5.06 -1.58 2 P 0 
L 5.06 -1.58 5.06 -0.655 2 P 0 
L 5.06 -0.655 1.36 -0.655 2 P 0 
A 1.559 -1.33655 1.559 -1.33655 1.55268002 -1.33655 1 P 0 N
A 1.54775 -1.205 1.54775 -1.205 1.53883002 -1.205 1 P 0 N
A 1.54763996 -0.99775 1.54763996 -0.99775 1.53871998 -0.99775 1 P 0 N
A 1.54063996 -1.10118002 1.54063996 -1.10118002 1.52603996 -1.10118002 1 P 0 N
A 1.49695 -1.10118002 1.49695 -1.10118002 1.48656998 -1.10118002 1 P 0 N
A 1.45963996 -1.10118002 1.45963996 -1.10118002 1.4533 -1.10118002 1 P 0 N
A 1.52135 -0.98681004 1.52135 -0.98681004 1.51503002 -0.98681004 1 P 0 N
A 1.79433002 -1.43586998 1.79433002 -1.43586998 1.78798996 -1.43586998 1 P 0 N
A 1.79841004 -1.40261004 1.79841004 -1.40261004 1.78798996 -1.40261004 1 P 0 N
A 1.80255 -1.36311004 1.80255 -1.36311004 1.78798996 -1.36311004 1 P 0 N
A 1.80668996 -1.31528002 1.80668996 -1.31528002 1.78798996 -1.31528002 1 P 0 N
A 1.68013002 -1.37456004 1.68013002 -1.37456004 1.67378996 -1.37456004 1 P 0 N
A 1.69321998 -1.35033002 1.69321998 -1.35033002 1.6843 -1.35033002 1 P 0 N
A 1.7108 -1.31738996 1.7108 -1.31738996 1.69798002 -1.31738996 1 P 0 N
A 1.89666998 -1.31511004 1.89666998 -1.31511004 1.88383996 -1.31511004 1 P 0 N
A 1.88198996 -1.16876004 1.88198996 -1.16876004 1.85558996 -1.16876004 1 P 0 N
A 1.87928002 -1.27801998 1.87928002 -1.27801998 1.86343996 -1.27801998 1 P 0 N
A 1.86176998 -1.23075 1.86176998 -1.23075 1.84206004 -1.23075 1 P 0 N
A 1.80978996 -1.25916998 1.80978996 -1.25916998 1.78798996 -1.25916998 1 P 0 N
A 1.74681004 -1.16876004 1.74681004 -1.16876004 1.72041004 -1.16876004 1 P 0 N
A 1.67813002 -1.15513002 1.67813002 -1.15513002 1.65841998 -1.15513002 1 P 0 N
A 1.73018002 -1.27816004 1.73018002 -1.27816004 1.71433996 -1.27816004 1 P 0 N
A 1.75373002 -1.23081004 1.75373002 -1.23081004 1.73405 -1.23081004 1 P 0 N
A 1.65531004 -1.25255 1.65531004 -1.25255 1.63661998 -1.25255 1 P 0 N
A 1.69808996 -1.21291998 1.69808996 -1.21291998 1.67628996 -1.21291998 1 P 0 N
A 1.81438996 -1.1968 1.81438996 -1.1968 1.78798996 -1.1968 1 P 0 N
A 1.6269 -1.1749 1.6269 -1.1749 1.61106004 -1.1749 1 P 0 N
A 1.58461004 -1.19126004 1.58461004 -1.19126004 1.57178002 -1.19126004 1 P 0 N
A 1.5853 -1.31428002 1.5853 -1.31428002 1.57488996 -1.31428002 1 P 0 N
A 1.61735 -1.28638996 1.61735 -1.28638996 1.60276998 -1.28638996 1 P 0 N
A 1.88198996 -1.03361004 1.88198996 -1.03361004 1.85558996 -1.03361004 1 P 0 N
A 1.71881004 -1.10118002 1.71881004 -1.10118002 1.69238996 -1.10118002 1 P 0 N
A 1.65183002 -1.10118002 1.65183002 -1.10118002 1.63003002 -1.10118002 1 P 0 N
A 1.67801998 -1.04738996 1.67801998 -1.04738996 1.65831004 -1.04738996 1 P 0 N
A 1.74681004 -1.03361004 1.74681004 -1.03361004 1.72041004 -1.03361004 1 P 0 N
A 1.69811998 -0.98951004 1.69811998 -0.98951004 1.67631998 -0.98951004 1 P 0 N
A 1.81438996 -1.00556004 1.81438996 -1.00556004 1.78798996 -1.00556004 1 P 0 N
A 1.59258002 -1.10118002 1.59258002 -1.10118002 1.5739 -1.10118002 1 P 0 N
A 1.58451004 -1.01148996 1.58451004 -1.01148996 1.57168002 -1.01148996 1 P 0 N
A 1.62681004 -1.02773996 1.62681004 -1.02773996 1.61096998 -1.02773996 1 P 0 N
A 1.92148002 -1.21285 1.92148002 -1.21285 1.89968002 -1.21285 1 P 0 N
A 1.92148002 -0.98951004 1.92148002 -0.98951004 1.89968002 -0.98951004 1 P 0 N
A 1.80978996 -0.9432 1.80978996 -0.9432 1.78798996 -0.9432 1 P 0 N
A 1.80668996 -0.88708002 1.80668996 -0.88708002 1.78798996 -0.88708002 1 P 0 N
A 1.80255 -0.83923996 1.80255 -0.83923996 1.78798996 -0.83923996 1 P 0 N
A 1.8919 -0.88538002 1.8919 -0.88538002 1.87906998 -0.88538002 1 P 0 N
A 1.87838996 -0.92456998 1.87838996 -0.92456998 1.86255 -0.92456998 1 P 0 N
A 1.65531004 -0.94981004 1.65531004 -0.94981004 1.63661998 -0.94981004 1 P 0 N
A 1.73123002 -0.92378002 1.73123002 -0.92378002 1.71538996 -0.92378002 1 P 0 N
A 1.71216998 -0.88443996 1.71216998 -0.88443996 1.69935 -0.88443996 1 P 0 N
A 1.86225 -0.97178002 1.86225 -0.97178002 1.84253996 -0.97178002 1 P 0 N
A 1.75451998 -0.97123996 1.75451998 -0.97123996 1.73483996 -0.97123996 1 P 0 N
A 1.61741998 -0.91601004 1.61741998 -0.91601004 1.60283996 -0.91601004 1 P 0 N
A 1.5853 -0.88808996 1.5853 -0.88808996 1.57488996 -0.88808996 1 P 0 N
A 1.79841004 -0.79975 1.79841004 -0.79975 1.78798996 -0.79975 1 P 0 N
A 1.79433002 -0.76648002 1.79433002 -0.76648002 1.78798996 -0.76648002 1 P 0 N
A 1.92135 -1.36781004 1.92135 -1.36781004 1.91503996 -1.36781004 1 P 0 N
A 1.91096004 -1.34658002 1.91096004 -1.34658002 1.90203996 -1.34658002 1 P 0 N
A 2.19078996 -1.1806 2.26591004 -1.16473002 2.21741014 -1.12088169 1 P 0 N
A 2.15903002 -1.1402 2.19078996 -1.18061004 2.22093406 -1.12423278 1 P 0 N
A 2.05721004 -1.16178996 2.08853002 -1.16658996 2.08281614 -1.09929134 1 P 0 N
A 2.00546998 -1.13951998 2.03345 -1.17196004 2.07793927 -1.10530069 1 P 0 N
A 2.03346004 -1.17195 2.0847 -1.18461004 2.07891181 -1.09801299 1 P 0 N
A 2.0847 -1.18461998 2.14261004 -1.15663002 2.07348435 -1.08751378 1 P 0 N
A 2.08853996 -1.16658002 2.13313002 -1.14451998 2.06368967 -1.06025512 1 P 0 N
A 1.95808002 -1.25255 1.95808002 -1.25255 1.93938996 -1.25255 1 P 0 N
A 1.98775 -1.28635 1.98775 -1.28635 1.97316998 -1.28635 1 P 0 N
A 2.27411998 -1.11835 2.15906004 -1.11835 2.21658996 -1.11611998 1 P 0 N
L 2.25188002 -1.11418002 2.1807 -1.11418002 1 P 0 
L 2.1807 -1.11418002 2.1807 -1.11398996 1 P 8191 
A 2.25188996 -1.11398996 2.18071004 -1.11398996 2.2163 -1.1124 1 P 0 N
A 2.08028996 -1.03428996 2.02048996 -1.08258996 2.0798126 -1.09486801 1 P 0 N
A 2.13151998 -1.05146004 2.0803 -1.0343 2.0802999 -1.11932195 1 P 0 N
A 2.1315 -1.05146998 2.14175 -1.03951004 2.1356003 -1.04461171 1 P 0 N
A 2.14175 -1.03951004 2.08283002 -1.01613002 2.07772461 -1.11492805 1 P 0 N
A 2.08283996 -1.01611998 2.00698002 -1.05835 2.08064724 -1.10143169 1 P 0 N
L 2.27413002 -1.12868996 2.18073996 -1.12868996 1 P 0 
A 2.18075 -1.12868996 2.19083002 -1.15751998 2.22417795 -1.12968307 1 P 0 N
A 2.19083002 -1.15753002 2.25311004 -1.15211004 2.21927195 -1.12381791 1 P 0 N
L 2.15903996 -1.1402 2.15903996 -1.11835 1 P 0 
A 2.02048996 -1.0826 2.05721998 -1.16181004 2.09087933 -1.0980811 1 P 0 N
A 2.00698996 -1.05836004 2.00546998 -1.13953002 2.09672953 -1.10063967 1 P 0 N
A 2.14258996 -1.15661004 2.13313996 -1.14453002 2.13544892 -1.15246004 1 P 0 N
A 1.95808002 -0.94981004 1.95808002 -0.94981004 1.93938996 -0.94981004 1 P 0 N
A 1.90183996 -0.8525 1.90183996 -0.8525 1.89291004 -0.8525 1 P 0 N
A 1.91108002 -0.82726998 1.91108002 -0.82726998 1.90473996 -0.82726998 1 P 0 N
L 2.32081004 -1.02041004 2.32081004 -1.17625 1 P 0 
A 2.49568002 -1.15528996 2.47898002 -1.16443002 2.4882003 -1.1614502 1 P 0 N
A 2.47896998 -1.16443996 2.50283002 -1.18086004 2.51649242 -1.13546152 1 P 0 N
A 2.50281998 -1.18086998 2.54318002 -1.1834 2.52887392 -1.08843022 1 P 0 N
A 2.52306998 -1.16761004 2.52848996 -1.16771998 2.52673258 -1.12070098 1 P 0 N
A 2.49566004 -1.15528996 2.52306998 -1.1676 2.5255122 -1.12549094 1 P 0 N
A 2.37851998 -1.15753002 2.4408 -1.15211004 2.40696191 -1.12381791 1 P 0 N
A 2.45358002 -1.16471998 2.44078996 -1.1521 2.44541191 -1.16020689 1 P 0 N
A 2.37848002 -1.1806 2.4536 -1.16473002 2.4051001 -1.12088169 1 P 0 N
A 2.34673002 -1.1402 2.37848996 -1.18061004 2.40863406 -1.12423278 1 P 0 N
A 2.2659 -1.16471998 2.25311004 -1.1521 2.25773199 -1.16020689 1 P 0 N
A 2.3006 -1.17626004 2.3208 -1.17626004 2.3107 -1.17386841 1 P 0 N
L 2.30058996 -1.17625 2.30058996 -1.02033996 1 P 0 
A 2.50836998 -1.10106004 2.54306004 -1.11513002 2.56106673 -1.02093386 1 P 0 N
A 2.51081004 -1.07948002 2.50836998 -1.10103996 2.51886093 -1.09130915 1 P 0 N
A 2.53611004 -1.07688996 2.5108 -1.07948996 2.52742205 -1.11680827 1 P 0 N
A 2.56883996 -1.07368002 2.50178002 -1.06358996 2.5273123 -1.12178858 1 P 0 N
A 2.50178996 -1.06358996 2.48536998 -1.08248996 2.52926211 -1.10403986 1 P 0 N
L 2.48536998 -1.0825 2.48536998 -1.09748002 1 P 0 
A 2.48536998 -1.09748002 2.49956004 -1.12031004 2.51189104 -1.09682067 1 P 0 N
A 2.46181004 -1.11835 2.34675 -1.11835 2.40428002 -1.11611998 1 P 0 N
L 2.43956998 -1.11418002 2.36841004 -1.11418002 1 P 0 
L 2.36841004 -1.11418002 2.36841004 -1.11398996 1 P 8191 
A 2.43958002 -1.11398996 2.3684 -1.11398996 2.40398996 -1.1124 1 P 0 N
L 2.43956998 -1.11398996 2.43956998 -1.11418002 1 P 8191 
A 2.49955 -1.1203 2.52723002 -1.12985 2.58163209 -0.92727982 1 P 0 N
A 2.55001998 -1.14328002 2.52723002 -1.12986004 2.51462185 -1.17733228 1 P 0 N
L 2.46181004 -1.12868996 2.36843996 -1.12868996 1 P 0 
A 2.36843996 -1.12868996 2.37851998 -1.15751998 2.41186801 -1.12968307 1 P 0 N
L 2.34675 -1.1402 2.34675 -1.11835 1 P 0 
L 2.46181004 -1.11835 2.46181004 -1.12868996 1 P 0 
L 2.25188002 -1.11398996 2.25188002 -1.11418002 1 P 8191 
A 2.3208 -1.02041004 2.3006 -1.02033996 2.31069163 -1.02276978 1 P 0 N
L 2.27413002 -1.11835 2.27413002 -1.12868996 1 P 0 
A 2.52848996 -1.16771004 2.54891998 -1.15895 2.52774557 -1.13777087 1 P 0 N
A 2.55608002 -1.08618002 2.53611998 -1.07688996 2.5249185 -1.12704419 1 P 0 N
L 2.71926004 -1.06796998 2.71926004 -1.17483996 1 P 0 
A 2.78888996 -1.16296998 2.81508002 -1.16676998 2.8083499 -1.12100167 1 P 0 N
A 2.8151 -1.16675 2.83966004 -1.15211998 2.80521398 -1.12222392 1 P 0 N
A 2.85201004 -1.16508002 2.83966004 -1.15211004 2.84505768 -1.15933514 1 P 0 N
L 2.85201004 -1.16508002 2.84523996 -1.17161004 1 P 0 
A 2.81425 -1.1835 2.84525 -1.17161004 2.81425 -1.13714291 1 P 0 N
L 2.81425 -1.1835 2.79571004 -1.1835 1 P 0 
A 2.75886998 -1.16443002 2.79571998 -1.18351998 2.80278976 -1.12476142 1 P 0 N
A 2.74528996 -1.13568002 2.75888002 -1.16443002 2.80246565 -1.12624016 1 P 0 N
A 2.54316998 -1.1834 2.56906004 -1.1647 2.5305814 -1.13869892 1 P 0 N
A 2.56906004 -1.1647 2.57053996 -1.13728002 2.53763041 -1.14925374 1 P 0 N
A 2.65463996 -1.18351998 2.66863996 -1.17373996 2.65440246 -1.16826969 1 P 0 N
L 2.65463002 -1.1835 2.64165 -1.1835 1 P 0 
A 2.60955 -1.16043002 2.64163996 -1.18351004 2.63911063 -1.15317815 1 P 0 N
A 2.62978002 -1.15461998 2.66001998 -1.16328996 2.6502374 -1.14033868 1 P 0 N
A 2.66863996 -1.17375 2.66001998 -1.16328996 2.66100344 -1.17126132 1 P 0 N
A 2.6962 -1.17483996 2.71926004 -1.17483996 2.70773002 -1.17286427 1 P 0 N
L 2.69618996 -1.17483996 2.69618996 -1.06796998 1 P 0 
A 2.83833002 -1.09275 2.82661998 -1.08201998 2.74555758 -1.18224094 1 P 0 N
A 2.82661998 -1.08198996 2.80036998 -1.07538996 2.80348839 -1.11848878 1 P 0 N
A 2.80036004 -1.07541998 2.76848996 -1.09933002 2.80700217 -1.1174685 1 P 0 N
A 2.76848996 -1.09931998 2.76446004 -1.12066004 2.82315728 -1.120694 1 P 0 N
A 2.74998002 -1.09273996 2.74528996 -1.11838996 2.8498563 -1.12425591 1 P 0 N
A 2.7954 -1.05776998 2.74998996 -1.09273996 2.80799961 -1.12109961 1 P 0 N
L 2.79541004 -1.05776998 2.80918996 -1.05776998 1 P 0 
A 2.85401998 -1.08106004 2.80918996 -1.05776998 2.80626024 -1.1181998 1 P 0 N
A 2.83833002 -1.09273996 2.85403002 -1.08106004 2.84418386 -1.08421683 1 P 0 N
L 2.76445 -1.12066004 2.76445 -1.12943002 1 P 0 
A 2.76446004 -1.12943002 2.76836998 -1.14305 2.80607844 -1.12485364 1 P 0 N
A 2.76836998 -1.14305 2.78891004 -1.16296998 2.80906152 -1.12164144 1 P 0 N
L 2.74528996 -1.13566004 2.74528996 -1.11838996 1 P 0 
A 2.55606004 -1.0862 2.56885 -1.07366998 2.56205354 -1.0795252 1 P 0 N
L 2.60953996 -1.07953996 2.59981998 -1.07953996 1 P 0 
A 2.5993 -1.05931998 2.59981004 -1.07955 2.6022813 -1.06936624 1 P 0 N
L 2.5993 -1.05931998 2.60953996 -1.05931998 1 P 0 
L 2.60953996 -1.05931998 2.60953996 -1.03491998 1 P 0 
A 2.62971998 -1.03418002 2.60953996 -1.03491004 2.61966791 -1.03559478 1 P 0 N
L 2.62971004 -1.03418996 2.62978002 -1.05931998 1 P 0 
L 2.62978002 -1.05931998 2.66008002 -1.05931998 1 P 0 
A 2.66003996 -1.07955 2.66008002 -1.05931998 2.65827421 -1.0694314 1 P 0 N
L 2.66003002 -1.07953996 2.62978002 -1.07953996 1 P 0 
A 2.71926004 -1.06796998 2.6962 -1.06796998 2.70773002 -1.0720561 1 P 0 N
A 2.71968996 -1.02341998 2.71968996 -1.02341998 2.70775 -1.02341998 1 P 0 N
A 2.57053996 -1.13728996 2.54306998 -1.11513002 2.53584449 -1.15219301 1 P 0 N
A 2.54891998 -1.15895 2.55001004 -1.14328002 2.54127923 -1.15054557 1 P 0 N
L 2.60953996 -1.16041004 2.60953996 -1.07953996 1 P 0 
L 2.62978002 -1.07953996 2.62978002 -1.15463002 1 P 0 
L 2.98495 -1.09393996 2.98495 -1.17625 1 P 0 
A 2.96473996 -1.17626998 2.98493996 -1.17626998 2.97483996 -1.17442303 1 P 0 N
L 2.96473002 -1.17625 2.96473002 -1.17226004 1 P 8191 
A 2.94165 -1.1835 2.96471004 -1.17226004 2.93076516 -1.1318935 1 P 0 N
L 2.94165 -1.1835 2.90701004 -1.1835 1 P 0 
A 2.90671004 -1.10841998 2.90703002 -1.18351004 2.9153065 -1.14592904 1 P 0 N
A 2.91853002 -1.12288996 2.91853002 -1.16618996 2.92048209 -1.14453996 1 P 0 N
L 2.91853002 -1.1662 2.94456004 -1.1662 1 P 0 
A 2.94456998 -1.16618996 2.94456998 -1.12288996 2.94406004 -1.14453996 1 P 0 N
A 2.96473002 -1.09686004 2.94741998 -1.07955 2.94874833 -1.09553169 1 P 0 N
L 2.9474 -1.07953996 2.90986998 -1.07953996 1 P 0 
A 2.90986998 -1.07953996 2.89821004 -1.0852 2.92433445 -1.12417766 1 P 0 N
A 2.89111998 -1.07086004 2.8982 -1.0852 2.8969689 -1.07688996 1 P 0 N
A 2.91561998 -1.05931998 2.89111998 -1.07085 2.92146033 -1.103525 1 P 0 N
L 2.91563002 -1.05931998 2.95031004 -1.05931998 1 P 0 
A 2.98496004 -1.09393996 2.95031004 -1.05933002 2.9453438 -1.09895197 1 P 0 N
A 2.92878996 -1.10535 2.9067 -1.10841998 2.93158484 -1.20646998 1 P 0 N
A 2.96471998 -1.10841004 2.92878002 -1.10536004 2.93215738 -1.27883829 1 P 0 N
L 2.96473002 -1.10841004 2.96473002 -1.09686004 1 P 0 
L 2.94456004 -1.12288002 2.91853002 -1.12288002 1 P 0 
L 3.04731004 -1.06001004 3.04191998 -1.07631998 1 P 0 
L 3.04191998 -1.07631998 3.03648002 -1.06001004 1 P 0 
L 3.03648002 -1.06001004 3.03243002 -1.06001004 1 P 8191 
L 3.03243002 -1.06001004 3.02698002 -1.08543996 1 P 0 
L 3.02698002 -1.08543996 3.03226004 -1.08543996 1 P 8191 
L 3.03226004 -1.08543996 3.03501004 -1.06886998 1 P 0 
L 3.03501004 -1.06886998 3.04086004 -1.08543996 1 P 0 
L 3.04086004 -1.08543996 3.04308996 -1.08543996 1 P 8191 
L 3.04308996 -1.08543996 3.04888996 -1.06871004 1 P 0 
L 3.04888996 -1.06871004 3.05171004 -1.08543996 1 P 0 
L 3.05171004 -1.08543996 3.05713002 -1.08543996 1 P 8191 
L 3.05713002 -1.08543996 3.05163996 -1.06001004 1 P 0 
L 3.05163996 -1.06001004 3.04731004 -1.06001004 1 P 8191 
L 3.01066998 -1.06508002 3.00223002 -1.06508002 1 P 0 
L 3.00223002 -1.06508002 3.00223002 -1.06001004 1 P 8191 
L 3.00223002 -1.06001004 3.02461004 -1.06001004 1 P 0 
L 3.02461004 -1.06001004 3.02461004 -1.06508002 1 P 8191 
L 3.02461004 -1.06508002 3.01615 -1.06508002 1 P 0 
L 3.01615 -1.06508002 3.01615 -1.08533996 1 P 0 
L 3.01615 -1.08533996 3.01066998 -1.08533996 1 P 8191 
L 3.01066998 -1.08533996 3.01066998 -1.06508002 1 P 0 
L 3.8183999 -1.32000217 3.82586663 -1.32625089 0 P 0 ;1,3=65,5=0.000000
L 3.82586663 -1.32625089 3.83426654 -1.33 0 P 0 ;1,3=65,5=0.000000
L 3.83426654 -1.33 3.84173337 -1.33 0 P 0 ;1,3=65,5=0.000000
L 3.84173337 -1.33 3.8492001 -1.32625089 0 P 0 ;1,3=65,5=0.000000
L 3.8492001 -1.32625089 3.85480059 -1.32000217 0 P 0 ;1,3=65,5=0.000000
L 3.85480059 -1.32000217 3.8576 -1.31124951 0 P 0 ;1,3=65,5=0.000000
L 3.8576 -1.31124951 3.85573376 -1.30250138 0 P 0 ;1,3=65,5=0.000000
L 3.85573376 -1.30250138 3.85106644 -1.29500069 0 P 0 ;1,3=65,5=0.000000
L 3.85106644 -1.29500069 3.84266644 -1.28999941 0 P 0 ;1,3=65,5=0.000000
L 3.84266644 -1.28999941 3.83146713 -1.2875 0 P 0 ;1,3=65,5=0.000000
L 3.83146713 -1.2875 3.82493346 -1.28250108 0 P 0 ;1,3=65,5=0.000000
L 3.82493346 -1.28250108 3.82213238 -1.27375059 0 P 0 ;1,3=65,5=0.000000
L 3.82213238 -1.27375059 3.82400039 -1.2650002 0 P 0 ;1,3=65,5=0.000000
L 3.82400039 -1.2650002 3.82866604 -1.25875157 0 P 0 ;1,3=65,5=0.000000
L 3.82866604 -1.25875157 3.8351997 -1.255 0 P 0 ;1,3=65,5=0.000000
L 3.8351997 -1.255 3.84173337 -1.255 0 P 0 ;1,3=65,5=0.000000
L 3.84173337 -1.255 3.84826703 -1.25749951 0 P 0 ;1,3=65,5=0.000000
L 3.84826703 -1.25749951 3.85386752 -1.26375049 0 P 0 ;1,3=65,5=0.000000
L 3.91299911 -1.33 3.90553228 -1.3287503 0 P 0 ;1,3=65,5=0.000000
L 3.90553228 -1.3287503 3.89900039 -1.32375138 0 P 0 ;1,3=65,5=0.000000
L 3.89900039 -1.32375138 3.8933999 -1.31625069 0 P 0 ;1,3=65,5=0.000000
L 3.8933999 -1.31625069 3.88966565 -1.3075003 0 P 0 ;1,3=65,5=0.000000
L 3.88966565 -1.3075003 3.88779931 -1.2975001 0 P 0 ;1,3=65,5=0.000000
L 3.88779931 -1.2975001 3.88779931 -1.2875 0 P 0 ;1,3=65,5=0.000000
L 3.88779931 -1.2875 3.88966565 -1.2774998 0 P 0 ;1,3=65,5=0.000000
L 3.88966565 -1.2774998 3.8933999 -1.26874941 0 P 0 ;1,3=65,5=0.000000
L 3.8933999 -1.26874941 3.89900039 -1.26125098 0 P 0 ;1,3=65,5=0.000000
L 3.89900039 -1.26125098 3.90553228 -1.2562498 0 P 0 ;1,3=65,5=0.000000
L 3.90553228 -1.2562498 3.91299911 -1.255 0 P 0 ;1,3=65,5=0.000000
L 3.91299911 -1.255 3.92046585 -1.2562498 0 P 0 ;1,3=65,5=0.000000
L 3.92046585 -1.2562498 3.92699951 -1.26125098 0 P 0 ;1,3=65,5=0.000000
L 3.92699951 -1.26125098 3.9326 -1.26874941 0 P 0 ;1,3=65,5=0.000000
L 3.9326 -1.26874941 3.93633425 -1.2774998 0 P 0 ;1,3=65,5=0.000000
L 3.93633425 -1.2774998 3.93820059 -1.2875 0 P 0 ;1,3=65,5=0.000000
L 3.93820059 -1.2875 3.93820059 -1.2975001 0 P 0 ;1,3=65,5=0.000000
L 3.93820059 -1.2975001 3.93633425 -1.3075003 0 P 0 ;1,3=65,5=0.000000
L 3.93633425 -1.3075003 3.9326 -1.31625069 0 P 0 ;1,3=65,5=0.000000
L 3.9326 -1.31625069 3.92699951 -1.32375138 0 P 0 ;1,3=65,5=0.000000
L 3.92699951 -1.32375138 3.92046585 -1.3287503 0 P 0 ;1,3=65,5=0.000000
L 3.92046585 -1.3287503 3.91299911 -1.33 0 P 0 ;1,3=65,5=0.000000
L 3.96933297 -1.255 3.96933297 -1.33 0 P 0 ;1,3=65,5=0.000000
L 3.96933297 -1.33 4.00666693 -1.33 0 P 0 ;1,3=65,5=0.000000
L 4.04246673 -1.33 4.04246673 -1.255 0 P 0 ;1,3=65,5=0.000000
L 4.04246673 -1.255 4.06113287 -1.255 0 P 0 ;1,3=65,5=0.000000
L 4.06113287 -1.255 4.06859961 -1.25875157 0 P 0 ;1,3=65,5=0.000000
L 4.06859961 -1.25875157 4.0742001 -1.26375049 0 P 0 ;1,3=65,5=0.000000
L 4.0742001 -1.26375049 4.07886752 -1.27124882 0 P 0 ;1,3=65,5=0.000000
L 4.07886752 -1.27124882 4.0826 -1.28000157 0 P 0 ;1,3=65,5=0.000000
L 4.0826 -1.28000157 4.08353317 -1.29250118 0 P 0 ;1,3=65,5=0.000000
L 4.08353317 -1.29250118 4.0826 -1.30500079 0 P 0 ;1,3=65,5=0.000000
L 4.0826 -1.30500079 4.07886752 -1.31375128 0 P 0 ;1,3=65,5=0.000000
L 4.07886752 -1.31375128 4.0742001 -1.32125187 0 P 0 ;1,3=65,5=0.000000
L 4.0742001 -1.32125187 4.06859961 -1.32625089 0 P 0 ;1,3=65,5=0.000000
L 4.06859961 -1.32625089 4.06113287 -1.33 0 P 0 ;1,3=65,5=0.000000
L 4.06113287 -1.33 4.04246673 -1.33 0 P 0 ;1,3=65,5=0.000000
L 4.15666693 -1.33 4.11933297 -1.33 0 P 0 ;1,3=65,5=0.000000
L 4.11933297 -1.33 4.11933297 -1.255 0 P 0 ;1,3=65,5=0.000000
L 4.11933297 -1.255 4.15666693 -1.255 0 P 0 ;1,3=65,5=0.000000
L 4.14173337 -1.29124921 4.11933297 -1.29124921 0 P 0 ;1,3=65,5=0.000000
L 4.19433297 -1.33 4.19433297 -1.255 0 P 0 ;1,3=65,5=0.000000
L 4.19433297 -1.255 4.21766644 -1.255 0 P 0 ;1,3=65,5=0.000000
L 4.21766644 -1.255 4.22513327 -1.25875157 0 P 0 ;1,3=65,5=0.000000
L 4.22513327 -1.25875157 4.22980059 -1.26375049 0 P 0 ;1,3=65,5=0.000000
L 4.22980059 -1.26375049 4.23166693 -1.27375059 0 P 0 ;1,3=65,5=0.000000
L 4.23166693 -1.27375059 4.22980059 -1.28375079 0 P 0 ;1,3=65,5=0.000000
L 4.22980059 -1.28375079 4.2242001 -1.28999941 0 P 0 ;1,3=65,5=0.000000
L 4.2242001 -1.28999941 4.21766644 -1.29375089 0 P 0 ;1,3=65,5=0.000000
L 4.21766644 -1.29375089 4.19433297 -1.29375089 0 P 0 ;1,3=65,5=0.000000
L 4.21766644 -1.29375089 4.23166693 -1.33 0 P 0 ;1,3=65,5=0.000000
L 4.26933297 -1.33 4.26933297 -1.255 0 P 0 ;1,3=65,5=0.000000
L 4.26933297 -1.255 4.29173337 -1.255 0 P 0 ;1,3=65,5=0.000000
L 4.29173337 -1.255 4.2992001 -1.25875157 0 P 0 ;1,3=65,5=0.000000
L 4.2992001 -1.25875157 4.30480059 -1.2674997 0 P 0 ;1,3=65,5=0.000000
L 4.30480059 -1.2674997 4.30666693 -1.2774998 0 P 0 ;1,3=65,5=0.000000
L 4.30666693 -1.2774998 4.30480059 -1.2875 0 P 0 ;1,3=65,5=0.000000
L 4.30480059 -1.2875 4.30013327 -1.29500069 0 P 0 ;1,3=65,5=0.000000
L 4.30013327 -1.29500069 4.29173337 -1.29875217 0 P 0 ;1,3=65,5=0.000000
L 4.29173337 -1.29875217 4.26933297 -1.29875217 0 P 0 ;1,3=65,5=0.000000
L 4.33966565 -1.33 4.36299911 -1.255 0 P 0 ;1,3=65,5=0.000000
L 4.36299911 -1.255 4.38633425 -1.33 0 P 0 ;1,3=65,5=0.000000
L 4.37793268 -1.30375108 4.34806555 -1.30375108 0 P 0 ;1,3=65,5=0.000000
L 4.4183999 -1.32000217 4.42586663 -1.32625089 0 P 0 ;1,3=65,5=0.000000
L 4.42586663 -1.32625089 4.43426654 -1.33 0 P 0 ;1,3=65,5=0.000000
L 4.43426654 -1.33 4.44173337 -1.33 0 P 0 ;1,3=65,5=0.000000
L 4.44173337 -1.33 4.4492001 -1.32625089 0 P 0 ;1,3=65,5=0.000000
L 4.4492001 -1.32625089 4.45480059 -1.32000217 0 P 0 ;1,3=65,5=0.000000
L 4.45480059 -1.32000217 4.4576 -1.31124951 0 P 0 ;1,3=65,5=0.000000
L 4.4576 -1.31124951 4.45573376 -1.30250138 0 P 0 ;1,3=65,5=0.000000
L 4.45573376 -1.30250138 4.45106644 -1.29500069 0 P 0 ;1,3=65,5=0.000000
L 4.45106644 -1.29500069 4.44266644 -1.28999941 0 P 0 ;1,3=65,5=0.000000
L 4.44266644 -1.28999941 4.43146713 -1.2875 0 P 0 ;1,3=65,5=0.000000
L 4.43146713 -1.2875 4.42493346 -1.28250108 0 P 0 ;1,3=65,5=0.000000
L 4.42493346 -1.28250108 4.42213238 -1.27375059 0 P 0 ;1,3=65,5=0.000000
L 4.42213238 -1.27375059 4.42400039 -1.2650002 0 P 0 ;1,3=65,5=0.000000
L 4.42400039 -1.2650002 4.42866604 -1.25875157 0 P 0 ;1,3=65,5=0.000000
L 4.42866604 -1.25875157 4.4351997 -1.255 0 P 0 ;1,3=65,5=0.000000
L 4.4351997 -1.255 4.44173337 -1.255 0 P 0 ;1,3=65,5=0.000000
L 4.44173337 -1.255 4.44826703 -1.25749951 0 P 0 ;1,3=65,5=0.000000
L 4.44826703 -1.25749951 4.45386752 -1.26375049 0 P 0 ;1,3=65,5=0.000000
L 4.51299911 -1.255 4.51299911 -1.33 0 P 0 ;1,3=65,5=0.000000
L 4.49153356 -1.255 4.53446634 -1.255 0 P 0 ;1,3=65,5=0.000000
L 4.60666693 -1.33 4.56933297 -1.33 0 P 0 ;1,3=65,5=0.000000
L 4.56933297 -1.33 4.56933297 -1.255 0 P 0 ;1,3=65,5=0.000000
L 4.56933297 -1.255 4.60666693 -1.255 0 P 0 ;1,3=65,5=0.000000
L 4.59173337 -1.29124921 4.56933297 -1.29124921 0 P 0 ;1,3=65,5=0.000000
L 4.73799911 -1.255 4.73799911 -1.33 0 P 0 ;1,3=65,5=0.000000
L 4.71653356 -1.255 4.75946634 -1.255 0 P 0 ;1,3=65,5=0.000000
L 4.81299911 -1.33 4.80553228 -1.3287503 0 P 0 ;1,3=65,5=0.000000
L 4.80553228 -1.3287503 4.79900039 -1.32375138 0 P 0 ;1,3=65,5=0.000000
L 4.79900039 -1.32375138 4.7933999 -1.31625069 0 P 0 ;1,3=65,5=0.000000
L 4.7933999 -1.31625069 4.78966565 -1.3075003 0 P 0 ;1,3=65,5=0.000000
L 4.78966565 -1.3075003 4.78779931 -1.2975001 0 P 0 ;1,3=65,5=0.000000
L 4.78779931 -1.2975001 4.78779931 -1.2875 0 P 0 ;1,3=65,5=0.000000
L 4.78779931 -1.2875 4.78966565 -1.2774998 0 P 0 ;1,3=65,5=0.000000
L 4.78966565 -1.2774998 4.7933999 -1.26874941 0 P 0 ;1,3=65,5=0.000000
L 4.7933999 -1.26874941 4.79900039 -1.26125098 0 P 0 ;1,3=65,5=0.000000
L 4.79900039 -1.26125098 4.80553228 -1.2562498 0 P 0 ;1,3=65,5=0.000000
L 4.80553228 -1.2562498 4.81299911 -1.255 0 P 0 ;1,3=65,5=0.000000
L 4.81299911 -1.255 4.82046585 -1.2562498 0 P 0 ;1,3=65,5=0.000000
L 4.82046585 -1.2562498 4.82699951 -1.26125098 0 P 0 ;1,3=65,5=0.000000
L 4.82699951 -1.26125098 4.8326 -1.26874941 0 P 0 ;1,3=65,5=0.000000
L 4.8326 -1.26874941 4.83633425 -1.2774998 0 P 0 ;1,3=65,5=0.000000
L 4.83633425 -1.2774998 4.83820059 -1.2875 0 P 0 ;1,3=65,5=0.000000
L 4.83820059 -1.2875 4.83820059 -1.2975001 0 P 0 ;1,3=65,5=0.000000
L 4.83820059 -1.2975001 4.83633425 -1.3075003 0 P 0 ;1,3=65,5=0.000000
L 4.83633425 -1.3075003 4.8326 -1.31625069 0 P 0 ;1,3=65,5=0.000000
L 4.8326 -1.31625069 4.82699951 -1.32375138 0 P 0 ;1,3=65,5=0.000000
L 4.82699951 -1.32375138 4.82046585 -1.3287503 0 P 0 ;1,3=65,5=0.000000
L 4.82046585 -1.3287503 4.81299911 -1.33 0 P 0 ;1,3=65,5=0.000000
L 4.86933297 -1.33 4.86933297 -1.255 0 P 0 ;1,3=65,5=0.000000
L 4.86933297 -1.255 4.89173337 -1.255 0 P 0 ;1,3=65,5=0.000000
L 4.89173337 -1.255 4.8992001 -1.25875157 0 P 0 ;1,3=65,5=0.000000
L 4.8992001 -1.25875157 4.90480059 -1.2674997 0 P 0 ;1,3=65,5=0.000000
L 4.90480059 -1.2674997 4.90666693 -1.2774998 0 P 0 ;1,3=65,5=0.000000
L 4.90666693 -1.2774998 4.90480059 -1.2875 0 P 0 ;1,3=65,5=0.000000
L 4.90480059 -1.2875 4.90013327 -1.29500069 0 P 0 ;1,3=65,5=0.000000
L 4.90013327 -1.29500069 4.89173337 -1.29875217 0 P 0 ;1,3=65,5=0.000000
L 4.89173337 -1.29875217 4.86933297 -1.29875217 0 P 0 ;1,3=65,5=0.000000
L 3.36933297 -0.955 3.36933297 -0.88 0 P 0 ;1,3=66,5=0.000000
L 3.36933297 -0.88 3.39173337 -0.88 0 P 0 ;1,3=66,5=0.000000
L 3.39173337 -0.88 3.3992001 -0.88375157 0 P 0 ;1,3=66,5=0.000000
L 3.3992001 -0.88375157 3.40480059 -0.8924997 0 P 0 ;1,3=66,5=0.000000
L 3.40480059 -0.8924997 3.40666693 -0.9024998 0 P 0 ;1,3=66,5=0.000000
L 3.40666693 -0.9024998 3.40480059 -0.9125 0 P 0 ;1,3=66,5=0.000000
L 3.40480059 -0.9125 3.40013327 -0.92000069 0 P 0 ;1,3=66,5=0.000000
L 3.40013327 -0.92000069 3.39173337 -0.92375217 0 P 0 ;1,3=66,5=0.000000
L 3.39173337 -0.92375217 3.36933297 -0.92375217 0 P 0 ;1,3=66,5=0.000000
L 3.44619931 -0.95749941 3.47980059 -0.88 0 P 0 ;1,3=66,5=0.000000
L 3.51653356 -0.955 3.51653356 -0.88 0 P 0 ;1,3=66,5=0.000000
L 3.51653356 -0.88 3.55946634 -0.955 0 P 0 ;1,3=66,5=0.000000
L 3.55946634 -0.955 3.55946634 -0.88 0 P 0 ;1,3=66,5=0.000000
L 3.68799911 -0.95749941 3.68613287 -0.9562497 0 P 0 ;1,3=66,5=0.000000
L 3.68613287 -0.9562497 3.68613287 -0.9537503 0 P 0 ;1,3=66,5=0.000000
L 3.68613287 -0.9537503 3.68799911 -0.95250059 0 P 0 ;1,3=66,5=0.000000
L 3.68799911 -0.95250059 3.68986703 -0.9537503 0 P 0 ;1,3=66,5=0.000000
L 3.68986703 -0.9537503 3.68986703 -0.9562497 0 P 0 ;1,3=66,5=0.000000
L 3.68986703 -0.9562497 3.68799911 -0.95749941 0 P 0 ;1,3=66,5=0.000000
L 3.68799911 -0.92375217 3.68613287 -0.9225001 0 P 0 ;1,3=66,5=0.000000
L 3.68613287 -0.9225001 3.68613287 -0.92000069 0 P 0 ;1,3=66,5=0.000000
L 3.68613287 -0.92000069 3.68799911 -0.91875089 0 P 0 ;1,3=66,5=0.000000
L 3.68799911 -0.91875089 3.68986703 -0.92000069 0 P 0 ;1,3=66,5=0.000000
L 3.68986703 -0.92000069 3.68986703 -0.9225001 0 P 0 ;1,3=66,5=0.000000
L 3.68986703 -0.9225001 3.68799911 -0.92375217 0 P 0 ;1,3=66,5=0.000000
L 3.81933297 -0.955 3.81933297 -0.88 0 P 0 ;1,3=66,5=0.000000
L 3.81933297 -0.88 3.84266644 -0.88 0 P 0 ;1,3=66,5=0.000000
L 3.84266644 -0.88 3.85013327 -0.88375157 0 P 0 ;1,3=66,5=0.000000
L 3.85013327 -0.88375157 3.85480059 -0.88875049 0 P 0 ;1,3=66,5=0.000000
L 3.85480059 -0.88875049 3.85666693 -0.89875059 0 P 0 ;1,3=66,5=0.000000
L 3.85666693 -0.89875059 3.85480059 -0.90875079 0 P 0 ;1,3=66,5=0.000000
L 3.85480059 -0.90875079 3.8492001 -0.91499941 0 P 0 ;1,3=66,5=0.000000
L 3.8492001 -0.91499941 3.84266644 -0.91875089 0 P 0 ;1,3=66,5=0.000000
L 3.84266644 -0.91875089 3.81933297 -0.91875089 0 P 0 ;1,3=66,5=0.000000
L 3.84266644 -0.91875089 3.85666693 -0.955 0 P 0 ;1,3=66,5=0.000000
L 3.9242001 -0.955 3.9242001 -0.88 0 P 0 ;1,3=66,5=0.000000
L 3.9242001 -0.88 3.88966565 -0.93375 0 P 0 ;1,3=66,5=0.000000
L 3.88966565 -0.93375 3.93633425 -0.93375 0 P 0 ;1,3=66,5=0.000000
L 3.98799911 -0.88 3.98053228 -0.88249951 0 P 0 ;1,3=66,5=0.000000
L 3.98053228 -0.88249951 3.97493346 -0.88875049 0 P 0 ;1,3=66,5=0.000000
L 3.97493346 -0.88875049 3.97119931 -0.89624882 0 P 0 ;1,3=66,5=0.000000
L 3.97119931 -0.89624882 3.9683999 -0.90625128 0 P 0 ;1,3=66,5=0.000000
L 3.9683999 -0.90625128 3.96746673 -0.91750118 0 P 0 ;1,3=66,5=0.000000
L 3.96746673 -0.91750118 3.9683999 -0.92875108 0 P 0 ;1,3=66,5=0.000000
L 3.9683999 -0.92875108 3.97119931 -0.93875128 0 P 0 ;1,3=66,5=0.000000
L 3.97119931 -0.93875128 3.97493346 -0.94625187 0 P 0 ;1,3=66,5=0.000000
L 3.97493346 -0.94625187 3.98053228 -0.95250059 0 P 0 ;1,3=66,5=0.000000
L 3.98053228 -0.95250059 3.98799911 -0.955 0 P 0 ;1,3=66,5=0.000000
L 3.98799911 -0.955 3.99546585 -0.95250059 0 P 0 ;1,3=66,5=0.000000
L 3.99546585 -0.95250059 4.00106644 -0.94625187 0 P 0 ;1,3=66,5=0.000000
L 4.00106644 -0.94625187 4.00480059 -0.93875128 0 P 0 ;1,3=66,5=0.000000
L 4.00480059 -0.93875128 4.0076 -0.92875108 0 P 0 ;1,3=66,5=0.000000
L 4.0076 -0.92875108 4.00853317 -0.91750118 0 P 0 ;1,3=66,5=0.000000
L 4.00853317 -0.91750118 4.0076 -0.90625128 0 P 0 ;1,3=66,5=0.000000
L 4.0076 -0.90625128 4.00480059 -0.89624882 0 P 0 ;1,3=66,5=0.000000
L 4.00480059 -0.89624882 4.00106644 -0.88875049 0 P 0 ;1,3=66,5=0.000000
L 4.00106644 -0.88875049 3.99546585 -0.88249951 0 P 0 ;1,3=66,5=0.000000
L 3.99546585 -0.88249951 3.98799911 -0.88 0 P 0 ;1,3=66,5=0.000000
L 4.06299911 -0.88 4.05553228 -0.88249951 0 P 0 ;1,3=66,5=0.000000
L 4.05553228 -0.88249951 4.04993346 -0.88875049 0 P 0 ;1,3=66,5=0.000000
L 4.04993346 -0.88875049 4.04619931 -0.89624882 0 P 0 ;1,3=66,5=0.000000
L 4.04619931 -0.89624882 4.0433999 -0.90625128 0 P 0 ;1,3=66,5=0.000000
L 4.0433999 -0.90625128 4.04246673 -0.91750118 0 P 0 ;1,3=66,5=0.000000
L 4.04246673 -0.91750118 4.0433999 -0.92875108 0 P 0 ;1,3=66,5=0.000000
L 4.0433999 -0.92875108 4.04619931 -0.93875128 0 P 0 ;1,3=66,5=0.000000
L 4.04619931 -0.93875128 4.04993346 -0.94625187 0 P 0 ;1,3=66,5=0.000000
L 4.04993346 -0.94625187 4.05553228 -0.95250059 0 P 0 ;1,3=66,5=0.000000
L 4.05553228 -0.95250059 4.06299911 -0.955 0 P 0 ;1,3=66,5=0.000000
L 4.06299911 -0.955 4.07046585 -0.95250059 0 P 0 ;1,3=66,5=0.000000
L 4.07046585 -0.95250059 4.07606644 -0.94625187 0 P 0 ;1,3=66,5=0.000000
L 4.07606644 -0.94625187 4.07980059 -0.93875128 0 P 0 ;1,3=66,5=0.000000
L 4.07980059 -0.93875128 4.0826 -0.92875108 0 P 0 ;1,3=66,5=0.000000
L 4.0826 -0.92875108 4.08353317 -0.91750118 0 P 0 ;1,3=66,5=0.000000
L 4.08353317 -0.91750118 4.0826 -0.90625128 0 P 0 ;1,3=66,5=0.000000
L 4.0826 -0.90625128 4.07980059 -0.89624882 0 P 0 ;1,3=66,5=0.000000
L 4.07980059 -0.89624882 4.07606644 -0.88875049 0 P 0 ;1,3=66,5=0.000000
L 4.07606644 -0.88875049 4.07046585 -0.88249951 0 P 0 ;1,3=66,5=0.000000
L 4.07046585 -0.88249951 4.06299911 -0.88 0 P 0 ;1,3=66,5=0.000000
L 4.12026614 -0.92375217 4.1267998 -0.91499941 0 P 0 ;1,3=66,5=0.000000
L 4.1267998 -0.91499941 4.1324003 -0.91000049 0 P 0 ;1,3=66,5=0.000000
L 4.1324003 -0.91000049 4.13986703 -0.90750108 0 P 0 ;1,3=66,5=0.000000
L 4.13986703 -0.90750108 4.14640069 -0.91000049 0 P 0 ;1,3=66,5=0.000000
L 4.14640069 -0.91000049 4.15106644 -0.91499941 0 P 0 ;1,3=66,5=0.000000
L 4.15106644 -0.91499941 4.15480059 -0.9225001 0 P 0 ;1,3=66,5=0.000000
L 4.15480059 -0.9225001 4.15573376 -0.93125059 0 P 0 ;1,3=66,5=0.000000
L 4.15573376 -0.93125059 4.15480059 -0.93875128 0 P 0 ;1,3=66,5=0.000000
L 4.15480059 -0.93875128 4.15106644 -0.94625187 0 P 0 ;1,3=66,5=0.000000
L 4.15106644 -0.94625187 4.14546585 -0.95250059 0 P 0 ;1,3=66,5=0.000000
L 4.14546585 -0.95250059 4.13893396 -0.955 0 P 0 ;1,3=66,5=0.000000
L 4.13893396 -0.955 4.13146713 -0.95250059 0 P 0 ;1,3=66,5=0.000000
L 4.13146713 -0.95250059 4.12493346 -0.94500217 0 P 0 ;1,3=66,5=0.000000
L 4.12493346 -0.94500217 4.12119931 -0.93375 0 P 0 ;1,3=66,5=0.000000
L 4.12119931 -0.93375 4.12026614 -0.92125039 0 P 0 ;1,3=66,5=0.000000
L 4.12026614 -0.92125039 4.12213238 -0.90500157 0 P 0 ;1,3=66,5=0.000000
L 4.12213238 -0.90500157 4.12493346 -0.89624882 0 P 0 ;1,3=66,5=0.000000
L 4.12493346 -0.89624882 4.12959921 -0.88750069 0 P 0 ;1,3=66,5=0.000000
L 4.12959921 -0.88750069 4.13613287 -0.8812498 0 P 0 ;1,3=66,5=0.000000
L 4.13613287 -0.8812498 4.14266644 -0.88 0 P 0 ;1,3=66,5=0.000000
L 4.14266644 -0.88 4.1492001 -0.88249951 0 P 0 ;1,3=66,5=0.000000
L 4.1492001 -0.88249951 4.15386752 -0.88875049 0 P 0 ;1,3=66,5=0.000000
L 4.20086663 -0.93000079 4.22513327 -0.93000079 0 P 0 ;1,3=66,5=0.000000
L 4.29546585 -0.91499941 4.2992001 -0.9112502 0 P 0 ;1,3=66,5=0.000000
L 4.2992001 -0.9112502 4.30199951 -0.90500157 0 P 0 ;1,3=66,5=0.000000
L 4.30199951 -0.90500157 4.30386752 -0.89624882 0 P 0 ;1,3=66,5=0.000000
L 4.30386752 -0.89624882 4.30199951 -0.88875049 0 P 0 ;1,3=66,5=0.000000
L 4.30199951 -0.88875049 4.29826703 -0.88375157 0 P 0 ;1,3=66,5=0.000000
L 4.29826703 -0.88375157 4.29173337 -0.88 0 P 0 ;1,3=66,5=0.000000
L 4.29173337 -0.88 4.26653356 -0.88 0 P 0 ;1,3=66,5=0.000000
L 4.26653356 -0.88 4.26653356 -0.955 0 P 0 ;1,3=66,5=0.000000
L 4.26653356 -0.955 4.29733386 -0.955 0 P 0 ;1,3=66,5=0.000000
L 4.29733386 -0.955 4.30386752 -0.95000108 0 P 0 ;1,3=66,5=0.000000
L 4.30386752 -0.95000108 4.3076 -0.94250039 0 P 0 ;1,3=66,5=0.000000
L 4.3076 -0.94250039 4.30946634 -0.93375 0 P 0 ;1,3=66,5=0.000000
L 4.30946634 -0.93375 4.3076 -0.92500187 0 P 0 ;1,3=66,5=0.000000
L 4.3076 -0.92500187 4.30199951 -0.91750118 0 P 0 ;1,3=66,5=0.000000
L 4.30199951 -0.91750118 4.29546585 -0.91499941 0 P 0 ;1,3=66,5=0.000000
L 4.29546585 -0.91499941 4.26653356 -0.91499941 0 P 0 ;1,3=66,5=0.000000
L 4.36299911 -0.88 4.35553228 -0.88249951 0 P 0 ;1,3=66,5=0.000000
L 4.35553228 -0.88249951 4.34993346 -0.88875049 0 P 0 ;1,3=66,5=0.000000
L 4.34993346 -0.88875049 4.34619931 -0.89624882 0 P 0 ;1,3=66,5=0.000000
L 4.34619931 -0.89624882 4.3433999 -0.90625128 0 P 0 ;1,3=66,5=0.000000
L 4.3433999 -0.90625128 4.34246673 -0.91750118 0 P 0 ;1,3=66,5=0.000000
L 4.34246673 -0.91750118 4.3433999 -0.92875108 0 P 0 ;1,3=66,5=0.000000
L 4.3433999 -0.92875108 4.34619931 -0.93875128 0 P 0 ;1,3=66,5=0.000000
L 4.34619931 -0.93875128 4.34993346 -0.94625187 0 P 0 ;1,3=66,5=0.000000
L 4.34993346 -0.94625187 4.35553228 -0.95250059 0 P 0 ;1,3=66,5=0.000000
L 4.35553228 -0.95250059 4.36299911 -0.955 0 P 0 ;1,3=66,5=0.000000
L 4.36299911 -0.955 4.37046585 -0.95250059 0 P 0 ;1,3=66,5=0.000000
L 4.37046585 -0.95250059 4.37606644 -0.94625187 0 P 0 ;1,3=66,5=0.000000
L 4.37606644 -0.94625187 4.37980059 -0.93875128 0 P 0 ;1,3=66,5=0.000000
L 4.37980059 -0.93875128 4.3826 -0.92875108 0 P 0 ;1,3=66,5=0.000000
L 4.3826 -0.92875108 4.38353317 -0.91750118 0 P 0 ;1,3=66,5=0.000000
L 4.38353317 -0.91750118 4.3826 -0.90625128 0 P 0 ;1,3=66,5=0.000000
L 4.3826 -0.90625128 4.37980059 -0.89624882 0 P 0 ;1,3=66,5=0.000000
L 4.37980059 -0.89624882 4.37606644 -0.88875049 0 P 0 ;1,3=66,5=0.000000
L 4.37606644 -0.88875049 4.37046585 -0.88249951 0 P 0 ;1,3=66,5=0.000000
L 4.37046585 -0.88249951 4.36299911 -0.88 0 P 0 ;1,3=66,5=0.000000
L 4.43799911 -0.88 4.43053228 -0.88249951 0 P 0 ;1,3=66,5=0.000000
L 4.43053228 -0.88249951 4.42493346 -0.88875049 0 P 0 ;1,3=66,5=0.000000
L 4.42493346 -0.88875049 4.42119931 -0.89624882 0 P 0 ;1,3=66,5=0.000000
L 4.42119931 -0.89624882 4.4183999 -0.90625128 0 P 0 ;1,3=66,5=0.000000
L 4.4183999 -0.90625128 4.41746673 -0.91750118 0 P 0 ;1,3=66,5=0.000000
L 4.41746673 -0.91750118 4.4183999 -0.92875108 0 P 0 ;1,3=66,5=0.000000
L 4.4183999 -0.92875108 4.42119931 -0.93875128 0 P 0 ;1,3=66,5=0.000000
L 4.42119931 -0.93875128 4.42493346 -0.94625187 0 P 0 ;1,3=66,5=0.000000
L 4.42493346 -0.94625187 4.43053228 -0.95250059 0 P 0 ;1,3=66,5=0.000000
L 4.43053228 -0.95250059 4.43799911 -0.955 0 P 0 ;1,3=66,5=0.000000
L 4.43799911 -0.955 4.44546585 -0.95250059 0 P 0 ;1,3=66,5=0.000000
L 4.44546585 -0.95250059 4.45106644 -0.94625187 0 P 0 ;1,3=66,5=0.000000
L 4.45106644 -0.94625187 4.45480059 -0.93875128 0 P 0 ;1,3=66,5=0.000000
L 4.45480059 -0.93875128 4.4576 -0.92875108 0 P 0 ;1,3=66,5=0.000000
L 4.4576 -0.92875108 4.45853317 -0.91750118 0 P 0 ;1,3=66,5=0.000000
L 4.45853317 -0.91750118 4.4576 -0.90625128 0 P 0 ;1,3=66,5=0.000000
L 4.4576 -0.90625128 4.45480059 -0.89624882 0 P 0 ;1,3=66,5=0.000000
L 4.45480059 -0.89624882 4.45106644 -0.88875049 0 P 0 ;1,3=66,5=0.000000
L 4.45106644 -0.88875049 4.44546585 -0.88249951 0 P 0 ;1,3=66,5=0.000000
L 4.44546585 -0.88249951 4.43799911 -0.88 0 P 0 ;1,3=66,5=0.000000
L 4.51299911 -0.88 4.50553228 -0.88249951 0 P 0 ;1,3=66,5=0.000000
L 4.50553228 -0.88249951 4.49993346 -0.88875049 0 P 0 ;1,3=66,5=0.000000
L 4.49993346 -0.88875049 4.49619931 -0.89624882 0 P 0 ;1,3=66,5=0.000000
L 4.49619931 -0.89624882 4.4933999 -0.90625128 0 P 0 ;1,3=66,5=0.000000
L 4.4933999 -0.90625128 4.49246673 -0.91750118 0 P 0 ;1,3=66,5=0.000000
L 4.49246673 -0.91750118 4.4933999 -0.92875108 0 P 0 ;1,3=66,5=0.000000
L 4.4933999 -0.92875108 4.49619931 -0.93875128 0 P 0 ;1,3=66,5=0.000000
L 4.49619931 -0.93875128 4.49993346 -0.94625187 0 P 0 ;1,3=66,5=0.000000
L 4.49993346 -0.94625187 4.50553228 -0.95250059 0 P 0 ;1,3=66,5=0.000000
L 4.50553228 -0.95250059 4.51299911 -0.955 0 P 0 ;1,3=66,5=0.000000
L 4.51299911 -0.955 4.52046585 -0.95250059 0 P 0 ;1,3=66,5=0.000000
L 4.52046585 -0.95250059 4.52606644 -0.94625187 0 P 0 ;1,3=66,5=0.000000
L 4.52606644 -0.94625187 4.52980059 -0.93875128 0 P 0 ;1,3=66,5=0.000000
L 4.52980059 -0.93875128 4.5326 -0.92875108 0 P 0 ;1,3=66,5=0.000000
L 4.5326 -0.92875108 4.53353317 -0.91750118 0 P 0 ;1,3=66,5=0.000000
L 4.53353317 -0.91750118 4.5326 -0.90625128 0 P 0 ;1,3=66,5=0.000000
L 4.5326 -0.90625128 4.52980059 -0.89624882 0 P 0 ;1,3=66,5=0.000000
L 4.52980059 -0.89624882 4.52606644 -0.88875049 0 P 0 ;1,3=66,5=0.000000
L 4.52606644 -0.88875049 4.52046585 -0.88249951 0 P 0 ;1,3=66,5=0.000000
L 4.52046585 -0.88249951 4.51299911 -0.88 0 P 0 ;1,3=66,5=0.000000
L 4.58799911 -0.955 4.58799911 -0.88 0 P 0 ;1,3=66,5=0.000000
L 4.58799911 -0.88 4.5767998 -0.89499911 0 P 0 ;1,3=66,5=0.000000
L 4.5767998 -0.955 4.59919843 -0.955 0 P 0 ;1,3=66,5=0.000000
L 4.65086663 -0.93000079 4.67513327 -0.93000079 0 P 0 ;1,3=66,5=0.000000
L 4.73799911 -0.88 4.73053228 -0.88249951 0 P 0 ;1,3=66,5=0.000000
L 4.73053228 -0.88249951 4.72493346 -0.88875049 0 P 0 ;1,3=66,5=0.000000
L 4.72493346 -0.88875049 4.72119931 -0.89624882 0 P 0 ;1,3=66,5=0.000000
L 4.72119931 -0.89624882 4.7183999 -0.90625128 0 P 0 ;1,3=66,5=0.000000
L 4.7183999 -0.90625128 4.71746673 -0.91750118 0 P 0 ;1,3=66,5=0.000000
L 4.71746673 -0.91750118 4.7183999 -0.92875108 0 P 0 ;1,3=66,5=0.000000
L 4.7183999 -0.92875108 4.72119931 -0.93875128 0 P 0 ;1,3=66,5=0.000000
L 4.72119931 -0.93875128 4.72493346 -0.94625187 0 P 0 ;1,3=66,5=0.000000
L 4.72493346 -0.94625187 4.73053228 -0.95250059 0 P 0 ;1,3=66,5=0.000000
L 4.73053228 -0.95250059 4.73799911 -0.955 0 P 0 ;1,3=66,5=0.000000
L 4.73799911 -0.955 4.74546585 -0.95250059 0 P 0 ;1,3=66,5=0.000000
L 4.74546585 -0.95250059 4.75106644 -0.94625187 0 P 0 ;1,3=66,5=0.000000
L 4.75106644 -0.94625187 4.75480059 -0.93875128 0 P 0 ;1,3=66,5=0.000000
L 4.75480059 -0.93875128 4.7576 -0.92875108 0 P 0 ;1,3=66,5=0.000000
L 4.7576 -0.92875108 4.75853317 -0.91750118 0 P 0 ;1,3=66,5=0.000000
L 4.75853317 -0.91750118 4.7576 -0.90625128 0 P 0 ;1,3=66,5=0.000000
L 4.7576 -0.90625128 4.75480059 -0.89624882 0 P 0 ;1,3=66,5=0.000000
L 4.75480059 -0.89624882 4.75106644 -0.88875049 0 P 0 ;1,3=66,5=0.000000
L 4.75106644 -0.88875049 4.74546585 -0.88249951 0 P 0 ;1,3=66,5=0.000000
L 4.74546585 -0.88249951 4.73799911 -0.88 0 P 0 ;1,3=66,5=0.000000
L 4.79526614 -0.8924997 4.80086663 -0.88500128 0 P 0 ;1,3=66,5=0.000000
L 4.80086663 -0.88500128 4.8074003 -0.8812498 0 P 0 ;1,3=66,5=0.000000
L 4.8074003 -0.8812498 4.81486703 -0.88 0 P 0 ;1,3=66,5=0.000000
L 4.81486703 -0.88 4.8242001 -0.88249951 0 P 0 ;1,3=66,5=0.000000
L 4.8242001 -0.88249951 4.83073376 -0.88875049 0 P 0 ;1,3=66,5=0.000000
L 4.83073376 -0.88875049 4.8326 -0.89624882 0 P 0 ;1,3=66,5=0.000000
L 4.8326 -0.89624882 4.83166693 -0.90375187 0 P 0 ;1,3=66,5=0.000000
L 4.83166693 -0.90375187 4.82793268 -0.91000049 0 P 0 ;1,3=66,5=0.000000
L 4.82793268 -0.91000049 4.80926654 -0.9225001 0 P 0 ;1,3=66,5=0.000000
L 4.80926654 -0.9225001 4.80086663 -0.93125059 0 P 0 ;1,3=66,5=0.000000
L 4.80086663 -0.93125059 4.79526614 -0.94375246 0 P 0 ;1,3=66,5=0.000000
L 4.79526614 -0.94375246 4.7933999 -0.955 0 P 0 ;1,3=66,5=0.000000
L 4.7933999 -0.955 4.8326 -0.955 0 P 0 ;1,3=66,5=0.000000
L 3.36746673 -1.205 3.36746673 -1.13 0 P 0 ;1,3=67,5=0.000000
L 3.36746673 -1.13 3.38613287 -1.13 0 P 0 ;1,3=67,5=0.000000
L 3.38613287 -1.13 3.39359961 -1.13375157 0 P 0 ;1,3=67,5=0.000000
L 3.39359961 -1.13375157 3.3992001 -1.13875049 0 P 0 ;1,3=67,5=0.000000
L 3.3992001 -1.13875049 3.40386752 -1.14624882 0 P 0 ;1,3=67,5=0.000000
L 3.40386752 -1.14624882 3.4076 -1.15500157 0 P 0 ;1,3=67,5=0.000000
L 3.4076 -1.15500157 3.40853317 -1.16750118 0 P 0 ;1,3=67,5=0.000000
L 3.40853317 -1.16750118 3.4076 -1.18000079 0 P 0 ;1,3=67,5=0.000000
L 3.4076 -1.18000079 3.40386752 -1.18875128 0 P 0 ;1,3=67,5=0.000000
L 3.40386752 -1.18875128 3.3992001 -1.19625187 0 P 0 ;1,3=67,5=0.000000
L 3.3992001 -1.19625187 3.39359961 -1.20125089 0 P 0 ;1,3=67,5=0.000000
L 3.39359961 -1.20125089 3.38613287 -1.205 0 P 0 ;1,3=67,5=0.000000
L 3.38613287 -1.205 3.36746673 -1.205 0 P 0 ;1,3=67,5=0.000000
L 3.47980059 -1.205 3.47980059 -1.15500157 0 P 0 ;1,3=67,5=0.000000
L 3.47980059 -1.1637497 3.47606644 -1.15875079 0 P 0 ;1,3=67,5=0.000000
L 3.47606644 -1.15875079 3.47046585 -1.15625128 0 P 0 ;1,3=67,5=0.000000
L 3.47046585 -1.15625128 3.46393396 -1.15500157 0 P 0 ;1,3=67,5=0.000000
L 3.46393396 -1.15500157 3.4574003 -1.15750108 0 P 0 ;1,3=67,5=0.000000
L 3.4574003 -1.15750108 3.4517998 -1.1625 0 P 0 ;1,3=67,5=0.000000
L 3.4517998 -1.1625 3.44806555 -1.17000069 0 P 0 ;1,3=67,5=0.000000
L 3.44806555 -1.17000069 3.44619931 -1.18000079 0 P 0 ;1,3=67,5=0.000000
L 3.44619931 -1.18000079 3.44806555 -1.19000098 0 P 0 ;1,3=67,5=0.000000
L 3.44806555 -1.19000098 3.4517998 -1.19750167 0 P 0 ;1,3=67,5=0.000000
L 3.4517998 -1.19750167 3.4574003 -1.20250059 0 P 0 ;1,3=67,5=0.000000
L 3.4574003 -1.20250059 3.46393396 -1.205 0 P 0 ;1,3=67,5=0.000000
L 3.46393396 -1.205 3.47046585 -1.2037503 0 P 0 ;1,3=67,5=0.000000
L 3.47046585 -1.2037503 3.47606644 -1.20000108 0 P 0 ;1,3=67,5=0.000000
L 3.47606644 -1.20000108 3.47980059 -1.19500217 0 P 0 ;1,3=67,5=0.000000
L 3.53799911 -1.13 3.53799911 -1.205 0 P 0 ;1,3=67,5=0.000000
L 3.52493346 -1.15500157 3.55106644 -1.15500157 0 P 0 ;1,3=67,5=0.000000
L 3.59900039 -1.17125039 3.62886752 -1.17125039 0 P 0 ;1,3=67,5=0.000000
L 3.62886752 -1.17125039 3.62606644 -1.1625 0 P 0 ;1,3=67,5=0.000000
L 3.62606644 -1.1625 3.62140069 -1.15750108 0 P 0 ;1,3=67,5=0.000000
L 3.62140069 -1.15750108 3.61486703 -1.15500157 0 P 0 ;1,3=67,5=0.000000
L 3.61486703 -1.15500157 3.60833346 -1.15625128 0 P 0 ;1,3=67,5=0.000000
L 3.60833346 -1.15625128 3.60273287 -1.16000049 0 P 0 ;1,3=67,5=0.000000
L 3.60273287 -1.16000049 3.59900039 -1.16875089 0 P 0 ;1,3=67,5=0.000000
L 3.59900039 -1.16875089 3.59713238 -1.17625157 0 P 0 ;1,3=67,5=0.000000
L 3.59713238 -1.17625157 3.59713238 -1.18375 0 P 0 ;1,3=67,5=0.000000
L 3.59713238 -1.18375 3.59900039 -1.19125069 0 P 0 ;1,3=67,5=0.000000
L 3.59900039 -1.19125069 3.60366604 -1.19875138 0 P 0 ;1,3=67,5=0.000000
L 3.60366604 -1.19875138 3.60926654 -1.2037503 0 P 0 ;1,3=67,5=0.000000
L 3.60926654 -1.2037503 3.6158002 -1.205 0 P 0 ;1,3=67,5=0.000000
L 3.6158002 -1.205 3.62233386 -1.20250059 0 P 0 ;1,3=67,5=0.000000
L 3.62233386 -1.20250059 3.62886752 -1.19500217 0 P 0 ;1,3=67,5=0.000000
L 3.68799911 -1.20749941 3.68613287 -1.2062497 0 P 0 ;1,3=67,5=0.000000
L 3.68613287 -1.2062497 3.68613287 -1.2037503 0 P 0 ;1,3=67,5=0.000000
L 3.68613287 -1.2037503 3.68799911 -1.20250059 0 P 0 ;1,3=67,5=0.000000
L 3.68799911 -1.20250059 3.68986703 -1.2037503 0 P 0 ;1,3=67,5=0.000000
L 3.68986703 -1.2037503 3.68986703 -1.2062497 0 P 0 ;1,3=67,5=0.000000
L 3.68986703 -1.2062497 3.68799911 -1.20749941 0 P 0 ;1,3=67,5=0.000000
L 3.68799911 -1.17375217 3.68613287 -1.1725001 0 P 0 ;1,3=67,5=0.000000
L 3.68613287 -1.1725001 3.68613287 -1.17000069 0 P 0 ;1,3=67,5=0.000000
L 3.68613287 -1.17000069 3.68799911 -1.16875089 0 P 0 ;1,3=67,5=0.000000
L 3.68799911 -1.16875089 3.68986703 -1.17000069 0 P 0 ;1,3=67,5=0.000000
L 3.68986703 -1.17000069 3.68986703 -1.1725001 0 P 0 ;1,3=67,5=0.000000
L 3.68986703 -1.1725001 3.68799911 -1.17375217 0 P 0 ;1,3=67,5=0.000000
L 3.82026614 -1.1424997 3.82586663 -1.13500128 0 P 0 ;1,3=67,5=0.000000
L 3.82586663 -1.13500128 3.8324003 -1.1312498 0 P 0 ;1,3=67,5=0.000000
L 3.8324003 -1.1312498 3.83986703 -1.13 0 P 0 ;1,3=67,5=0.000000
L 3.83986703 -1.13 3.8492001 -1.13249951 0 P 0 ;1,3=67,5=0.000000
L 3.8492001 -1.13249951 3.85573376 -1.13875049 0 P 0 ;1,3=67,5=0.000000
L 3.85573376 -1.13875049 3.8576 -1.14624882 0 P 0 ;1,3=67,5=0.000000
L 3.8576 -1.14624882 3.85666693 -1.15375187 0 P 0 ;1,3=67,5=0.000000
L 3.85666693 -1.15375187 3.85293268 -1.16000049 0 P 0 ;1,3=67,5=0.000000
L 3.85293268 -1.16000049 3.83426654 -1.1725001 0 P 0 ;1,3=67,5=0.000000
L 3.83426654 -1.1725001 3.82586663 -1.18125059 0 P 0 ;1,3=67,5=0.000000
L 3.82586663 -1.18125059 3.82026614 -1.19375246 0 P 0 ;1,3=67,5=0.000000
L 3.82026614 -1.19375246 3.8183999 -1.205 0 P 0 ;1,3=67,5=0.000000
L 3.8183999 -1.205 3.8576 -1.205 0 P 0 ;1,3=67,5=0.000000
L 3.91299911 -1.13 3.90553228 -1.13249951 0 P 0 ;1,3=67,5=0.000000
L 3.90553228 -1.13249951 3.89993346 -1.13875049 0 P 0 ;1,3=67,5=0.000000
L 3.89993346 -1.13875049 3.89619931 -1.14624882 0 P 0 ;1,3=67,5=0.000000
L 3.89619931 -1.14624882 3.8933999 -1.15625128 0 P 0 ;1,3=67,5=0.000000
L 3.8933999 -1.15625128 3.89246673 -1.16750118 0 P 0 ;1,3=67,5=0.000000
L 3.89246673 -1.16750118 3.8933999 -1.17875108 0 P 0 ;1,3=67,5=0.000000
L 3.8933999 -1.17875108 3.89619931 -1.18875128 0 P 0 ;1,3=67,5=0.000000
L 3.89619931 -1.18875128 3.89993346 -1.19625187 0 P 0 ;1,3=67,5=0.000000
L 3.89993346 -1.19625187 3.90553228 -1.20250059 0 P 0 ;1,3=67,5=0.000000
L 3.90553228 -1.20250059 3.91299911 -1.205 0 P 0 ;1,3=67,5=0.000000
L 3.91299911 -1.205 3.92046585 -1.20250059 0 P 0 ;1,3=67,5=0.000000
L 3.92046585 -1.20250059 3.92606644 -1.19625187 0 P 0 ;1,3=67,5=0.000000
L 3.92606644 -1.19625187 3.92980059 -1.18875128 0 P 0 ;1,3=67,5=0.000000
L 3.92980059 -1.18875128 3.9326 -1.17875108 0 P 0 ;1,3=67,5=0.000000
L 3.9326 -1.17875108 3.93353317 -1.16750118 0 P 0 ;1,3=67,5=0.000000
L 3.93353317 -1.16750118 3.9326 -1.15625128 0 P 0 ;1,3=67,5=0.000000
L 3.9326 -1.15625128 3.92980059 -1.14624882 0 P 0 ;1,3=67,5=0.000000
L 3.92980059 -1.14624882 3.92606644 -1.13875049 0 P 0 ;1,3=67,5=0.000000
L 3.92606644 -1.13875049 3.92046585 -1.13249951 0 P 0 ;1,3=67,5=0.000000
L 3.92046585 -1.13249951 3.91299911 -1.13 0 P 0 ;1,3=67,5=0.000000
L 3.97026614 -1.1424997 3.97586663 -1.13500128 0 P 0 ;1,3=67,5=0.000000
L 3.97586663 -1.13500128 3.9824003 -1.1312498 0 P 0 ;1,3=67,5=0.000000
L 3.9824003 -1.1312498 3.98986703 -1.13 0 P 0 ;1,3=67,5=0.000000
L 3.98986703 -1.13 3.9992001 -1.13249951 0 P 0 ;1,3=67,5=0.000000
L 3.9992001 -1.13249951 4.00573376 -1.13875049 0 P 0 ;1,3=67,5=0.000000
L 4.00573376 -1.13875049 4.0076 -1.14624882 0 P 0 ;1,3=67,5=0.000000
L 4.0076 -1.14624882 4.00666693 -1.15375187 0 P 0 ;1,3=67,5=0.000000
L 4.00666693 -1.15375187 4.00293268 -1.16000049 0 P 0 ;1,3=67,5=0.000000
L 4.00293268 -1.16000049 3.98426654 -1.1725001 0 P 0 ;1,3=67,5=0.000000
L 3.98426654 -1.1725001 3.97586663 -1.18125059 0 P 0 ;1,3=67,5=0.000000
L 3.97586663 -1.18125059 3.97026614 -1.19375246 0 P 0 ;1,3=67,5=0.000000
L 3.97026614 -1.19375246 3.9683999 -1.205 0 P 0 ;1,3=67,5=0.000000
L 3.9683999 -1.205 4.0076 -1.205 0 P 0 ;1,3=67,5=0.000000
L 4.04526614 -1.1424997 4.05086663 -1.13500128 0 P 0 ;1,3=67,5=0.000000
L 4.05086663 -1.13500128 4.0574003 -1.1312498 0 P 0 ;1,3=67,5=0.000000
L 4.0574003 -1.1312498 4.06486703 -1.13 0 P 0 ;1,3=67,5=0.000000
L 4.06486703 -1.13 4.0742001 -1.13249951 0 P 0 ;1,3=67,5=0.000000
L 4.0742001 -1.13249951 4.08073376 -1.13875049 0 P 0 ;1,3=67,5=0.000000
L 4.08073376 -1.13875049 4.0826 -1.14624882 0 P 0 ;1,3=67,5=0.000000
L 4.0826 -1.14624882 4.08166693 -1.15375187 0 P 0 ;1,3=67,5=0.000000
L 4.08166693 -1.15375187 4.07793268 -1.16000049 0 P 0 ;1,3=67,5=0.000000
L 4.07793268 -1.16000049 4.05926654 -1.1725001 0 P 0 ;1,3=67,5=0.000000
L 4.05926654 -1.1725001 4.05086663 -1.18125059 0 P 0 ;1,3=67,5=0.000000
L 4.05086663 -1.18125059 4.04526614 -1.19375246 0 P 0 ;1,3=67,5=0.000000
L 4.04526614 -1.19375246 4.0433999 -1.205 0 P 0 ;1,3=67,5=0.000000
L 4.0433999 -1.205 4.0826 -1.205 0 P 0 ;1,3=67,5=0.000000
L 4.12586663 -1.18000079 4.15013327 -1.18000079 0 P 0 ;1,3=67,5=0.000000
L 4.21299911 -1.13 4.20553228 -1.13249951 0 P 0 ;1,3=67,5=0.000000
L 4.20553228 -1.13249951 4.19993346 -1.13875049 0 P 0 ;1,3=67,5=0.000000
L 4.19993346 -1.13875049 4.19619931 -1.14624882 0 P 0 ;1,3=67,5=0.000000
L 4.19619931 -1.14624882 4.1933999 -1.15625128 0 P 0 ;1,3=67,5=0.000000
L 4.1933999 -1.15625128 4.19246673 -1.16750118 0 P 0 ;1,3=67,5=0.000000
L 4.19246673 -1.16750118 4.1933999 -1.17875108 0 P 0 ;1,3=67,5=0.000000
L 4.1933999 -1.17875108 4.19619931 -1.18875128 0 P 0 ;1,3=67,5=0.000000
L 4.19619931 -1.18875128 4.19993346 -1.19625187 0 P 0 ;1,3=67,5=0.000000
L 4.19993346 -1.19625187 4.20553228 -1.20250059 0 P 0 ;1,3=67,5=0.000000
L 4.20553228 -1.20250059 4.21299911 -1.205 0 P 0 ;1,3=67,5=0.000000
L 4.21299911 -1.205 4.22046585 -1.20250059 0 P 0 ;1,3=67,5=0.000000
L 4.22046585 -1.20250059 4.22606644 -1.19625187 0 P 0 ;1,3=67,5=0.000000
L 4.22606644 -1.19625187 4.22980059 -1.18875128 0 P 0 ;1,3=67,5=0.000000
L 4.22980059 -1.18875128 4.2326 -1.17875108 0 P 0 ;1,3=67,5=0.000000
L 4.2326 -1.17875108 4.23353317 -1.16750118 0 P 0 ;1,3=67,5=0.000000
L 4.23353317 -1.16750118 4.2326 -1.15625128 0 P 0 ;1,3=67,5=0.000000
L 4.2326 -1.15625128 4.22980059 -1.14624882 0 P 0 ;1,3=67,5=0.000000
L 4.22980059 -1.14624882 4.22606644 -1.13875049 0 P 0 ;1,3=67,5=0.000000
L 4.22606644 -1.13875049 4.22046585 -1.13249951 0 P 0 ;1,3=67,5=0.000000
L 4.22046585 -1.13249951 4.21299911 -1.13 0 P 0 ;1,3=67,5=0.000000
L 4.27026614 -1.1424997 4.27586663 -1.13500128 0 P 0 ;1,3=67,5=0.000000
L 4.27586663 -1.13500128 4.2824003 -1.1312498 0 P 0 ;1,3=67,5=0.000000
L 4.2824003 -1.1312498 4.28986703 -1.13 0 P 0 ;1,3=67,5=0.000000
L 4.28986703 -1.13 4.2992001 -1.13249951 0 P 0 ;1,3=67,5=0.000000
L 4.2992001 -1.13249951 4.30573376 -1.13875049 0 P 0 ;1,3=67,5=0.000000
L 4.30573376 -1.13875049 4.3076 -1.14624882 0 P 0 ;1,3=67,5=0.000000
L 4.3076 -1.14624882 4.30666693 -1.15375187 0 P 0 ;1,3=67,5=0.000000
L 4.30666693 -1.15375187 4.30293268 -1.16000049 0 P 0 ;1,3=67,5=0.000000
L 4.30293268 -1.16000049 4.28426654 -1.1725001 0 P 0 ;1,3=67,5=0.000000
L 4.28426654 -1.1725001 4.27586663 -1.18125059 0 P 0 ;1,3=67,5=0.000000
L 4.27586663 -1.18125059 4.27026614 -1.19375246 0 P 0 ;1,3=67,5=0.000000
L 4.27026614 -1.19375246 4.2683999 -1.205 0 P 0 ;1,3=67,5=0.000000
L 4.2683999 -1.205 4.3076 -1.205 0 P 0 ;1,3=67,5=0.000000
L 4.35086663 -1.18000079 4.37513327 -1.18000079 0 P 0 ;1,3=67,5=0.000000
L 4.42026614 -1.1424997 4.42586663 -1.13500128 0 P 0 ;1,3=67,5=0.000000
L 4.42586663 -1.13500128 4.4324003 -1.1312498 0 P 0 ;1,3=67,5=0.000000
L 4.4324003 -1.1312498 4.43986703 -1.13 0 P 0 ;1,3=67,5=0.000000
L 4.43986703 -1.13 4.4492001 -1.13249951 0 P 0 ;1,3=67,5=0.000000
L 4.4492001 -1.13249951 4.45573376 -1.13875049 0 P 0 ;1,3=67,5=0.000000
L 4.45573376 -1.13875049 4.4576 -1.14624882 0 P 0 ;1,3=67,5=0.000000
L 4.4576 -1.14624882 4.45666693 -1.15375187 0 P 0 ;1,3=67,5=0.000000
L 4.45666693 -1.15375187 4.45293268 -1.16000049 0 P 0 ;1,3=67,5=0.000000
L 4.45293268 -1.16000049 4.43426654 -1.1725001 0 P 0 ;1,3=67,5=0.000000
L 4.43426654 -1.1725001 4.42586663 -1.18125059 0 P 0 ;1,3=67,5=0.000000
L 4.42586663 -1.18125059 4.42026614 -1.19375246 0 P 0 ;1,3=67,5=0.000000
L 4.42026614 -1.19375246 4.4183999 -1.205 0 P 0 ;1,3=67,5=0.000000
L 4.4183999 -1.205 4.4576 -1.205 0 P 0 ;1,3=67,5=0.000000
L 4.49246673 -1.19375246 4.49806555 -1.20000108 0 P 0 ;1,3=67,5=0.000000
L 4.49806555 -1.20000108 4.50459921 -1.2037503 0 P 0 ;1,3=67,5=0.000000
L 4.50459921 -1.2037503 4.51299911 -1.205 0 P 0 ;1,3=67,5=0.000000
L 4.51299911 -1.205 4.52140069 -1.20250059 0 P 0 ;1,3=67,5=0.000000
L 4.52140069 -1.20250059 4.52793268 -1.19750167 0 P 0 ;1,3=67,5=0.000000
L 4.52793268 -1.19750167 4.5326 -1.18875128 0 P 0 ;1,3=67,5=0.000000
L 4.5326 -1.18875128 4.53353317 -1.17875108 0 P 0 ;1,3=67,5=0.000000
L 4.53353317 -1.17875108 4.53166693 -1.16875089 0 P 0 ;1,3=67,5=0.000000
L 4.53166693 -1.16875089 4.52699951 -1.1625 0 P 0 ;1,3=67,5=0.000000
L 4.52699951 -1.1625 4.52046585 -1.15750108 0 P 0 ;1,3=67,5=0.000000
L 4.52046585 -1.15750108 4.51393396 -1.15625128 0 P 0 ;1,3=67,5=0.000000
L 4.51393396 -1.15625128 4.5074003 -1.15750108 0 P 0 ;1,3=67,5=0.000000
L 4.5074003 -1.15750108 4.49900039 -1.1625 0 P 0 ;1,3=67,5=0.000000
L 4.49900039 -1.1625 4.5017998 -1.13 0 P 0 ;1,3=67,5=0.000000
L 4.5017998 -1.13 4.52699951 -1.13 0 P 0 ;1,3=67,5=0.000000
L 3.29433297 -1.255 3.29433297 -1.33 0 P 0 ;1,3=68,5=0.000000
L 3.29433297 -1.33 3.33166693 -1.33 0 P 0 ;1,3=68,5=0.000000
L 3.40480059 -1.33 3.40480059 -1.28000157 0 P 0 ;1,3=68,5=0.000000
L 3.40480059 -1.2887497 3.40106644 -1.28375079 0 P 0 ;1,3=68,5=0.000000
L 3.40106644 -1.28375079 3.39546585 -1.28125128 0 P 0 ;1,3=68,5=0.000000
L 3.39546585 -1.28125128 3.38893396 -1.28000157 0 P 0 ;1,3=68,5=0.000000
L 3.38893396 -1.28000157 3.3824003 -1.28250108 0 P 0 ;1,3=68,5=0.000000
L 3.3824003 -1.28250108 3.3767998 -1.2875 0 P 0 ;1,3=68,5=0.000000
L 3.3767998 -1.2875 3.37306555 -1.29500069 0 P 0 ;1,3=68,5=0.000000
L 3.37306555 -1.29500069 3.37119931 -1.30500079 0 P 0 ;1,3=68,5=0.000000
L 3.37119931 -1.30500079 3.37306555 -1.31500098 0 P 0 ;1,3=68,5=0.000000
L 3.37306555 -1.31500098 3.3767998 -1.32250167 0 P 0 ;1,3=68,5=0.000000
L 3.3767998 -1.32250167 3.3824003 -1.32750059 0 P 0 ;1,3=68,5=0.000000
L 3.3824003 -1.32750059 3.38893396 -1.33 0 P 0 ;1,3=68,5=0.000000
L 3.38893396 -1.33 3.39546585 -1.3287503 0 P 0 ;1,3=68,5=0.000000
L 3.39546585 -1.3287503 3.40106644 -1.32500108 0 P 0 ;1,3=68,5=0.000000
L 3.40106644 -1.32500108 3.40480059 -1.32000217 0 P 0 ;1,3=68,5=0.000000
L 3.4433999 -1.3524997 3.44900039 -1.35499921 0 P 0 ;1,3=68,5=0.000000
L 3.44900039 -1.35499921 3.45646713 -1.3524997 0 P 0 ;1,3=68,5=0.000000
L 3.45646713 -1.3524997 3.46113287 -1.34750079 0 P 0 ;1,3=68,5=0.000000
L 3.46113287 -1.34750079 3.46486703 -1.3412498 0 P 0 ;1,3=68,5=0.000000
L 3.46486703 -1.3412498 3.47046585 -1.32125187 0 P 0 ;1,3=68,5=0.000000
L 3.47046585 -1.32125187 3.4826 -1.28000157 0 P 0 ;1,3=68,5=0.000000
L 3.45273287 -1.28000157 3.47046585 -1.32125187 0 P 0 ;1,3=68,5=0.000000
L 3.52400039 -1.29625039 3.55386752 -1.29625039 0 P 0 ;1,3=68,5=0.000000
L 3.55386752 -1.29625039 3.55106644 -1.2875 0 P 0 ;1,3=68,5=0.000000
L 3.55106644 -1.2875 3.54640069 -1.28250108 0 P 0 ;1,3=68,5=0.000000
L 3.54640069 -1.28250108 3.53986703 -1.28000157 0 P 0 ;1,3=68,5=0.000000
L 3.53986703 -1.28000157 3.53333346 -1.28125128 0 P 0 ;1,3=68,5=0.000000
L 3.53333346 -1.28125128 3.52773287 -1.28500049 0 P 0 ;1,3=68,5=0.000000
L 3.52773287 -1.28500049 3.52400039 -1.29375089 0 P 0 ;1,3=68,5=0.000000
L 3.52400039 -1.29375089 3.52213238 -1.30125157 0 P 0 ;1,3=68,5=0.000000
L 3.52213238 -1.30125157 3.52213238 -1.30875 0 P 0 ;1,3=68,5=0.000000
L 3.52213238 -1.30875 3.52400039 -1.31625069 0 P 0 ;1,3=68,5=0.000000
L 3.52400039 -1.31625069 3.52866604 -1.32375138 0 P 0 ;1,3=68,5=0.000000
L 3.52866604 -1.32375138 3.53426654 -1.3287503 0 P 0 ;1,3=68,5=0.000000
L 3.53426654 -1.3287503 3.5408002 -1.33 0 P 0 ;1,3=68,5=0.000000
L 3.5408002 -1.33 3.54733386 -1.32750059 0 P 0 ;1,3=68,5=0.000000
L 3.54733386 -1.32750059 3.55386752 -1.32000217 0 P 0 ;1,3=68,5=0.000000
L 3.59993346 -1.33 3.59993346 -1.28000157 0 P 0 ;1,3=68,5=0.000000
L 3.59993346 -1.28999941 3.60459921 -1.28500049 0 P 0 ;1,3=68,5=0.000000
L 3.60459921 -1.28500049 3.60926654 -1.28125128 0 P 0 ;1,3=68,5=0.000000
L 3.60926654 -1.28125128 3.6158002 -1.28000157 0 P 0 ;1,3=68,5=0.000000
L 3.6158002 -1.28000157 3.62046585 -1.28125128 0 P 0 ;1,3=68,5=0.000000
L 3.62046585 -1.28125128 3.62606644 -1.28500049 0 P 0 ;1,3=68,5=0.000000
L 3.68799911 -1.33249941 3.68613287 -1.3312497 0 P 0 ;1,3=68,5=0.000000
L 3.68613287 -1.3312497 3.68613287 -1.3287503 0 P 0 ;1,3=68,5=0.000000
L 3.68613287 -1.3287503 3.68799911 -1.32750059 0 P 0 ;1,3=68,5=0.000000
L 3.68799911 -1.32750059 3.68986703 -1.3287503 0 P 0 ;1,3=68,5=0.000000
L 3.68986703 -1.3287503 3.68986703 -1.3312497 0 P 0 ;1,3=68,5=0.000000
L 3.68986703 -1.3312497 3.68799911 -1.33249941 0 P 0 ;1,3=68,5=0.000000
L 3.68799911 -1.29875217 3.68613287 -1.2975001 0 P 0 ;1,3=68,5=0.000000
L 3.68613287 -1.2975001 3.68613287 -1.29500069 0 P 0 ;1,3=68,5=0.000000
L 3.68613287 -1.29500069 3.68799911 -1.29375089 0 P 0 ;1,3=68,5=0.000000
L 3.68799911 -1.29375089 3.68986703 -1.29500069 0 P 0 ;1,3=68,5=0.000000
L 3.68986703 -1.29500069 3.68986703 -1.2975001 0 P 0 ;1,3=68,5=0.000000
L 3.68986703 -1.2975001 3.68799911 -1.29875217 0 P 0 ;1,3=68,5=0.000000
L 3.36933297 -1.08 3.36933297 -1.005 0 P 0 ;1,3=69,5=0.000000
L 3.36933297 -1.005 3.39266644 -1.005 0 P 0 ;1,3=69,5=0.000000
L 3.39266644 -1.005 3.40013327 -1.00875157 0 P 0 ;1,3=69,5=0.000000
L 3.40013327 -1.00875157 3.40480059 -1.01375049 0 P 0 ;1,3=69,5=0.000000
L 3.40480059 -1.01375049 3.40666693 -1.02375059 0 P 0 ;1,3=69,5=0.000000
L 3.40666693 -1.02375059 3.40480059 -1.03375079 0 P 0 ;1,3=69,5=0.000000
L 3.40480059 -1.03375079 3.3992001 -1.03999941 0 P 0 ;1,3=69,5=0.000000
L 3.3992001 -1.03999941 3.39266644 -1.04375089 0 P 0 ;1,3=69,5=0.000000
L 3.39266644 -1.04375089 3.36933297 -1.04375089 0 P 0 ;1,3=69,5=0.000000
L 3.39266644 -1.04375089 3.40666693 -1.08 0 P 0 ;1,3=69,5=0.000000
L 3.44900039 -1.04625039 3.47886752 -1.04625039 0 P 0 ;1,3=69,5=0.000000
L 3.47886752 -1.04625039 3.47606644 -1.0375 0 P 0 ;1,3=69,5=0.000000
L 3.47606644 -1.0375 3.47140069 -1.03250108 0 P 0 ;1,3=69,5=0.000000
L 3.47140069 -1.03250108 3.46486703 -1.03000157 0 P 0 ;1,3=69,5=0.000000
L 3.46486703 -1.03000157 3.45833346 -1.03125128 0 P 0 ;1,3=69,5=0.000000
L 3.45833346 -1.03125128 3.45273287 -1.03500049 0 P 0 ;1,3=69,5=0.000000
L 3.45273287 -1.03500049 3.44900039 -1.04375089 0 P 0 ;1,3=69,5=0.000000
L 3.44900039 -1.04375089 3.44713238 -1.05125157 0 P 0 ;1,3=69,5=0.000000
L 3.44713238 -1.05125157 3.44713238 -1.05875 0 P 0 ;1,3=69,5=0.000000
L 3.44713238 -1.05875 3.44900039 -1.06625069 0 P 0 ;1,3=69,5=0.000000
L 3.44900039 -1.06625069 3.45366604 -1.07375138 0 P 0 ;1,3=69,5=0.000000
L 3.45366604 -1.07375138 3.45926654 -1.0787503 0 P 0 ;1,3=69,5=0.000000
L 3.45926654 -1.0787503 3.4658002 -1.08 0 P 0 ;1,3=69,5=0.000000
L 3.4658002 -1.08 3.47233386 -1.07750059 0 P 0 ;1,3=69,5=0.000000
L 3.47233386 -1.07750059 3.47886752 -1.07000217 0 P 0 ;1,3=69,5=0.000000
L 3.52119931 -1.03000157 3.53799911 -1.08 0 P 0 ;1,3=69,5=0.000000
L 3.53799911 -1.08 3.55480059 -1.03000157 0 P 0 ;1,3=69,5=0.000000
L 3.68799911 -1.08249941 3.68613287 -1.0812497 0 P 0 ;1,3=69,5=0.000000
L 3.68613287 -1.0812497 3.68613287 -1.0787503 0 P 0 ;1,3=69,5=0.000000
L 3.68613287 -1.0787503 3.68799911 -1.07750059 0 P 0 ;1,3=69,5=0.000000
L 3.68799911 -1.07750059 3.68986703 -1.0787503 0 P 0 ;1,3=69,5=0.000000
L 3.68986703 -1.0787503 3.68986703 -1.0812497 0 P 0 ;1,3=69,5=0.000000
L 3.68986703 -1.0812497 3.68799911 -1.08249941 0 P 0 ;1,3=69,5=0.000000
L 3.68799911 -1.04875217 3.68613287 -1.0475001 0 P 0 ;1,3=69,5=0.000000
L 3.68613287 -1.0475001 3.68613287 -1.04500069 0 P 0 ;1,3=69,5=0.000000
L 3.68613287 -1.04500069 3.68799911 -1.04375089 0 P 0 ;1,3=69,5=0.000000
L 3.68799911 -1.04375089 3.68986703 -1.04500069 0 P 0 ;1,3=69,5=0.000000
L 3.68986703 -1.04500069 3.68986703 -1.0475001 0 P 0 ;1,3=69,5=0.000000
L 3.68986703 -1.0475001 3.68799911 -1.04875217 0 P 0 ;1,3=69,5=0.000000
L 3.83799911 -1.005 3.83053228 -1.00749951 0 P 0 ;1,3=69,5=0.000000
L 3.83053228 -1.00749951 3.82493346 -1.01375049 0 P 0 ;1,3=69,5=0.000000
L 3.82493346 -1.01375049 3.82119931 -1.02124882 0 P 0 ;1,3=69,5=0.000000
L 3.82119931 -1.02124882 3.8183999 -1.03125128 0 P 0 ;1,3=69,5=0.000000
L 3.8183999 -1.03125128 3.81746673 -1.04250118 0 P 0 ;1,3=69,5=0.000000
L 3.81746673 -1.04250118 3.8183999 -1.05375108 0 P 0 ;1,3=69,5=0.000000
L 3.8183999 -1.05375108 3.82119931 -1.06375128 0 P 0 ;1,3=69,5=0.000000
L 3.82119931 -1.06375128 3.82493346 -1.07125187 0 P 0 ;1,3=69,5=0.000000
L 3.82493346 -1.07125187 3.83053228 -1.07750059 0 P 0 ;1,3=69,5=0.000000
L 3.83053228 -1.07750059 3.83799911 -1.08 0 P 0 ;1,3=69,5=0.000000
L 3.83799911 -1.08 3.84546585 -1.07750059 0 P 0 ;1,3=69,5=0.000000
L 3.84546585 -1.07750059 3.85106644 -1.07125187 0 P 0 ;1,3=69,5=0.000000
L 3.85106644 -1.07125187 3.85480059 -1.06375128 0 P 0 ;1,3=69,5=0.000000
L 3.85480059 -1.06375128 3.8576 -1.05375108 0 P 0 ;1,3=69,5=0.000000
L 3.8576 -1.05375108 3.85853317 -1.04250118 0 P 0 ;1,3=69,5=0.000000
L 3.85853317 -1.04250118 3.8576 -1.03125128 0 P 0 ;1,3=69,5=0.000000
L 3.8576 -1.03125128 3.85480059 -1.02124882 0 P 0 ;1,3=69,5=0.000000
L 3.85480059 -1.02124882 3.85106644 -1.01375049 0 P 0 ;1,3=69,5=0.000000
L 3.85106644 -1.01375049 3.84546585 -1.00749951 0 P 0 ;1,3=69,5=0.000000
L 3.84546585 -1.00749951 3.83799911 -1.005 0 P 0 ;1,3=69,5=0.000000
L 3.91299911 -1.08 3.91299911 -1.005 0 P 0 ;1,3=69,5=0.000000
L 3.91299911 -1.005 3.9017998 -1.01999911 0 P 0 ;1,3=69,5=0.000000
L 3.9017998 -1.08 3.92419843 -1.08 0 P 0 ;1,3=69,5=0.000000
S P 0
OB 1.6515 3.011 I
OS 1.7085 3.011
OS 1.7085 2.99
OS 1.70848996063 2.98998996063
OC 1.6985 2.9995 1.6985 2.989497933071 N
OC 1.6885 2.9895 1.6985 2.9895 N
OC 1.6978 2.979519980315 1.698504822835 2.989499901575 N
OS 1.6978 2.9795
OS 1.6515 2.9795
OS 1.6515 3.011
OE
SE
S P 0
OB 1.6515 3.019 I
OS 1.6515 3.0405
OC 1.6615 3.0505 1.6615 3.0405 N
OS 1.7085 3.0505
OS 1.7085 3.019
OS 1.6515 3.019
OE
SE
S P 0
OB 5.0897 2.7425 I
OS 5.1365 2.7425
OS 5.1365 2.711
OS 5.0795 2.711
OS 5.0795 2.7323
OC 5.0895 2.7225 5.0895 2.732502066929 N
OC 5.0995 2.7325 5.0895 2.7325 N
OC 5.0897 2.7425 5.089497933071 2.7325 N
OE
SE
S P 0
OB 5.1365 2.703 I
OS 5.1365 2.6815
OC 5.1265 2.6715 5.1265 2.6815 N
OS 5.0795 2.6715
OS 5.0795 2.703
OS 5.1365 2.703
OE
SE
S P 0
OB 5.5965 0.675 I
OS 5.6535 0.675
OS 5.6535 0.6542
OS 5.653480019685 0.654180019685
OC 5.6435 0.6635 5.6435 0.653496653543 N
OC 5.6335 0.6535 5.6435 0.6535 N
OC 5.6429 0.643519980315 5.643497933071 0.6535 N
OS 5.6429 0.6435
OS 5.5965 0.6435
OS 5.5965 0.675
OE
SE
S P 0
OB 5.5965 0.683 I
OS 5.5965 0.7045
OC 5.6065 0.7145 5.6065 0.7045 N
OS 5.6535 0.7145
OS 5.6535 0.683
OS 5.5965 0.683
OE
SE
S P 0
OB 3.9475 2.9165 I
OS 3.916 2.9165
OS 3.916 2.9735
OS 3.9475 2.9735
OS 3.9475 2.9165
OE
SE
S P 0
OB 3.908 2.9165 I
OS 3.8865 2.9165
OC 3.8765 2.9265 3.8865 2.9265 N
OS 3.8765 2.9735
OS 3.908 2.9735
OS 3.908 2.9165
OE
SE
S P 0
OB 4.3915 2.924 I
OS 4.3915 2.88
OS 4.36 2.88
OS 4.36 2.924
OS 4.3915 2.924
OE
SE
S P 0
OB 4.352 2.872 I
OS 4.352 2.828
OS 4.3205 2.828
OS 4.3205 2.872
OS 4.352 2.872
OE
SE
S P 0
OB 4.3915 2.872 I
OS 4.3915 2.838
OC 4.3815 2.828 4.3815 2.838 N
OS 4.36 2.828
OS 4.36 2.872
OS 4.3915 2.872
OE
SE
S P 0
OB 4.3205 2.88 I
OS 4.3205 2.914
OC 4.3305 2.924 4.3305 2.914 N
OS 4.352 2.924
OS 4.352 2.88
OS 4.3205 2.88
OE
SE
S P 0
OB 4.132669980315 4.0085 I
OS 4.155330019685 4.0085
OC 4.1605 4.003330019685 4.1645 4.0125 N
OS 4.1605 3.980669980315
OC 4.155330019685 3.9755 4.1645 3.9715 N
OS 4.132669980315 3.9755
OC 4.1275 3.980669980315 4.1235 3.9715 N
OS 4.1275 4.003330019685
OC 4.132669980315 4.0085 4.1235 4.0125 N
OE
SE
S P 0
OB 4.0865 4.0085 I
OS 4.114330019685 4.0085
OC 4.1195 4.003330019685 4.1235 4.0125 N
OS 4.1195 3.9755
OS 4.0865 3.9755
OS 4.0865 4.0085
OE
SE
S P 0
OB 4.1275 4.0495 I
OS 4.1605 4.0495
OS 4.1605 4.021669980315
OC 4.155330019685 4.0165 4.1645 4.0125 N
OS 4.132669980315 4.0165
OC 4.1275 4.021669980315 4.1235 4.0125 N
OS 4.1275 4.0495
OE
SE
S P 0
OB 4.173669980315 4.0085 I
OS 4.2015 4.0085
OS 4.2015 3.9755
OS 4.173669980315 3.9755
OC 4.1685 3.980669980315 4.1645 3.9715 N
OS 4.1685 4.003330019685
OC 4.173669980315 4.0085 4.1645 4.0125 N
OE
SE
S P 0
OB 4.132669980315 3.9675 I
OS 4.155330019685 3.9675
OC 4.1605 3.962330019685 4.1645 3.9715 N
OS 4.1605 3.9345
OS 4.1275 3.9345
OS 4.1275 3.962330019685
OC 4.132669980315 3.9675 4.1235 3.9715 N
OE
SE
S P 0
OB 4.173669980315 3.9675 I
OS 4.2015 3.9675
OS 4.2015 3.9446
OC 4.1915 3.9545 4.1915 3.944499507874 N
OC 4.1815 3.9445 4.1915 3.9445 N
OC 4.1913 3.9345 4.191502066929 3.9445 N
OS 4.1685 3.9345
OS 4.1685 3.962330019685
OC 4.173669980315 3.9675 4.1645 3.9715 N
OE
SE
S P 0
OB 4.0865 3.9675 I
OS 4.114330019685 3.9675
OC 4.1195 3.962330019685 4.1235 3.9715 N
OS 4.1195 3.9345
OS 4.0967 3.9345
OC 4.1065 3.9445 4.096497933071 3.9445 N
OC 4.0965 3.9545 4.0965 3.9445 N
OC 4.086519980315 3.9451 4.0965 3.944502066929 N
OS 4.0865 3.9451
OS 4.0865 3.9675
OE
SE
S P 0
OB 4.0966 4.0495 I
OS 4.1195 4.0495
OS 4.1195 4.021669980315
OC 4.114330019685 4.0165 4.1235 4.0125 N
OS 4.0865 4.0165
OS 4.0865 4.039
OS 4.08651003937 4.039
OC 4.0965 4.0295 4.096500098425 4.03950265748 N
OC 4.1065 4.0395 4.0965 4.0395 N
OC 4.0966 4.0495 4.096499507874 4.0395 N
OE
SE
S P 0
OB 4.1685 4.0495 I
OS 4.1911 4.0495
OS 4.19111003937 4.04948996063
OC 4.1815 4.0395 4.19149753937 4.039499901575 N
OC 4.1915 4.0295 4.1915 4.0395 N
OC 4.2015 4.0393 4.1915 4.039502066929 N
OS 4.2015 4.0165
OS 4.173669980315 4.0165
OC 4.1685 4.021669980315 4.1645 4.0125 N
OS 4.1685 4.0495
OE
SE
S P 0
OB 2.854669980315 1.090069980315 I
OS 2.854669980315 1.079469980315
OC 2.821630019685 1.046430019685 2.860669291339 1.040430708661 N
OS 2.811030019685 1.046430019685
OC 2.854669980315 1.090069980315 2.860670570866 1.040429429134 Y
OE
SE
S P 0
OB 2.811030019685 1.034430019685 I
OS 2.821630019685 1.034430019685
OC 2.854669980315 1.00138996063 2.860669291339 1.040429232283 N
OS 2.854669980315 0.99078996063
OC 2.811030019685 1.034430019685 2.860670570866 1.040430511811 Y
OE
SE
S P 0
OB 2.866669980315 0.99078996063 I
OS 2.866669980315 1.00138996063
OC 2.89971003937 1.034430019685 2.860670767717 1.040429232283 N
OS 2.91031003937 1.034430019685
OC 2.866669980315 0.99078996063 2.860669488189 1.040430511811 Y
OE
SE
S P 0
OB 2.91031003937 1.046430019685 I
OS 2.89971003937 1.046430019685
OC 2.866669980315 1.079469980315 2.860670767717 1.040430708661 N
OS 2.866669980315 1.090069980315
OC 2.91031003937 1.046430019685 2.860669488189 1.040429429134 Y
OE
SE
S P 0
OB 2.82831003937 0.940430019685 I
OS 2.81771003937 0.940430019685
OC 2.784669980315 0.973469980315 2.778670767717 0.934430708661 N
OS 2.784669980315 0.984069980315
OC 2.82831003937 0.940430019685 2.778669488189 0.934429429134 Y
OE
SE
S P 0
OB 2.784669980315 0.88478996063 I
OS 2.784669980315 0.89538996063
OC 2.81771003937 0.928430019685 2.778670767717 0.934429232283 N
OS 2.82831003937 0.928430019685
OC 2.784669980315 0.88478996063 2.778669488189 0.934430511811 Y
OE
SE
S P 0
OB 2.729030019685 0.928430019685 I
OS 2.739630019685 0.928430019685
OC 2.772669980315 0.89538996063 2.778669291339 0.934429232283 N
OS 2.772669980315 0.88478996063
OC 2.729030019685 0.928430019685 2.778670570866 0.934430511811 Y
OE
SE
S P 0
OB 2.772669980315 0.984069980315 I
OS 2.772669980315 0.973469980315
OC 2.739630019685 0.940430019685 2.778669291339 0.934430708661 N
OS 2.729030019685 0.940430019685
OC 2.772669980315 0.984069980315 2.778670570866 0.934429429134 Y
OE
SE
S P 0
OB 2.70931003937 0.940430019685 I
OS 2.69871003937 0.940430019685
OC 2.665669980315 0.973469980315 2.659670767717 0.934430708661 N
OS 2.665669980315 0.984069980315
OC 2.70931003937 0.940430019685 2.659669488189 0.934429429134 Y
OE
SE
S P 0
OB 2.665669980315 0.88478996063 I
OS 2.665669980315 0.89538996063
OC 2.69871003937 0.928430019685 2.659670767717 0.934429232283 N
OS 2.70931003937 0.928430019685
OC 2.665669980315 0.88478996063 2.659669488189 0.934430511811 Y
OE
SE
S P 0
OB 2.610030019685 0.928430019685 I
OS 2.620630019685 0.928430019685
OC 2.653669980315 0.89538996063 2.659669291339 0.934429232283 N
OS 2.653669980315 0.88478996063
OC 2.610030019685 0.928430019685 2.659670570866 0.934430511811 Y
OE
SE
S P 0
OB 2.653669980315 0.984069980315 I
OS 2.653669980315 0.973469980315
OC 2.620630019685 0.940430019685 2.659669291339 0.934430708661 N
OS 2.610030019685 0.940430019685
OC 2.653669980315 0.984069980315 2.659670570866 0.934429429134 Y
OE
SE
S P 0
OB 2.58931003937 0.940430019685 I
OS 2.57871003937 0.940430019685
OC 2.545669980315 0.973469980315 2.539670767717 0.934430708661 N
OS 2.545669980315 0.984069980315
OC 2.58931003937 0.940430019685 2.539669488189 0.934429429134 Y
OE
SE
S P 0
OB 2.545669980315 0.88478996063 I
OS 2.545669980315 0.89538996063
OC 2.57871003937 0.928430019685 2.539670767717 0.934429232283 N
OS 2.58931003937 0.928430019685
OC 2.545669980315 0.88478996063 2.539669488189 0.934430511811 Y
OE
SE
S P 0
OB 2.490030019685 0.928430019685 I
OS 2.500630019685 0.928430019685
OC 2.533669980315 0.89538996063 2.539669291339 0.934429232283 N
OS 2.533669980315 0.88478996063
OC 2.490030019685 0.928430019685 2.539670570866 0.934430511811 Y
OE
SE
S P 0
OB 2.533669980315 0.984069980315 I
OS 2.533669980315 0.973469980315
OC 2.500630019685 0.940430019685 2.539669291339 0.934430708661 N
OS 2.490030019685 0.940430019685
OC 2.533669980315 0.984069980315 2.539670570866 0.934429429134 Y
OE
SE
S P 0
OB 1.254669980315 1.090069980315 I
OS 1.254669980315 1.079469980315
OC 1.221630019685 1.046430019685 1.260669291339 1.040430708661 N
OS 1.211030019685 1.046430019685
OC 1.254669980315 1.090069980315 1.260670570866 1.040429429134 Y
OE
SE
S P 0
OB 1.211030019685 1.034430019685 I
OS 1.221630019685 1.034430019685
OC 1.254669980315 1.00138996063 1.260669291339 1.040429232283 N
OS 1.254669980315 0.99078996063
OC 1.211030019685 1.034430019685 1.260670570866 1.040430511811 Y
OE
SE
S P 0
OB 1.266669980315 0.99078996063 I
OS 1.266669980315 1.00138996063
OC 1.29971003937 1.034430019685 1.260670767717 1.040429232283 N
OS 1.31031003937 1.034430019685
OC 1.266669980315 0.99078996063 1.260669488189 1.040430511811 Y
OE
SE
S P 0
OB 1.31031003937 1.046430019685 I
OS 1.29971003937 1.046430019685
OC 1.266669980315 1.079469980315 1.260670767717 1.040430708661 N
OS 1.266669980315 1.090069980315
OC 1.31031003937 1.046430019685 1.260669488189 1.040429429134 Y
OE
SE
S P 0
OB 2.91031003937 2.646430019685 I
OS 2.89971003937 2.646430019685
OC 2.866669980315 2.679469980315 2.860670767717 2.640430708661 N
OS 2.866669980315 2.690069980315
OC 2.91031003937 2.646430019685 2.860669488189 2.640429429134 Y
OE
SE
S P 0
OB 2.866669980315 2.59078996063 I
OS 2.866669980315 2.60138996063
OC 2.89971003937 2.634430019685 2.860670767717 2.640429232283 N
OS 2.91031003937 2.634430019685
OC 2.866669980315 2.59078996063 2.860669488189 2.640430511811 Y
OE
SE
S P 0
OB 2.811030019685 2.634430019685 I
OS 2.821630019685 2.634430019685
OC 2.854669980315 2.60138996063 2.860669291339 2.640429232283 N
OS 2.854669980315 2.59078996063
OC 2.811030019685 2.634430019685 2.860670570866 2.640430511811 Y
OE
SE
S P 0
OB 2.854669980315 2.690069980315 I
OS 2.854669980315 2.679469980315
OC 2.821630019685 2.646430019685 2.860669291339 2.640430708661 N
OS 2.811030019685 2.646430019685
OC 2.854669980315 2.690069980315 2.860670570866 2.640429429134 Y
OE
SE
S P 0
OB 1.31031003937 2.646430019685 I
OS 1.29971003937 2.646430019685
OC 1.266669980315 2.679469980315 1.260670767717 2.640430708661 N
OS 1.266669980315 2.690069980315
OC 1.31031003937 2.646430019685 1.260669488189 2.640429429134 Y
OE
SE
S P 0
OB 1.266669980315 2.59078996063 I
OS 1.266669980315 2.60138996063
OC 1.29971003937 2.634430019685 1.260670767717 2.640429232283 N
OS 1.31031003937 2.634430019685
OC 1.266669980315 2.59078996063 1.260669488189 2.640430511811 Y
OE
SE
S P 0
OB 1.211030019685 2.634430019685 I
OS 1.221630019685 2.634430019685
OC 1.254669980315 2.60138996063 1.260669291339 2.640429232283 N
OS 1.254669980315 2.59078996063
OC 1.211030019685 2.634430019685 1.260670570866 2.640430511811 Y
OE
SE
S P 0
OB 1.254669980315 2.690069980315 I
OS 1.254669980315 2.679469980315
OC 1.221630019685 2.646430019685 1.260669291339 2.640430708661 N
OS 1.211030019685 2.646430019685
OC 1.254669980315 2.690069980315 1.260670570866 2.640429429134 Y
OE
SE
S P 0
OB 1.254669980315 1.890069980315 I
OS 1.254669980315 1.879469980315
OC 1.221630019685 1.846430019685 1.260669291339 1.840430708661 N
OS 1.211030019685 1.846430019685
OC 1.254669980315 1.890069980315 1.260670570866 1.840429429134 Y
OE
SE
S P 0
OB 1.211030019685 1.834430019685 I
OS 1.221630019685 1.834430019685
OC 1.254669980315 1.80138996063 1.260669291339 1.840429232283 N
OS 1.254669980315 1.79078996063
OC 1.211030019685 1.834430019685 1.260670570866 1.840430511811 Y
OE
SE
S P 0
OB 1.266669980315 1.79078996063 I
OS 1.266669980315 1.80138996063
OC 1.29971003937 1.834430019685 1.260670767717 1.840429232283 N
OS 1.31031003937 1.834430019685
OC 1.266669980315 1.79078996063 1.260669488189 1.840430511811 Y
OE
SE
S P 0
OB 1.31031003937 1.846430019685 I
OS 1.29971003937 1.846430019685
OC 1.266669980315 1.879469980315 1.260670767717 1.840430708661 N
OS 1.266669980315 1.890069980315
OC 1.31031003937 1.846430019685 1.260669488189 1.840429429134 Y
OE
SE
S P 0
OB 5.994 2.1135 I
OS 6.0255 2.1135
OS 6.0255 2.0853
OS 6.025469980315 2.085269980315
OC 6.0155 2.0945 6.015499901575 2.084500295276 N
OC 6.0055 2.0845 6.0155 2.0845 N
OC 6.0146 2.07453996063 6.015500590551 2.084499901575 N
OS 6.0146 2.0745
OS 5.994 2.0745
OS 5.994 2.1135
OE
SE
S P 0
OB 5.9649 2.1135 I
OS 5.986 2.1135
OS 5.986 2.0745
OS 5.9545 2.0745
OS 5.9545 2.1029
OS 5.954519980315 2.1029
OC 5.9645 2.0935 5.9645 2.103497933071 N
OC 5.9745 2.1035 5.9645 2.1035 N
OC 5.9649 2.11348996063 5.964502066929 2.103499901575 N
OS 5.9649 2.1135
OE
SE
S P 0
OB 5.023719980315 4.114080019685 I
OS 5.0658 4.114080019685
OC 4.94693996063 3.995219980315 4.94093996063 4.120080019685 Y
OS 4.94693996063 4.0373
OC 5.023719980315 4.114080019685 4.94093996063 4.120080019685 N
OE
SE
S P 0
OB 4.94693996063 4.20286003937 I
OS 4.94693996063 4.24493996063
OC 5.0658 4.126080019685 4.940940059055 4.120080019685 Y
OS 5.023719980315 4.126080019685
OC 4.94693996063 4.20286003937 4.94093996063 4.120080019685 N
OE
SE
S P 0
OB 4.93493996063 4.0373 I
OS 4.93493996063 3.995219980315
OC 4.816080019685 4.114080019685 4.94093996063 4.12007992126 Y
OS 4.85816003937 4.114080019685
OC 4.93493996063 4.0373 4.94093996063 4.12007992126 N
OE
SE
S P 0
OB 4.85816003937 4.126080019685 I
OS 4.816080019685 4.126080019685
OC 4.93493996063 4.24493996063 4.94093996063 4.120080019685 Y
OS 4.93493996063 4.20286003937
OC 4.85816003937 4.126080019685 4.94093996063 4.12008011811 N
OE
SE
S P 0
OB 4.85816003937 3.10246003937 I
OS 4.816080019685 3.10246003937
OC 4.93493996063 3.221319980315 4.94093996063 3.09646003937 Y
OS 4.93493996063 3.17923996063
OC 4.85816003937 3.10246003937 4.94093996063 3.09646003937 N
OE
SE
S P 0
OB 4.93493996063 3.013680019685 I
OS 4.93493996063 2.9716
OC 4.816080019685 3.09046003937 4.94093996063 3.096459940945 Y
OS 4.85816003937 3.09046003937
OC 4.93493996063 3.013680019685 4.94093996063 3.096459940945 N
OE
SE
S P 0
OB 4.94693996063 3.17923996063 I
OS 4.94693996063 3.221319980315
OC 5.0658 3.10246003937 4.940940059055 3.09646003937 Y
OS 5.023719980315 3.10246003937
OC 4.94693996063 3.17923996063 4.940940059055 3.09646003937 N
OE
SE
S P 0
OB 5.023719980315 3.09046003937 I
OS 5.0658 3.09046003937
OC 4.94693996063 2.9716 4.94093996063 3.09646003937 Y
OS 4.94693996063 3.013680019685
OC 5.023719980315 3.09046003937 4.94093996063 3.09646003937 N
OE
SE
S P 0
OB 2.476280019685 4.126080019685 I
OS 2.4342 4.126080019685
OC 2.55306003937 4.24493996063 2.559059940945 4.120080019685 Y
OS 2.55306003937 4.20286003937
OC 2.476280019685 4.126080019685 2.55906003937 4.120080019685 N
OE
SE
S P 0
OB 2.55306003937 4.0373 I
OS 2.55306003937 3.995219980315
OC 2.4342 4.114080019685 2.55906003937 4.120080019685 Y
OS 2.476280019685 4.114080019685
OC 2.55306003937 4.0373 2.55906003937 4.120080019685 N
OE
SE
S P 0
OB 2.56506003937 4.20286003937 I
OS 2.56506003937 4.24493996063
OC 2.683919980315 4.126080019685 2.55906003937 4.120080019685 Y
OS 2.64183996063 4.126080019685
OC 2.56506003937 4.20286003937 2.55906003937 4.12008011811 N
OE
SE
S P 0
OB 2.64183996063 4.114080019685 I
OS 2.683919980315 4.114080019685
OC 2.56506003937 3.995219980315 2.55906003937 4.12007992126 Y
OS 2.56506003937 4.0373
OC 2.64183996063 4.114080019685 2.55906003937 4.12007992126 N
OE
SE
S P 0
OB 2.476280019685 3.10246003937 I
OS 2.4342 3.10246003937
OC 2.55306003937 3.221319980315 2.559059940945 3.09646003937 Y
OS 2.55306003937 3.17923996063
OC 2.476280019685 3.10246003937 2.559059940945 3.09646003937 N
OE
SE
S P 0
OB 2.55306003937 3.013680019685 I
OS 2.55306003937 2.9716
OC 2.4342 3.09046003937 2.55906003937 3.09646003937 Y
OS 2.476280019685 3.09046003937
OC 2.55306003937 3.013680019685 2.55906003937 3.09646003937 N
OE
SE
S P 0
OB 2.56506003937 3.17923996063 I
OS 2.56506003937 3.221319980315
OC 2.683919980315 3.10246003937 2.55906003937 3.09646003937 Y
OS 2.64183996063 3.10246003937
OC 2.56506003937 3.17923996063 2.55906003937 3.09646003937 N
OE
SE
S P 0
OB 2.64183996063 3.09046003937 I
OS 2.683919980315 3.09046003937
OC 2.56506003937 2.9716 2.55906003937 3.096459940945 Y
OS 2.56506003937 3.013680019685
OC 2.64183996063 3.09046003937 2.55906003937 3.096459940945 N
OE
SE
S P 0
OB 0.669 4.14 I
OS 0.7082 4.14
OS 0.7082 4.100769980315
OC 0.704719980315 4.0976 0.713003346457 4.092001673228 N
OS 0.669 4.0976
OS 0.669 4.14
OE
SE
S P 0
OB 0.7162 4.14 I
OS 0.7554 4.14
OS 0.7554 4.100880019685
OC 0.751719980315 4.0976 0.760007677165 4.092006003937 N
OS 0.721280019685 4.0976
OC 0.7162 4.101469980315 0.712999114173 4.091999015748 N
OS 0.7162 4.14
OE
SE
S P 0
OB 0.72271003937 4.0896 I
OS 0.75028996063 4.0896
OC 0.7554 4.083119980315 0.759998425197 4.092001082677 N
OS 0.7554 4.050880019685
OC 0.75146003937 4.0472 0.760003051181 4.04200265748 N
OS 0.72153996063 4.0472
OC 0.7162 4.051469980315 0.71300226378 4.041996948819 N
OS 0.7162 4.082530019685
OC 0.72271003937 4.0896 0.713004133858 4.092005019685 N
OE
SE
S P 0
OB 0.669 4.0896 I
OS 0.70328996063 4.0896
OC 0.7082 4.083230019685 0.712996555118 4.092004625984 N
OS 0.7082 4.050769980315
OC 0.70446003937 4.0472 0.712999114173 4.041998326772 N
OS 0.669 4.0472
OS 0.669 4.0896
OE
SE
S P 0
OB 0.7634 4.14 I
OS 0.8026 4.14
OS 0.8026 4.100980019685
OC 0.798719980315 4.0976 0.807006496063 4.092004724409 N
OS 0.768280019685 4.0976
OC 0.7634 4.1014 0.759999015748 4.091998917323 N
OS 0.7634 4.14
OE
SE
S P 0
OB 0.76971003937 4.0896 I
OS 0.79728996063 4.0896
OC 0.8026 4.083019980315 0.806998031496 4.092001771654 N
OS 0.8026 4.0472
OS 0.7634 4.0472
OS 0.7634 4.0826
OC 0.76971003937 4.0896 0.760004133858 4.092005216535 N
OE
SE
S P 0
OB 0.8106 4.14 I
OS 0.8498 4.14
OS 0.8498 4.101080019685
OC 0.845719980315 4.0976 0.854011909449 4.092010137795 N
OS 0.815280019685 4.0976
OC 0.8106 4.101330019685 0.806993700787 4.092004232283 N
OS 0.8106 4.14
OE
SE
S P 0
OB 0.81671003937 4.0896 I
OS 0.84428996063 4.0896
OC 0.8498 4.082919980315 0.854000590551 4.09199734252 N
OS 0.8498 4.051080019685
OC 0.84546003937 4.0472 0.854007086614 4.042006988189 N
OS 0.81553996063 4.0472
OC 0.8106 4.051330019685 0.806997637795 4.042001771654 N
OS 0.8106 4.082669980315
OC 0.81671003937 4.0896 0.807001673228 4.092001082677 N
OE
SE
S P 0
OB 0.8578 4.14 I
OS 0.897 4.14
OS 0.897 4.0976
OS 0.862280019685 4.0976
OC 0.8578 4.10125 0.853993897638 4.092004035433 N
OS 0.8578 4.14
OE
SE
S P 0
OB 0.86371003937 4.0896 I
OS 0.897 4.0896
OS 0.897 4.0472
OS 0.86253996063 4.0472
OC 0.8578 4.05125 0.853997933071 4.042001476378 N
OS 0.8578 4.08275
OC 0.86371003937 4.0896 0.854001870079 4.092001476378 N
OE
SE
S P 0
OB 0.669 4.0392 I
OS 0.7034 4.0392
OC 0.7082 4.033230019685 0.712998425197 4.042002755906 N
OS 0.7082 4.000769980315
OC 0.704230019685 3.9968 0.713 3.992 N
OS 0.669 3.9968
OS 0.669 4.0392
OE
SE
S P 0
OB 0.7226 4.0392 I
OS 0.7504 4.0392
OC 0.7554 4.033119980315 0.760000492126 4.041999212598 N
OS 0.7554 4.000880019685
OC 0.751230019685 3.9968 0.760004133858 3.992003444882 N
OS 0.721769980315 3.9968
OC 0.7162 4.001469980315 0.713000984252 3.99199773622 N
OS 0.7162 4.032530019685
OC 0.7226 4.0392 0.71300246063 4.042003641732 N
OE
SE
S P 0
OB 0.7696 4.0392 I
OS 0.7974 4.0392
OC 0.8026 4.033019980315 0.807 4.041999901575 N
OS 0.8026 4.000980019685
OC 0.798230019685 3.9968 0.807003149606 3.99200246063 N
OS 0.768769980315 3.9968
OC 0.7634 4.0014 0.760000984252 3.991997637795 N
OS 0.7634 4.0326
OC 0.7696 4.0392 0.76000246063 4.042003740157 N
OE
SE
S P 0
OB 0.8166 4.0392 I
OS 0.8444 4.0392
OC 0.8498 4.032919980315 0.854002755906 4.041995472441 N
OS 0.8498 4.001080019685
OC 0.845230019685 3.9968 0.85400757874 3.99200757874 N
OS 0.815769980315 3.9968
OC 0.8106 4.001330019685 0.806996653543 3.99200246063 N
OS 0.8106 4.032669980315
OC 0.8166 4.0392 0.806999704724 4.041999606299 N
OE
SE
S P 0
OB 0.8636 4.0392 I
OS 0.897 4.0392
OS 0.897 3.9968
OS 0.862769980315 3.9968
OC 0.8578 4.00125 0.853996948819 3.992002165354 N
OS 0.8578 4.03275
OC 0.8636 4.0392 0.853999901575 4.041999901575 N
OE
SE
S P 0
OB 0.669 3.9888 I
OS 0.703530019685 3.9888
OC 0.7082 3.983230019685 0.71300226378 3.991999015748 N
OS 0.7082 3.950769980315
OC 0.704019980315 3.9464 0.71299753937 3.941996850394 N
OS 0.669 3.9464
OS 0.669 3.9888
OE
SE
S P 0
OB 0.722469980315 3.9888 I
OS 0.750530019685 3.9888
OC 0.7554 3.983119980315 0.760004527559 3.991995570866 N
OS 0.7554 3.950880019685
OC 0.751019980315 3.9464 0.760000688976 3.942000885827 N
OS 0.721980019685 3.9464
OC 0.7162 3.951469980315 0.713003444882 3.941996062992 N
OS 0.7162 3.982530019685
OC 0.722469980315 3.9888 0.713 3.992 N
OE
SE
S P 0
OB 0.769469980315 3.9888 I
OS 0.797530019685 3.9888
OC 0.8026 3.983019980315 0.807003937008 3.991996555118 N
OS 0.8026 3.950980019685
OC 0.798019980315 3.9464 0.807 3.942 N
OS 0.768980019685 3.9464
OC 0.7634 3.9514 0.760003543307 3.941995866142 N
OS 0.7634 3.9826
OC 0.769469980315 3.9888 0.759999015748 3.992000984252 N
OE
SE
S P 0
OB 0.816469980315 3.9888 I
OS 0.844530019685 3.9888
OC 0.8498 3.982919980315 0.854006988189 3.991992125984 N
OS 0.8498 3.951080019685
OC 0.845019980315 3.9464 0.854004035433 3.942005019685 N
OS 0.815980019685 3.9464
OC 0.8106 3.951330019685 0.806999704724 3.942000492126 N
OS 0.8106 3.982669980315
OC 0.816469980315 3.9888 0.806995964567 3.991996653543 N
OE
SE
S P 0
OB 0.863469980315 3.9888 I
OS 0.897 3.9888
OS 0.897 3.9464
OS 0.862980019685 3.9464
OC 0.8578 3.95125 0.853999901575 3.942000098425 N
OS 0.8578 3.98275
OC 0.863469980315 3.9888 0.853996161417 3.991996850394 N
OE
SE
S P 0
OB 0.863330019685 3.9384 I
OS 0.897 3.9384
OS 0.897 3.896
OS 0.8578 3.896
OS 0.8578 3.93275
OC 0.863330019685 3.9384 0.854000393701 3.94200019685 N
OE
SE
S P 0
OB 0.816330019685 3.9384 I
OS 0.844669980315 3.9384
OC 0.8498 3.932919980315 0.854002854331 3.941995570866 N
OS 0.8498 3.896
OS 0.8106 3.896
OS 0.8106 3.932669980315
OC 0.816330019685 3.9384 0.807 3.942 N
OE
SE
S P 0
OB 0.769330019685 3.9384 I
OS 0.797669980315 3.9384
OC 0.8026 3.933019980315 0.806999507874 3.942000295276 N
OS 0.8026 3.896
OS 0.7634 3.896
OS 0.7634 3.9326
OC 0.769330019685 3.9384 0.760003346457 3.942004232283 N
OE
SE
S P 0
OB 0.722330019685 3.9384 I
OS 0.750669980315 3.9384
OC 0.7554 3.933119980315 0.760000098425 3.941999606299 N
OS 0.7554 3.896
OS 0.7162 3.896
OS 0.7162 3.932530019685
OC 0.722330019685 3.9384 0.713003346457 3.942004035433 N
OE
SE
S P 0
OB 0.669 3.9384 I
OS 0.703669980315 3.9384
OC 0.7082 3.933230019685 0.71299753937 3.942003346457 N
OS 0.7082 3.896
OS 0.669 3.896
OS 0.669 3.9384
OE
SE
S P 0
OB 5.5605 3.69868996063 I
OS 5.5605 3.68868996063
OS 5.5115 3.68868996063
OS 5.5115 3.69868996063
OS 5.5605 3.69868996063
OE
SE
S P 0
OB 5.5605 3.734130019685 I
OS 5.5605 3.724130019685
OS 5.5115 3.724130019685
OS 5.5115 3.734130019685
OS 5.5605 3.734130019685
OE
SE
S P 0
OB 5.5605 3.76956003937 I
OS 5.5605 3.75956003937
OS 5.5115 3.75956003937
OS 5.5115 3.76956003937
OS 5.5605 3.76956003937
OE
SE
S P 0
OB 5.5605 3.80498996063 I
OS 5.5605 3.79498996063
OS 5.5115 3.79498996063
OS 5.5115 3.80498996063
OS 5.5605 3.80498996063
OE
SE

### steps/pcb/layers/ssb/features
#
#Num Features
#
F 24295

#
#Units
#
U INCH

#
#Feature symbol names
#
$0 r5
$1 r6
$2 r7
$3 r8
$4 r10

#
#Feature attribute names
#
@0 .nomenclature
@1 .string_mirrored
@2 .string
@3 .string_angle

#
#Feature attribute text strings
#
&0 A
&1 SERIAL NO.
&2 L10
&3 L22
&4 L4
&5 L14
&6 Q2
&7 2
&8 Q3
&9 SILKSCREEN BOT
&10 P/N : R4006-B0001-02
&11 Date: 2022-02-25
&12 Layer:
&13 Rev : 01
&14 R197
&15 R198
&16 R503
&17 R504
&18 R500
&19 R271
&20 R270
&21 R502
&22 R278
&23 R275
&24 R437
&25 R436
&26 C218
&27 C118
&28 C105
&29 C111
&30 C124
&31 C213
&32 C203
&33 C222
&34 C106
&35 C209
&36 C205
&37 C110
&38 C217
&39 C103
&40 C121
&41 C141
&42 C109
&43 C156
&44 C166
&45 C169
&46 C208
&47 C204
&48 C146
&49 C142
&50 C214
&51 C220
&52 C216
&53 C140
&54 C157
&55 C211
&56 C135
&57 C108
&58 C112
&59 C153
&60 C119
&61 C162
&62 C144
&63 C221
&64 C200
&65 C129
&66 C206
&67 C107
&68 C139
&69 C210
&70 C151
&71 C201
&72 C161
&73 C147
&74 C152
&75 C207
&76 C132
&77 C126
&78 C202
&79 C215
&80 C171
&81 C127
&82 C122
&83 C134
&84 C223
&85 C130
&86 C131
&87 C117
&88 C167
&89 C120
&90 C170
&91 C138
&92 C160
&93 C93
&94 C154
&95 L35
&96 L21
&97 L3
&98 C172
&99 C90
&100 C91
&101 C98
&102 C99
&103 C159
&104 C128
&105 C163
&106 SP1
&107 SP2
&108 SP3
&109 C
&110 CR3
&111 5
&112 4
&113 3
&114 U12
&115 U31
&116 8
&117 U8
&118 R491
&119 R32
&120 R188
&121 R50
&122 FU3
&123 R54
&124 R252
&125 R33
&126 R357
&127 R39
&128 R253
&129 R23
&130 R106
&131 R90
&132 R196
&133 R492
&134 R493
&135 R494
&136 R495
&137 R501
&138 R482
&139 R457
&140 R450
&141 R328
&142 R326
&143 R309
&144 R286
&145 R284
&146 R473
&147 R470
&148 R469
&149 R468
&150 R467
&151 R434
&152 R433
&153 R432
&154 R431
&155 R430
&156 R429
&157 R428
&158 R329
&159 R483
&160 R460
&161 R458
&162 R451
&163 R479
&164 R478
&165 R466
&166 R488
&167 R447
&168 R446
&169 R444
&170 R441
&171 R440
&172 R31
&173 R37
&174 R61
&175 R62
&176 R92
&177 R250
&178 R343
&179 R47
&180 R49
&181 R51
&182 R130
&183 R247
&184 R295
&185 R355
&186 R358
&187 R161
&188 R163
&189 R173
&190 R123
&191 R251
&192 R144
&193 R148
&194 R59
&195 R27
&196 R340
&197 R332
&198 R379
&199 R336
&200 R335
&201 R334
&202 R333
&203 R338
&204 R337
&205 R2
&206 R176
&207 R175
&208 R10
&209 R91
&210 R281
&211 R314
&212 R344
&213 R1991
&214 R282
&215 R316
&216 R315
&217 R26
&218 R147
&219 R58
&220 R145
&221 R409
&222 R413
&223 R43
&224 R41
&225 R42
&226 R28
&227 R30
&228 R48
&229 R142
&230 R1
&231 R3
&232 R118
&233 R119
&234 R24
&235 R416
&236 R195
&237 R18
&238 R264
&239 R209
&240 R265
&241 R215
&242 R216
&243 R89
&244 R76
&245 R77
&246 R75
&247 R74
&248 R105
&249 R44
&250 R267
&251 R107
&252 R230
&253 R101
&254 R229
&255 R99
&256 R102
&257 R100
&258 R103
&259 R227
&260 R225
&261 R218
&262 R217
&263 R226
&264 R260
&265 R342
&266 R363
&267 R223
&268 R224
&269 R219
&270 R220
&271 R207
&272 R174
&273 R319
&274 R149
&275 R155
&276 R152
&277 R146
&278 R150
&279 R153
&280 R60
&281 R151
&282 R154
&283 R165
&284 R263
&285 R36
&286 R53
&287 R201
&288 R205
&289 R204
&290 R200
&291 R191
&292 R206
&293 R202
&294 R203
&295 R192
&296 R199
&297 R341
&298 R330
&299 R110
&300 R269
&301 R109
&302 R111
&303 R115
&304 R318
&305 R317
&306 R321
&307 R322
&308 R82
&309 R81
&310 R135
&311 R133
&312 R134
&313 R403
&314 R402
&315 R169
&316 R171
&317 R168
&318 R137
&319 R136
&320 R159
&321 R208
&322 R210
&323 R257
&324 R158
&325 R405
&326 R404
&327 R279
&328 R280
&329 R180
&330 R262
&331 R256
&332 R108
&333 R139
&334 R160
&335 R258
&336 R259
&337 R138
&338 R162
&339 R261
&340 R45
&341 R244
&342 R246
&343 R249
&344 R243
&345 R417
&346 R415
&347 R411
&348 R300
&349 R65
&350 R69
&351 R64
&352 R293
&353 R131
&354 R349
&355 R132
&356 R80
&357 R454
&358 R463
&359 R16
&360 R233
&361 R232
&362 R177
&363 C263
&364 C164
&365 C143
&366 C125
&367 C303
&368 C299
&369 C297
&370 C301
&371 C179
&372 C158
&373 C64
&374 C168
&375 C282
&376 C283
&377 C58
&378 C243
&379 C241
&380 C180
&381 C181
&382 C245
&383 C136
&384 C36
&385 C35
&386 C34
&387 C28
&388 C27
&389 C26
&390 C25
&391 C24
&392 C19
&393 C23
&394 C290
&395 C289
&396 C67
&397 C116
&398 C104
&399 C123
&400 C94
&401 C101
&402 C102
&403 C39
&404 C82
&405 C1
&406 C45
&407 C44
&408 C42
&409 C145
&410 C266
&411 C88
&412 C178
&413 C150
&414 C65
&415 C66
&416 C219
&417 C113
&418 C133
&419 C71
&420 C59
&421 C70
&422 C69
&423 C62
&424 C60
&425 C68
&426 C293
&427 C149
&428 C115
&429 C212
&430 C114
&431 C165
&432 C244
&433 C246
&434 C248
&435 C57
&436 C294
&437 C229
&438 C78
&439 C73
&440 C316
&441 C286
&442 C54
&443 C56
&444 C80
&445 C273
&446 C315
&447 C95
&448 C100
&449 C96
&450 C265
&451 CR7
&452 CR6
&453 U10
&454 A1
&455 A32

#
#Layer features
#
L 4.615 1.81 4.615 1.795 1 P 0 
L 4.615 1.795 4.6 1.795 1 P 0 
L 4.6 1.795 4.6 1.72 1 P 0 
L 4.6 1.72 4.555 1.72 1 P 0 
L 4.555 1.72 4.555 1.605 1 P 0 
L 4.29 1.875 4.525 1.875 1 P 0 
L 4.525 1.875 4.525 1.92 1 P 0 
L 4.525 1.92 4.575 1.92 1 P 0 
L 4.27 1.77 4.28 1.77 1 P 0 
L 4.28 1.77 4.28 1.845 1 P 0 
L 4.24 1.775 4.255 1.775 1 P 0 
L 4.2 1.775 4.215 1.775 1 P 0 
L 4.08 1.775 4.1 1.775 1 P 0 
L 4.415 1.535 4.51 1.535 1 P 0 
L 4.51 1.535 4.51 1.605 1 P 0 
L 4.51 1.605 4.555 1.605 1 P 0 
L 4.415 1.415 4.415 1.535 1 P 0 
L 4.29 1.385 4.29 1.415 1 P 0 
L 4.29 1.415 4.415 1.415 1 P 0 
L 4.02 1.68 4.02 1.725 1 P 0 
L 4.02 1.725 4.07 1.725 1 P 0 
L 4.07 1.725 4.07 1.74 1 P 0 
L 4.08 1.455 4.175 1.455 1 P 0 
L 4.02 1.34 4.02 1.427 1 P 0 
L 4.08 1.34 4.08 1.455 1 P 0 
L 4.175 1.455 4.175 1.385 1 P 0 
L 4.175 1.385 4.29 1.385 1 P 0 
L 4.02 1.68 3.845 1.68 1 P 0 
L 3.845 1.68 3.845 1.41 1 P 0 
L 3.978 1.428 3.975 1.428 1 P 0 
L 3.975 1.428 3.975 1.41 1 P 0 
L 4.02 1.427 4.004 1.427 1 P 0 
L 3.988 1.412 3.998 1.403 1 P 0 
L 4.013 1.412 3.988 1.412 1 P 0 
L 3.988 1.412 3.999 1.42 1 P 0 
L 3.845 1.41 3.975 1.41 1 P 0 
L 3.975 1.41 3.975 1.34 1 P 0 
L 3.975 1.34 4.08 1.34 1 P 0 
L 2.934 1.417 2.826 1.417 1 P 0 
L 2.908 1.385 2.893 1.373 1 P 0 
L 2.862 1.385 2.908 1.385 1 P 0 
L 2.908 1.385 2.894 1.397 1 P 0 
L 2.826 1.417 2.826 1.311 1 P 0 
L 2.935 1.41 2.935 1.805 1 P 0 
L 2.935 1.805 2.145 1.805 1 P 0 
L 2.145 1.805 2.145 1.255 1 P 0 
L 2.145 1.255 2.38 1.255 1 P 0 
L 2.38 1.255 2.38 1.31 1 P 0 
L 2.38 1.31 2.935 1.31 1 P 0 
L 2.935 1.31 2.935 1.41 1 P 0 
L 3.98891624 1.3475 3.99849961 1.3785 1 P 0 ;0,2=0,3=0.000000
L 3.99849961 1.3785 4.00808366 1.3475 1 P 0 ;0,2=0,3=0.000000
L 4.00463307 1.35834951 3.99236614 1.35834951 1 P 0 ;0,2=0,3=0.000000
L 2.88041624 1.3345 2.88999961 1.3655 1 P 0 ;0,2=0,3=0.000000
L 2.88999961 1.3655 2.89958366 1.3345 1 P 0 ;0,2=0,3=0.000000
L 2.89613307 1.34534951 2.88386614 1.34534951 1 P 0 ;0,2=0,3=0.000000
L 2.27 2.365 1.17 2.365 2 P 0 
L 1.17 2.365 1.17 2.115 2 P 0 
L 1.17 2.115 2.27 2.115 2 P 0 
L 2.27 2.115 2.27 2.365 2 P 0 
L 2.1496502 2.20753061 2.14045 2.19969892 3 P 0 ;0,1,2=1,3=0.000000
L 2.14045 2.19969892 2.1301001 2.195 3 P 0 ;0,1,2=1,3=0.000000
L 2.1301001 2.195 2.1209 2.195 3 P 0 ;0,1,2=1,3=0.000000
L 2.1209 2.195 2.1116998 2.19969892 3 P 0 ;0,1,2=1,3=0.000000
L 2.1116998 2.19969892 2.10479921 2.20753061 3 P 0 ;0,1,2=1,3=0.000000
L 2.10479921 2.20753061 2.1013499 2.21850069 3 P 0 ;0,1,2=1,3=0.000000
L 2.1013499 2.21850069 2.10364941 2.22946496 3 P 0 ;0,1,2=1,3=0.000000
L 2.10364941 2.22946496 2.1094003 2.23886585 3 P 0 ;0,1,2=1,3=0.000000
L 2.1094003 2.23886585 2.1197502 2.24513406 3 P 0 ;0,1,2=1,3=0.000000
L 2.1197502 2.24513406 2.13354941 2.24826673 3 P 0 ;0,1,2=1,3=0.000000
L 2.13354941 2.24826673 2.1415998 2.25453209 3 P 0 ;0,1,2=1,3=0.000000
L 2.1415998 2.25453209 2.14505118 2.26549921 3 P 0 ;0,1,2=1,3=0.000000
L 2.14505118 2.26549921 2.14274951 2.27646644 3 P 0 ;0,1,2=1,3=0.000000
L 2.14274951 2.27646644 2.13700079 2.28429813 3 P 0 ;0,1,2=1,3=0.000000
L 2.13700079 2.28429813 2.12895039 2.289 3 P 0 ;0,1,2=1,3=0.000000
L 2.12895039 2.289 2.1209 2.289 3 P 0 ;0,1,2=1,3=0.000000
L 2.1209 2.289 2.11284961 2.28586732 3 P 0 ;0,1,2=1,3=0.000000
L 2.11284961 2.28586732 2.10594892 2.27803278 3 P 0 ;0,1,2=1,3=0.000000
L 2.0104997 2.195 2.05650039 2.195 3 P 0 ;0,1,2=1,3=0.000000
L 2.05650039 2.195 2.05650039 2.289 3 P 0 ;0,1,2=1,3=0.000000
L 2.05650039 2.289 2.0104997 2.289 3 P 0 ;0,1,2=1,3=0.000000
L 2.0289 2.24356772 2.05650039 2.24356772 3 P 0 ;0,1,2=1,3=0.000000
L 1.96450039 2.195 1.96450039 2.289 3 P 0 ;0,1,2=1,3=0.000000
L 1.96450039 2.289 1.9357502 2.289 3 P 0 ;0,1,2=1,3=0.000000
L 1.9357502 2.289 1.9265501 2.28429813 3 P 0 ;0,1,2=1,3=0.000000
L 1.9265501 2.28429813 1.92079921 2.27803278 3 P 0 ;0,1,2=1,3=0.000000
L 1.92079921 2.27803278 1.9184997 2.26549921 3 P 0 ;0,1,2=1,3=0.000000
L 1.9184997 2.26549921 1.92079921 2.25296575 3 P 0 ;0,1,2=1,3=0.000000
L 1.92079921 2.25296575 1.9276998 2.24513406 3 P 0 ;0,1,2=1,3=0.000000
L 1.9276998 2.24513406 1.9357502 2.24043219 3 P 0 ;0,1,2=1,3=0.000000
L 1.9357502 2.24043219 1.96450039 2.24043219 3 P 0 ;0,1,2=1,3=0.000000
L 1.9357502 2.24043219 1.9184997 2.195 3 P 0 ;0,1,2=1,3=0.000000
L 1.8633003 2.289 1.83570197 2.289 3 P 0 ;0,1,2=1,3=0.000000
L 1.84950108 2.289 1.84950108 2.195 3 P 0 ;0,1,2=1,3=0.000000
L 1.8633003 2.195 1.83570197 2.195 3 P 0 ;0,1,2=1,3=0.000000
L 1.78625128 2.195 1.75750108 2.289 3 P 0 ;0,1,2=1,3=0.000000
L 1.75750108 2.289 1.72874882 2.195 3 P 0 ;0,1,2=1,3=0.000000
L 1.73910079 2.22789862 1.77590138 2.22789862 3 P 0 ;0,1,2=1,3=0.000000
L 1.68850039 2.289 1.68850039 2.195 3 P 0 ;0,1,2=1,3=0.000000
L 1.68850039 2.195 1.6424997 2.195 3 P 0 ;0,1,2=1,3=0.000000
L 1.5079497 2.195 1.5079497 2.289 3 P 0 ;0,1,2=1,3=0.000000
L 1.5079497 2.289 1.45505039 2.195 3 P 0 ;0,1,2=1,3=0.000000
L 1.45505039 2.195 1.45505039 2.289 3 P 0 ;0,1,2=1,3=0.000000
L 1.38950108 2.195 1.39870128 2.19656624 3 P 0 ;0,1,2=1,3=0.000000
L 1.39870128 2.19656624 1.40674951 2.20283159 3 P 0 ;0,1,2=1,3=0.000000
L 1.40674951 2.20283159 1.4136502 2.21223248 3 P 0 ;0,1,2=1,3=0.000000
L 1.4136502 2.21223248 1.41825128 2.2231997 3 P 0 ;0,1,2=1,3=0.000000
L 1.41825128 2.2231997 1.42055079 2.23573317 3 P 0 ;0,1,2=1,3=0.000000
L 1.42055079 2.23573317 1.42055079 2.24826673 3 P 0 ;0,1,2=1,3=0.000000
L 1.42055079 2.24826673 1.41825128 2.2608002 3 P 0 ;0,1,2=1,3=0.000000
L 1.41825128 2.2608002 1.4136502 2.27176742 3 P 0 ;0,1,2=1,3=0.000000
L 1.4136502 2.27176742 1.40674951 2.28116545 3 P 0 ;0,1,2=1,3=0.000000
L 1.40674951 2.28116545 1.39870128 2.28743366 3 P 0 ;0,1,2=1,3=0.000000
L 1.39870128 2.28743366 1.38950108 2.289 3 P 0 ;0,1,2=1,3=0.000000
L 1.38950108 2.289 1.38030098 2.28743366 3 P 0 ;0,1,2=1,3=0.000000
L 1.38030098 2.28743366 1.37225059 2.28116545 3 P 0 ;0,1,2=1,3=0.000000
L 1.37225059 2.28116545 1.3653499 2.27176742 3 P 0 ;0,1,2=1,3=0.000000
L 1.3653499 2.27176742 1.36074882 2.2608002 3 P 0 ;0,1,2=1,3=0.000000
L 1.36074882 2.2608002 1.35844931 2.24826673 3 P 0 ;0,1,2=1,3=0.000000
L 1.35844931 2.24826673 1.35844931 2.23573317 3 P 0 ;0,1,2=1,3=0.000000
L 1.35844931 2.23573317 1.36074882 2.2231997 3 P 0 ;0,1,2=1,3=0.000000
L 1.36074882 2.2231997 1.3653499 2.21223248 3 P 0 ;0,1,2=1,3=0.000000
L 1.3653499 2.21223248 1.37225059 2.20283159 3 P 0 ;0,1,2=1,3=0.000000
L 1.37225059 2.20283159 1.38030098 2.19656624 3 P 0 ;0,1,2=1,3=0.000000
L 1.38030098 2.19656624 1.38950108 2.195 3 P 0 ;0,1,2=1,3=0.000000
L 1.29750108 2.19186742 1.29980059 2.19343376 3 P 0 ;0,1,2=1,3=0.000000
L 1.29980059 2.19343376 1.29980059 2.19656624 3 P 0 ;0,1,2=1,3=0.000000
L 1.29980059 2.19656624 1.29750108 2.19813258 3 P 0 ;0,1,2=1,3=0.000000
L 1.29750108 2.19813258 1.29519951 2.19656624 3 P 0 ;0,1,2=1,3=0.000000
L 1.29519951 2.19656624 1.29519951 2.19343376 3 P 0 ;0,1,2=1,3=0.000000
L 1.29519951 2.19343376 1.29750108 2.19186742 3 P 0 ;0,1,2=1,3=0.000000
L 3.798 0.838 3.798 0.942 1 P 0 
L 3.742 0.838 3.798 0.838 1 P 0 
L 3.742 0.942 3.742 0.838 1 P 0 
L 3.798 0.942 3.742 0.942 1 P 0 
L 3.8725 0.86266654 3.8475 0.86266654 1 P 0 ;0,1,2=2,3=90.000000
L 3.8475 0.86266654 3.8475 0.87333337 1 P 0 ;0,1,2=2,3=90.000000
L 3.8475 0.8899997 3.8725 0.8899997 1 P 0 ;0,1,2=2,3=90.000000
L 3.8725 0.8899997 3.8675003 0.8867999 1 P 0 ;0,1,2=2,3=90.000000
L 3.8475 0.8867999 3.8475 0.89319951 1 P 0 ;0,1,2=2,3=90.000000
L 3.8725 0.9119997 3.87166683 0.90986634 1 P 0 ;0,1,2=2,3=90.000000
L 3.87166683 0.90986634 3.86958317 0.90826663 1 P 0 ;0,1,2=2,3=90.000000
L 3.86958317 0.90826663 3.86708366 0.9071998 1 P 0 ;0,1,2=2,3=90.000000
L 3.86708366 0.9071998 3.86374951 0.9063999 1 P 0 ;0,1,2=2,3=90.000000
L 3.86374951 0.9063999 3.85999961 0.90613327 1 P 0 ;0,1,2=2,3=90.000000
L 3.85999961 0.90613327 3.85624961 0.9063999 1 P 0 ;0,1,2=2,3=90.000000
L 3.85624961 0.9063999 3.85291624 0.9071998 1 P 0 ;0,1,2=2,3=90.000000
L 3.85291624 0.9071998 3.85041604 0.90826663 1 P 0 ;0,1,2=2,3=90.000000
L 3.85041604 0.90826663 3.84833307 0.90986634 1 P 0 ;0,1,2=2,3=90.000000
L 3.84833307 0.90986634 3.8475 0.9119997 1 P 0 ;0,1,2=2,3=90.000000
L 3.8475 0.9119997 3.84833307 0.91413307 1 P 0 ;0,1,2=2,3=90.000000
L 3.84833307 0.91413307 3.85041604 0.91573327 1 P 0 ;0,1,2=2,3=90.000000
L 3.85041604 0.91573327 3.85291624 0.9168001 1 P 0 ;0,1,2=2,3=90.000000
L 3.85291624 0.9168001 3.85624961 0.9176 1 P 0 ;0,1,2=2,3=90.000000
L 3.85624961 0.9176 3.85999961 0.91786663 1 P 0 ;0,1,2=2,3=90.000000
L 3.85999961 0.91786663 3.86374951 0.9176 1 P 0 ;0,1,2=2,3=90.000000
L 3.86374951 0.9176 3.86708366 0.9168001 1 P 0 ;0,1,2=2,3=90.000000
L 3.86708366 0.9168001 3.86958317 0.91573327 1 P 0 ;0,1,2=2,3=90.000000
L 3.86958317 0.91573327 3.87166683 0.91413307 1 P 0 ;0,1,2=2,3=90.000000
L 3.87166683 0.91413307 3.8725 0.9119997 1 P 0 ;0,1,2=2,3=90.000000
L 1.348 3.627 1.292 3.627 1 P 0 
L 1.292 3.627 1.292 3.523 1 P 0 
L 1.292 3.523 1.348 3.523 1 P 0 
L 1.348 3.523 1.348 3.627 1 P 0 
L 1.3355 3.66133317 1.3045 3.66133317 1 P 0 ;0,1,2=3,3=90.000000
L 1.3045 3.66133317 1.3045 3.67666673 1 P 0 ;0,1,2=3,3=90.000000
L 1.33033346 3.69271644 1.33343278 3.69501663 1 P 0 ;0,1,2=3,3=90.000000
L 1.33343278 3.69501663 1.33498337 3.6977001 1 P 0 ;0,1,2=3,3=90.000000
L 1.33498337 3.6977001 1.3355 3.70076683 1 P 0 ;0,1,2=3,3=90.000000
L 1.3355 3.70076683 1.33446683 3.7046 1 P 0 ;0,1,2=3,3=90.000000
L 1.33446683 3.7046 1.33188307 3.70728346 1 P 0 ;0,1,2=3,3=90.000000
L 1.33188307 3.70728346 1.32878376 3.70805 1 P 0 ;0,1,2=3,3=90.000000
L 1.32878376 3.70805 1.32568258 3.70766673 1 P 0 ;0,1,2=3,3=90.000000
L 1.32568258 3.70766673 1.3230998 3.70613307 1 P 0 ;0,1,2=3,3=90.000000
L 1.3230998 3.70613307 1.31793327 3.69846663 1 P 0 ;0,1,2=3,3=90.000000
L 1.31793327 3.69846663 1.31431644 3.69501663 1 P 0 ;0,1,2=3,3=90.000000
L 1.31431644 3.69501663 1.30914892 3.69271644 1 P 0 ;0,1,2=3,3=90.000000
L 1.30914892 3.69271644 1.3045 3.6919499 1 P 0 ;0,1,2=3,3=90.000000
L 1.3045 3.6919499 1.3045 3.70805 1 P 0 ;0,1,2=3,3=90.000000
L 1.33033346 3.72371644 1.33343278 3.72601663 1 P 0 ;0,1,2=3,3=90.000000
L 1.33343278 3.72601663 1.33498337 3.7287001 1 P 0 ;0,1,2=3,3=90.000000
L 1.33498337 3.7287001 1.3355 3.73176683 1 P 0 ;0,1,2=3,3=90.000000
L 1.3355 3.73176683 1.33446683 3.7356 1 P 0 ;0,1,2=3,3=90.000000
L 1.33446683 3.7356 1.33188307 3.73828346 1 P 0 ;0,1,2=3,3=90.000000
L 1.33188307 3.73828346 1.32878376 3.73905 1 P 0 ;0,1,2=3,3=90.000000
L 1.32878376 3.73905 1.32568258 3.73866673 1 P 0 ;0,1,2=3,3=90.000000
L 1.32568258 3.73866673 1.3230998 3.73713307 1 P 0 ;0,1,2=3,3=90.000000
L 1.3230998 3.73713307 1.31793327 3.72946663 1 P 0 ;0,1,2=3,3=90.000000
L 1.31793327 3.72946663 1.31431644 3.72601663 1 P 0 ;0,1,2=3,3=90.000000
L 1.31431644 3.72601663 1.30914892 3.72371644 1 P 0 ;0,1,2=3,3=90.000000
L 1.30914892 3.72371644 1.3045 3.7229499 1 P 0 ;0,1,2=3,3=90.000000
L 1.3045 3.7229499 1.3045 3.73905 1 P 0 ;0,1,2=3,3=90.000000
L 1.118 3.433 1.118 3.537 1 P 0 
L 1.118 3.537 1.062 3.537 1 P 0 
L 1.062 3.537 1.062 3.433 1 P 0 
L 1.062 3.433 1.118 3.433 1 P 0 
L 1.1055 3.37183317 1.0745 3.37183317 1 P 0 ;0,1,2=4,3=90.000000
L 1.0745 3.37183317 1.0745 3.38716673 1 P 0 ;0,1,2=4,3=90.000000
L 1.0745 3.4151 1.1055 3.4151 1 P 0 ;0,1,2=4,3=90.000000
L 1.1055 3.4151 1.08328327 3.40091624 1 P 0 ;0,1,2=4,3=90.000000
L 1.08328327 3.40091624 1.08328327 3.42008366 1 P 0 ;0,1,2=4,3=90.000000
L 4.242 0.857 4.242 0.753 1 P 0 
L 4.242 0.753 4.298 0.753 1 P 0 
L 4.298 0.753 4.298 0.857 1 P 0 
L 4.298 0.857 4.242 0.857 1 P 0 
L 4.3455 0.79133317 4.3145 0.79133317 1 P 0 ;0,1,2=5,3=90.000000
L 4.3145 0.79133317 4.3145 0.80666673 1 P 0 ;0,1,2=5,3=90.000000
L 4.3145 0.82999961 4.3455 0.82999961 1 P 0 ;0,1,2=5,3=90.000000
L 4.3455 0.82999961 4.3393003 0.8253999 1 P 0 ;0,1,2=5,3=90.000000
L 4.3145 0.8253999 4.3145 0.83459931 1 P 0 ;0,1,2=5,3=90.000000
L 4.3145 0.8656 4.3455 0.8656 1 P 0 ;0,1,2=5,3=90.000000
L 4.3455 0.8656 4.32328327 0.85141624 1 P 0 ;0,1,2=5,3=90.000000
L 4.32328327 0.85141624 4.32328327 0.87058366 1 P 0 ;0,1,2=5,3=90.000000
L 3.091 2.1725 3.046 2.1725 1 P 0 
L 3.046 2.1725 3.046 2.1875 1 P 0 
L 3.046 2.1875 3.091 2.1875 1 P 0 
L 3.091 2.1875 3.091 2.247 1 P 0 
L 3.091 2.247 2.974 2.247 1 P 0 
L 2.974 2.247 2.974 2.2095 1 P 0 
L 3.091 2.113 3.091 2.1725 1 P 0 
L 2.974 2.1505 2.974 2.113 1 P 0 
L 2.974 2.113 3.091 2.113 1 P 0 
L 2.974 2.2095 2.929 2.2095 1 P 0 
L 2.929 2.2095 2.929 2.1505 1 P 0 
L 2.929 2.1505 2.974 2.1505 1 P 0 
S P 0
OB 3.125 2.23 I
OC 3.125 2.23 3.11 2.23 Y
OE
SE
L 3.1445 2.16449961 3.14501654 2.16143287 1 P 0 ;0,1,2=6,3=90.000000
L 3.14501654 2.16143287 3.14708278 2.1587501 1 P 0 ;0,1,2=6,3=90.000000
L 3.14708278 2.1587501 3.15018297 2.1564499 1 P 0 ;0,1,2=6,3=90.000000
L 3.15018297 2.1564499 3.1537999 2.15491624 1 P 0 ;0,1,2=6,3=90.000000
L 3.1537999 2.15491624 3.15793327 2.1541497 1 P 0 ;0,1,2=6,3=90.000000
L 3.15793327 2.1541497 3.16206663 2.1541497 1 P 0 ;0,1,2=6,3=90.000000
L 3.16206663 2.1541497 3.1662 2.15491624 1 P 0 ;0,1,2=6,3=90.000000
L 3.1662 2.15491624 3.16981693 2.1564499 1 P 0 ;0,1,2=6,3=90.000000
L 3.16981693 2.1564499 3.17291624 2.1587501 1 P 0 ;0,1,2=6,3=90.000000
L 3.17291624 2.1587501 3.17498337 2.16143287 1 P 0 ;0,1,2=6,3=90.000000
L 3.17498337 2.16143287 3.1755 2.16449961 1 P 0 ;0,1,2=6,3=90.000000
L 3.1755 2.16449961 3.17498337 2.16756634 1 P 0 ;0,1,2=6,3=90.000000
L 3.17498337 2.16756634 3.17291624 2.1702498 1 P 0 ;0,1,2=6,3=90.000000
L 3.17291624 2.1702498 3.16981693 2.17255 1 P 0 ;0,1,2=6,3=90.000000
L 3.16981693 2.17255 3.1662 2.17408366 1 P 0 ;0,1,2=6,3=90.000000
L 3.1662 2.17408366 3.16206663 2.1748502 1 P 0 ;0,1,2=6,3=90.000000
L 3.16206663 2.1748502 3.15793327 2.1748502 1 P 0 ;0,1,2=6,3=90.000000
L 3.15793327 2.1748502 3.1537999 2.17408366 1 P 0 ;0,1,2=6,3=90.000000
L 3.1537999 2.17408366 3.15018297 2.17255 1 P 0 ;0,1,2=6,3=90.000000
L 3.15018297 2.17255 3.14708278 2.1702498 1 P 0 ;0,1,2=6,3=90.000000
L 3.14708278 2.1702498 3.14501654 2.16756634 1 P 0 ;0,1,2=6,3=90.000000
L 3.14501654 2.16756634 3.1445 2.16449961 1 P 0 ;0,1,2=6,3=90.000000
L 3.15276673 2.16756634 3.1445 2.17216673 1 P 0 ;0,1,2=6,3=90.000000
L 3.17033346 2.18821644 3.17343278 2.19051663 1 P 0 ;0,1,2=6,3=90.000000
L 3.17343278 2.19051663 3.17498337 2.1932001 1 P 0 ;0,1,2=6,3=90.000000
L 3.17498337 2.1932001 3.1755 2.19626683 1 P 0 ;0,1,2=6,3=90.000000
L 3.1755 2.19626683 3.17446683 2.2001 1 P 0 ;0,1,2=6,3=90.000000
L 3.17446683 2.2001 3.17188307 2.20278346 1 P 0 ;0,1,2=6,3=90.000000
L 3.17188307 2.20278346 3.16878376 2.20355 1 P 0 ;0,1,2=6,3=90.000000
L 3.16878376 2.20355 3.16568258 2.20316673 1 P 0 ;0,1,2=6,3=90.000000
L 3.16568258 2.20316673 3.1630998 2.20163307 1 P 0 ;0,1,2=6,3=90.000000
L 3.1630998 2.20163307 3.15793327 2.19396663 1 P 0 ;0,1,2=6,3=90.000000
L 3.15793327 2.19396663 3.15431644 2.19051663 1 P 0 ;0,1,2=6,3=90.000000
L 3.15431644 2.19051663 3.14914892 2.18821644 1 P 0 ;0,1,2=6,3=90.000000
L 3.14914892 2.18821644 3.1445 2.1874499 1 P 0 ;0,1,2=6,3=90.000000
L 3.1445 2.1874499 3.1445 2.20355 1 P 0 ;0,1,2=6,3=90.000000
L 3.12006683 2.13333337 3.11846673 2.13583287 1 P 0 ;0,1,2=7,3=0.000000
L 3.11846673 2.13583287 3.1166 2.13708337 1 P 0 ;0,1,2=7,3=0.000000
L 3.1166 2.13708337 3.11446663 2.1375 1 P 0 ;0,1,2=7,3=0.000000
L 3.11446663 2.1375 3.1118 2.13666683 1 P 0 ;0,1,2=7,3=0.000000
L 3.1118 2.13666683 3.10993327 2.13458317 1 P 0 ;0,1,2=7,3=0.000000
L 3.10993327 2.13458317 3.1094 2.13208366 1 P 0 ;0,1,2=7,3=0.000000
L 3.1094 2.13208366 3.10966663 2.12958268 1 P 0 ;0,1,2=7,3=0.000000
L 3.10966663 2.12958268 3.11073356 2.1274998 1 P 0 ;0,1,2=7,3=0.000000
L 3.11073356 2.1274998 3.11606673 2.12333327 1 P 0 ;0,1,2=7,3=0.000000
L 3.11606673 2.12333327 3.11846673 2.12041644 1 P 0 ;0,1,2=7,3=0.000000
L 3.11846673 2.12041644 3.12006683 2.11624911 1 P 0 ;0,1,2=7,3=0.000000
L 3.12006683 2.11624911 3.1206001 2.1125 1 P 0 ;0,1,2=7,3=0.000000
L 3.1206001 2.1125 3.1094 2.1125 1 P 0 ;0,1,2=7,3=0.000000
L 3.096 2.3445 3.051 2.3445 1 P 0 
L 3.051 2.3445 3.051 2.382 1 P 0 
L 2.979 2.3225 2.979 2.3075 1 P 0 
L 3.051 2.248 3.051 2.2855 1 P 0 
L 3.051 2.2855 3.096 2.2855 1 P 0 
L 3.096 2.2855 3.096 2.3445 1 P 0 
L 3.051 2.382 2.934 2.382 1 P 0 
L 2.934 2.382 2.934 2.3225 1 P 0 
L 2.934 2.3225 2.979 2.3225 1 P 0 
L 2.979 2.3075 2.934 2.3075 1 P 0 
L 2.934 2.3075 2.934 2.248 1 P 0 
L 2.934 2.248 3.051 2.248 1 P 0 
S P 0
OB 2.92 2.255 I
OC 2.92 2.255 2.905 2.255 Y
OE
SE
L 3.2045 2.39449961 3.20501654 2.39143287 1 P 0 ;0,1,2=8,3=90.000000
L 3.20501654 2.39143287 3.20708278 2.3887501 1 P 0 ;0,1,2=8,3=90.000000
L 3.20708278 2.3887501 3.21018297 2.3864499 1 P 0 ;0,1,2=8,3=90.000000
L 3.21018297 2.3864499 3.2137999 2.38491624 1 P 0 ;0,1,2=8,3=90.000000
L 3.2137999 2.38491624 3.21793327 2.3841497 1 P 0 ;0,1,2=8,3=90.000000
L 3.21793327 2.3841497 3.22206663 2.3841497 1 P 0 ;0,1,2=8,3=90.000000
L 3.22206663 2.3841497 3.2262 2.38491624 1 P 0 ;0,1,2=8,3=90.000000
L 3.2262 2.38491624 3.22981693 2.3864499 1 P 0 ;0,1,2=8,3=90.000000
L 3.22981693 2.3864499 3.23291624 2.3887501 1 P 0 ;0,1,2=8,3=90.000000
L 3.23291624 2.3887501 3.23498337 2.39143287 1 P 0 ;0,1,2=8,3=90.000000
L 3.23498337 2.39143287 3.2355 2.39449961 1 P 0 ;0,1,2=8,3=90.000000
L 3.2355 2.39449961 3.23498337 2.39756634 1 P 0 ;0,1,2=8,3=90.000000
L 3.23498337 2.39756634 3.23291624 2.4002498 1 P 0 ;0,1,2=8,3=90.000000
L 3.23291624 2.4002498 3.22981693 2.40255 1 P 0 ;0,1,2=8,3=90.000000
L 3.22981693 2.40255 3.2262 2.40408366 1 P 0 ;0,1,2=8,3=90.000000
L 3.2262 2.40408366 3.22206663 2.4048502 1 P 0 ;0,1,2=8,3=90.000000
L 3.22206663 2.4048502 3.21793327 2.4048502 1 P 0 ;0,1,2=8,3=90.000000
L 3.21793327 2.4048502 3.2137999 2.40408366 1 P 0 ;0,1,2=8,3=90.000000
L 3.2137999 2.40408366 3.21018297 2.40255 1 P 0 ;0,1,2=8,3=90.000000
L 3.21018297 2.40255 3.20708278 2.4002498 1 P 0 ;0,1,2=8,3=90.000000
L 3.20708278 2.4002498 3.20501654 2.39756634 1 P 0 ;0,1,2=8,3=90.000000
L 3.20501654 2.39756634 3.2045 2.39449961 1 P 0 ;0,1,2=8,3=90.000000
L 3.21276673 2.39756634 3.2045 2.40216673 1 P 0 ;0,1,2=8,3=90.000000
L 3.21069961 2.41706663 3.20708278 2.41936614 1 P 0 ;0,1,2=8,3=90.000000
L 3.20708278 2.41936614 3.20501654 2.42243287 1 P 0 ;0,1,2=8,3=90.000000
L 3.20501654 2.42243287 3.2045 2.42588356 1 P 0 ;0,1,2=8,3=90.000000
L 3.2045 2.42588356 3.20501654 2.4289503 1 P 0 ;0,1,2=8,3=90.000000
L 3.20501654 2.4289503 3.20759931 2.43201703 1 P 0 ;0,1,2=8,3=90.000000
L 3.20759931 2.43201703 3.21069961 2.43393327 1 P 0 ;0,1,2=8,3=90.000000
L 3.21069961 2.43393327 3.2137999 2.43431654 1 P 0 ;0,1,2=8,3=90.000000
L 3.2137999 2.43431654 3.21741575 2.43355 1 P 0 ;0,1,2=8,3=90.000000
L 3.21741575 2.43355 3.21999951 2.43086654 1 P 0 ;0,1,2=8,3=90.000000
L 3.21999951 2.43086654 3.22103356 2.42818307 1 P 0 ;0,1,2=8,3=90.000000
L 3.22103356 2.42818307 3.22103356 2.42473307 1 P 0 ;0,1,2=8,3=90.000000
L 3.22103356 2.42818307 3.22258317 2.43048327 1 P 0 ;0,1,2=8,3=90.000000
L 3.22258317 2.43048327 3.22516594 2.4324002 1 P 0 ;0,1,2=8,3=90.000000
L 3.22516594 2.4324002 3.22826624 2.43316673 1 P 0 ;0,1,2=8,3=90.000000
L 3.22826624 2.43316673 3.23136654 2.4324002 1 P 0 ;0,1,2=8,3=90.000000
L 3.23136654 2.4324002 3.23394931 2.43048327 1 P 0 ;0,1,2=8,3=90.000000
L 3.23394931 2.43048327 3.2355 2.42703327 1 P 0 ;0,1,2=8,3=90.000000
L 3.2355 2.42703327 3.23498337 2.42358337 1 P 0 ;0,1,2=8,3=90.000000
L 3.23498337 2.42358337 3.23291624 2.42013337 1 P 0 ;0,1,2=8,3=90.000000
L 2.97333337 2.38993317 2.97583287 2.39153327 1 P 0 ;0,1,2=7,3=90.000000
L 2.97583287 2.39153327 2.97708337 2.3934 1 P 0 ;0,1,2=7,3=90.000000
L 2.97708337 2.3934 2.9775 2.39553337 1 P 0 ;0,1,2=7,3=90.000000
L 2.9775 2.39553337 2.97666683 2.3982 1 P 0 ;0,1,2=7,3=90.000000
L 2.97666683 2.3982 2.97458317 2.40006673 1 P 0 ;0,1,2=7,3=90.000000
L 2.97458317 2.40006673 2.97208366 2.4006 1 P 0 ;0,1,2=7,3=90.000000
L 2.97208366 2.4006 2.96958268 2.40033337 1 P 0 ;0,1,2=7,3=90.000000
L 2.96958268 2.40033337 2.9674998 2.39926644 1 P 0 ;0,1,2=7,3=90.000000
L 2.9674998 2.39926644 2.96333327 2.39393327 1 P 0 ;0,1,2=7,3=90.000000
L 2.96333327 2.39393327 2.96041644 2.39153327 1 P 0 ;0,1,2=7,3=90.000000
L 2.96041644 2.39153327 2.95624911 2.38993317 1 P 0 ;0,1,2=7,3=90.000000
L 2.95624911 2.38993317 2.9525 2.3893999 1 P 0 ;0,1,2=7,3=90.000000
L 2.9525 2.3893999 2.9525 2.4006 1 P 0 ;0,1,2=7,3=90.000000
L 3.16 -0.655 3.16 -1.58 4 P 0 
L 1.36 -0.655 1.36 -1.58 4 P 0 
L 1.36 -1.58 5.06 -1.58 4 P 0 
L 5.06 -1.58 5.06 -0.655 4 P 0 
L 5.06 -0.655 1.36 -0.655 4 P 0 
A 1.559 -1.33655 1.559 -1.33655 1.55268002 -1.33655 1 P 0 N
A 1.54775 -1.205 1.54775 -1.205 1.53883002 -1.205 1 P 0 N
A 1.54763996 -0.99775 1.54763996 -0.99775 1.53871998 -0.99775 1 P 0 N
A 1.54063996 -1.10118002 1.54063996 -1.10118002 1.52603996 -1.10118002 1 P 0 N
A 1.49695 -1.10118002 1.49695 -1.10118002 1.48656998 -1.10118002 1 P 0 N
A 1.45963996 -1.10118002 1.45963996 -1.10118002 1.4533 -1.10118002 1 P 0 N
A 1.52135 -0.98681004 1.52135 -0.98681004 1.51503002 -0.98681004 1 P 0 N
A 1.79433002 -1.43586998 1.79433002 -1.43586998 1.78798996 -1.43586998 1 P 0 N
A 1.79841004 -1.40261004 1.79841004 -1.40261004 1.78798996 -1.40261004 1 P 0 N
A 1.80255 -1.36311004 1.80255 -1.36311004 1.78798996 -1.36311004 1 P 0 N
A 1.80668996 -1.31528002 1.80668996 -1.31528002 1.78798996 -1.31528002 1 P 0 N
A 1.68013002 -1.37456004 1.68013002 -1.37456004 1.67378996 -1.37456004 1 P 0 N
A 1.69321998 -1.35033002 1.69321998 -1.35033002 1.6843 -1.35033002 1 P 0 N
A 1.7108 -1.31738996 1.7108 -1.31738996 1.69798002 -1.31738996 1 P 0 N
A 1.89666998 -1.31511004 1.89666998 -1.31511004 1.88383996 -1.31511004 1 P 0 N
A 1.88198996 -1.16876004 1.88198996 -1.16876004 1.85558996 -1.16876004 1 P 0 N
A 1.87928002 -1.27801998 1.87928002 -1.27801998 1.86343996 -1.27801998 1 P 0 N
A 1.86176998 -1.23075 1.86176998 -1.23075 1.84206004 -1.23075 1 P 0 N
A 1.80978996 -1.25916998 1.80978996 -1.25916998 1.78798996 -1.25916998 1 P 0 N
A 1.74681004 -1.16876004 1.74681004 -1.16876004 1.72041004 -1.16876004 1 P 0 N
A 1.67813002 -1.15513002 1.67813002 -1.15513002 1.65841998 -1.15513002 1 P 0 N
A 1.73018002 -1.27816004 1.73018002 -1.27816004 1.71433996 -1.27816004 1 P 0 N
A 1.75373002 -1.23081004 1.75373002 -1.23081004 1.73405 -1.23081004 1 P 0 N
A 1.65531004 -1.25255 1.65531004 -1.25255 1.63661998 -1.25255 1 P 0 N
A 1.69808996 -1.21291998 1.69808996 -1.21291998 1.67628996 -1.21291998 1 P 0 N
A 1.81438996 -1.1968 1.81438996 -1.1968 1.78798996 -1.1968 1 P 0 N
A 1.6269 -1.1749 1.6269 -1.1749 1.61106004 -1.1749 1 P 0 N
A 1.58461004 -1.19126004 1.58461004 -1.19126004 1.57178002 -1.19126004 1 P 0 N
A 1.5853 -1.31428002 1.5853 -1.31428002 1.57488996 -1.31428002 1 P 0 N
A 1.61735 -1.28638996 1.61735 -1.28638996 1.60276998 -1.28638996 1 P 0 N
A 1.88198996 -1.03361004 1.88198996 -1.03361004 1.85558996 -1.03361004 1 P 0 N
A 1.71881004 -1.10118002 1.71881004 -1.10118002 1.69238996 -1.10118002 1 P 0 N
A 1.65183002 -1.10118002 1.65183002 -1.10118002 1.63003002 -1.10118002 1 P 0 N
A 1.67801998 -1.04738996 1.67801998 -1.04738996 1.65831004 -1.04738996 1 P 0 N
A 1.74681004 -1.03361004 1.74681004 -1.03361004 1.72041004 -1.03361004 1 P 0 N
A 1.69811998 -0.98951004 1.69811998 -0.98951004 1.67631998 -0.98951004 1 P 0 N
A 1.81438996 -1.00556004 1.81438996 -1.00556004 1.78798996 -1.00556004 1 P 0 N
A 1.59258002 -1.10118002 1.59258002 -1.10118002 1.5739 -1.10118002 1 P 0 N
A 1.58451004 -1.01148996 1.58451004 -1.01148996 1.57168002 -1.01148996 1 P 0 N
A 1.62681004 -1.02773996 1.62681004 -1.02773996 1.61096998 -1.02773996 1 P 0 N
A 1.92148002 -1.21285 1.92148002 -1.21285 1.89968002 -1.21285 1 P 0 N
A 1.92148002 -0.98951004 1.92148002 -0.98951004 1.89968002 -0.98951004 1 P 0 N
A 1.80978996 -0.9432 1.80978996 -0.9432 1.78798996 -0.9432 1 P 0 N
A 1.80668996 -0.88708002 1.80668996 -0.88708002 1.78798996 -0.88708002 1 P 0 N
A 1.80255 -0.83923996 1.80255 -0.83923996 1.78798996 -0.83923996 1 P 0 N
A 1.8919 -0.88538002 1.8919 -0.88538002 1.87906998 -0.88538002 1 P 0 N
A 1.87838996 -0.92456998 1.87838996 -0.92456998 1.86255 -0.92456998 1 P 0 N
A 1.65531004 -0.94981004 1.65531004 -0.94981004 1.63661998 -0.94981004 1 P 0 N
A 1.73123002 -0.92378002 1.73123002 -0.92378002 1.71538996 -0.92378002 1 P 0 N
A 1.71216998 -0.88443996 1.71216998 -0.88443996 1.69935 -0.88443996 1 P 0 N
A 1.86225 -0.97178002 1.86225 -0.97178002 1.84253996 -0.97178002 1 P 0 N
A 1.75451998 -0.97123996 1.75451998 -0.97123996 1.73483996 -0.97123996 1 P 0 N
A 1.61741998 -0.91601004 1.61741998 -0.91601004 1.60283996 -0.91601004 1 P 0 N
A 1.5853 -0.88808996 1.5853 -0.88808996 1.57488996 -0.88808996 1 P 0 N
A 1.79841004 -0.79975 1.79841004 -0.79975 1.78798996 -0.79975 1 P 0 N
A 1.79433002 -0.76648002 1.79433002 -0.76648002 1.78798996 -0.76648002 1 P 0 N
A 1.92135 -1.36781004 1.92135 -1.36781004 1.91503996 -1.36781004 1 P 0 N
A 1.91096004 -1.34658002 1.91096004 -1.34658002 1.90203996 -1.34658002 1 P 0 N
A 2.19078996 -1.1806 2.26591004 -1.16473002 2.21741014 -1.12088169 1 P 0 N
A 2.15903002 -1.1402 2.19078996 -1.18061004 2.22093406 -1.12423278 1 P 0 N
A 2.05721004 -1.16178996 2.08853002 -1.16658996 2.08281614 -1.09929134 1 P 0 N
A 2.00546998 -1.13951998 2.03345 -1.17196004 2.07793927 -1.10530069 1 P 0 N
A 2.03346004 -1.17195 2.0847 -1.18461004 2.07891181 -1.09801299 1 P 0 N
A 2.0847 -1.18461998 2.14261004 -1.15663002 2.07348435 -1.08751378 1 P 0 N
A 2.08853996 -1.16658002 2.13313002 -1.14451998 2.06368967 -1.06025512 1 P 0 N
A 1.95808002 -1.25255 1.95808002 -1.25255 1.93938996 -1.25255 1 P 0 N
A 1.98775 -1.28635 1.98775 -1.28635 1.97316998 -1.28635 1 P 0 N
A 2.27411998 -1.11835 2.15906004 -1.11835 2.21658996 -1.11611998 1 P 0 N
L 2.25188002 -1.11418002 2.1807 -1.11418002 1 P 0 
L 2.1807 -1.11418002 2.1807 -1.11398996 1 P 8191 
A 2.25188996 -1.11398996 2.18071004 -1.11398996 2.2163 -1.1124 1 P 0 N
A 2.08028996 -1.03428996 2.02048996 -1.08258996 2.0798126 -1.09486801 1 P 0 N
A 2.13151998 -1.05146004 2.0803 -1.0343 2.0802999 -1.11932195 1 P 0 N
A 2.1315 -1.05146998 2.14175 -1.03951004 2.1356003 -1.04461171 1 P 0 N
A 2.14175 -1.03951004 2.08283002 -1.01613002 2.07772461 -1.11492805 1 P 0 N
A 2.08283996 -1.01611998 2.00698002 -1.05835 2.08064724 -1.10143169 1 P 0 N
L 2.27413002 -1.12868996 2.18073996 -1.12868996 1 P 0 
A 2.18075 -1.12868996 2.19083002 -1.15751998 2.22417795 -1.12968307 1 P 0 N
A 2.19083002 -1.15753002 2.25311004 -1.15211004 2.21927195 -1.12381791 1 P 0 N
L 2.15903996 -1.1402 2.15903996 -1.11835 1 P 8191 
A 2.02048996 -1.0826 2.05721998 -1.16181004 2.09087933 -1.0980811 1 P 0 N
A 2.00698996 -1.05836004 2.00546998 -1.13953002 2.09672953 -1.10063967 1 P 0 N
A 2.14258996 -1.15661004 2.13313996 -1.14453002 2.13544892 -1.15246004 1 P 0 N
A 1.95808002 -0.94981004 1.95808002 -0.94981004 1.93938996 -0.94981004 1 P 0 N
A 1.90183996 -0.8525 1.90183996 -0.8525 1.89291004 -0.8525 1 P 0 N
A 1.91108002 -0.82726998 1.91108002 -0.82726998 1.90473996 -0.82726998 1 P 0 N
L 2.32081004 -1.02041004 2.32081004 -1.17625 1 P 0 
A 2.49568002 -1.15528996 2.47898002 -1.16443002 2.4882003 -1.1614502 1 P 0 N
A 2.47896998 -1.16443996 2.50283002 -1.18086004 2.51649242 -1.13546152 1 P 0 N
A 2.50281998 -1.18086998 2.54318002 -1.1834 2.52887392 -1.08843022 1 P 0 N
A 2.52306998 -1.16761004 2.52848996 -1.16771998 2.52673258 -1.12070098 1 P 0 N
A 2.49566004 -1.15528996 2.52306998 -1.1676 2.5255122 -1.12549094 1 P 0 N
A 2.37851998 -1.15753002 2.4408 -1.15211004 2.40696191 -1.12381791 1 P 0 N
A 2.45358002 -1.16471998 2.44078996 -1.1521 2.44541191 -1.16020689 1 P 0 N
A 2.37848002 -1.1806 2.4536 -1.16473002 2.4051001 -1.12088169 1 P 0 N
A 2.34673002 -1.1402 2.37848996 -1.18061004 2.40863406 -1.12423278 1 P 0 N
A 2.2659 -1.16471998 2.25311004 -1.1521 2.25773199 -1.16020689 1 P 0 N
A 2.3006 -1.17626004 2.3208 -1.17626004 2.3107 -1.17386841 1 P 0 N
L 2.30058996 -1.17625 2.30058996 -1.02033996 1 P 0 
A 2.50836998 -1.10106004 2.54306004 -1.11513002 2.56106673 -1.02093386 1 P 0 N
A 2.51081004 -1.07948002 2.50836998 -1.10103996 2.51886093 -1.09130915 1 P 0 N
A 2.53611004 -1.07688996 2.5108 -1.07948996 2.52742205 -1.11680827 1 P 0 N
A 2.56883996 -1.07368002 2.50178002 -1.06358996 2.5273123 -1.12178858 1 P 0 N
A 2.50178996 -1.06358996 2.48536998 -1.08248996 2.52926211 -1.10403986 1 P 0 N
L 2.48536998 -1.0825 2.48536998 -1.09748002 1 P 8191 
A 2.48536998 -1.09748002 2.49956004 -1.12031004 2.51189104 -1.09682067 1 P 0 N
A 2.46181004 -1.11835 2.34675 -1.11835 2.40428002 -1.11611998 1 P 0 N
L 2.43956998 -1.11418002 2.36841004 -1.11418002 1 P 0 
L 2.36841004 -1.11418002 2.36841004 -1.11398996 1 P 8191 
A 2.43958002 -1.11398996 2.3684 -1.11398996 2.40398996 -1.1124 1 P 0 N
L 2.43956998 -1.11398996 2.43956998 -1.11418002 1 P 8191 
A 2.49955 -1.1203 2.52723002 -1.12985 2.58163209 -0.92727982 1 P 0 N
A 2.55001998 -1.14328002 2.52723002 -1.12986004 2.51462185 -1.17733228 1 P 0 N
L 2.46181004 -1.12868996 2.36843996 -1.12868996 1 P 0 
A 2.36843996 -1.12868996 2.37851998 -1.15751998 2.41186801 -1.12968307 1 P 0 N
L 2.34675 -1.1402 2.34675 -1.11835 1 P 8191 
L 2.46181004 -1.11835 2.46181004 -1.12868996 1 P 8191 
L 2.25188002 -1.11398996 2.25188002 -1.11418002 1 P 8191 
A 2.3208 -1.02041004 2.3006 -1.02033996 2.31069163 -1.02276978 1 P 0 N
L 2.27413002 -1.11835 2.27413002 -1.12868996 1 P 8191 
A 2.52848996 -1.16771004 2.54891998 -1.15895 2.52774557 -1.13777087 1 P 0 N
A 2.55608002 -1.08618002 2.53611998 -1.07688996 2.5249185 -1.12704419 1 P 0 N
L 2.71926004 -1.06796998 2.71926004 -1.17483996 1 P 0 
A 2.78888996 -1.16296998 2.81508002 -1.16676998 2.8083499 -1.12100167 1 P 0 N
A 2.8151 -1.16675 2.83966004 -1.15211998 2.80521398 -1.12222392 1 P 0 N
A 2.85201004 -1.16508002 2.83966004 -1.15211004 2.84505768 -1.15933514 1 P 0 N
L 2.85201004 -1.16508002 2.84523996 -1.17161004 1 P 8191 
A 2.81425 -1.1835 2.84525 -1.17161004 2.81425 -1.13714291 1 P 0 N
L 2.81425 -1.1835 2.79571004 -1.1835 1 P 8191 
A 2.75886998 -1.16443002 2.79571998 -1.18351998 2.80278976 -1.12476142 1 P 0 N
A 2.74528996 -1.13568002 2.75888002 -1.16443002 2.80246565 -1.12624016 1 P 0 N
A 2.54316998 -1.1834 2.56906004 -1.1647 2.5305814 -1.13869892 1 P 0 N
A 2.56906004 -1.1647 2.57053996 -1.13728002 2.53763041 -1.14925374 1 P 0 N
A 2.65463996 -1.18351998 2.66863996 -1.17373996 2.65440246 -1.16826969 1 P 0 N
L 2.65463002 -1.1835 2.64165 -1.1835 1 P 8191 
A 2.60955 -1.16043002 2.64163996 -1.18351004 2.63911063 -1.15317815 1 P 0 N
A 2.62978002 -1.15461998 2.66001998 -1.16328996 2.6502374 -1.14033868 1 P 0 N
A 2.66863996 -1.17375 2.66001998 -1.16328996 2.66100344 -1.17126132 1 P 0 N
A 2.6962 -1.17483996 2.71926004 -1.17483996 2.70773002 -1.17286427 1 P 0 N
L 2.69618996 -1.17483996 2.69618996 -1.06796998 1 P 0 
A 2.83833002 -1.09275 2.82661998 -1.08201998 2.74555758 -1.18224094 1 P 0 N
A 2.82661998 -1.08198996 2.80036998 -1.07538996 2.80348839 -1.11848878 1 P 0 N
A 2.80036004 -1.07541998 2.76848996 -1.09933002 2.80700217 -1.1174685 1 P 0 N
A 2.76848996 -1.09931998 2.76446004 -1.12066004 2.82315728 -1.120694 1 P 0 N
A 2.74998002 -1.09273996 2.74528996 -1.11838996 2.8498563 -1.12425591 1 P 0 N
A 2.7954 -1.05776998 2.74998996 -1.09273996 2.80799961 -1.12109961 1 P 0 N
L 2.79541004 -1.05776998 2.80918996 -1.05776998 1 P 8191 
A 2.85401998 -1.08106004 2.80918996 -1.05776998 2.80626024 -1.1181998 1 P 0 N
A 2.83833002 -1.09273996 2.85403002 -1.08106004 2.84418386 -1.08421683 1 P 0 N
L 2.76445 -1.12066004 2.76445 -1.12943002 1 P 8191 
A 2.76446004 -1.12943002 2.76836998 -1.14305 2.80607844 -1.12485364 1 P 0 N
A 2.76836998 -1.14305 2.78891004 -1.16296998 2.80906152 -1.12164144 1 P 0 N
L 2.74528996 -1.13566004 2.74528996 -1.11838996 1 P 8191 
A 2.55606004 -1.0862 2.56885 -1.07366998 2.56205354 -1.0795252 1 P 0 N
L 2.60953996 -1.07953996 2.59981998 -1.07953996 1 P 8191 
A 2.5993 -1.05931998 2.59981004 -1.07955 2.6022813 -1.06936624 1 P 0 N
L 2.5993 -1.05931998 2.60953996 -1.05931998 1 P 8191 
L 2.60953996 -1.05931998 2.60953996 -1.03491998 1 P 8191 
A 2.62971998 -1.03418002 2.60953996 -1.03491004 2.61966791 -1.03559478 1 P 0 N
L 2.62971004 -1.03418996 2.62978002 -1.05931998 1 P 8191 
L 2.62978002 -1.05931998 2.66008002 -1.05931998 1 P 8191 
A 2.66003996 -1.07955 2.66008002 -1.05931998 2.65827421 -1.0694314 1 P 0 N
L 2.66003002 -1.07953996 2.62978002 -1.07953996 1 P 8191 
A 2.71926004 -1.06796998 2.6962 -1.06796998 2.70773002 -1.0720561 1 P 0 N
A 2.71968996 -1.02341998 2.71968996 -1.02341998 2.70775 -1.02341998 1 P 0 N
A 2.57053996 -1.13728996 2.54306998 -1.11513002 2.53584449 -1.15219301 1 P 0 N
A 2.54891998 -1.15895 2.55001004 -1.14328002 2.54127923 -1.15054557 1 P 0 N
L 2.60953996 -1.16041004 2.60953996 -1.07953996 1 P 0 
L 2.62978002 -1.07953996 2.62978002 -1.15463002 1 P 0 
L 2.98495 -1.09393996 2.98495 -1.17625 1 P 0 
A 2.96473996 -1.17626998 2.98493996 -1.17626998 2.97483996 -1.17442303 1 P 0 N
L 2.96473002 -1.17625 2.96473002 -1.17226004 1 P 8191 
A 2.94165 -1.1835 2.96471004 -1.17226004 2.93076516 -1.1318935 1 P 0 N
L 2.94165 -1.1835 2.90701004 -1.1835 1 P 8191 
A 2.90671004 -1.10841998 2.90703002 -1.18351004 2.9153065 -1.14592904 1 P 0 N
A 2.91853002 -1.12288996 2.91853002 -1.16618996 2.92048209 -1.14453996 1 P 0 N
L 2.91853002 -1.1662 2.94456004 -1.1662 1 P 8191 
A 2.94456998 -1.16618996 2.94456998 -1.12288996 2.94406004 -1.14453996 1 P 0 N
A 2.96473002 -1.09686004 2.94741998 -1.07955 2.94874833 -1.09553169 1 P 0 N
L 2.9474 -1.07953996 2.90986998 -1.07953996 1 P 8191 
A 2.90986998 -1.07953996 2.89821004 -1.0852 2.92433445 -1.12417766 1 P 0 N
A 2.89111998 -1.07086004 2.8982 -1.0852 2.8969689 -1.07688996 1 P 0 N
A 2.91561998 -1.05931998 2.89111998 -1.07085 2.92146033 -1.103525 1 P 0 N
L 2.91563002 -1.05931998 2.95031004 -1.05931998 1 P 8191 
A 2.98496004 -1.09393996 2.95031004 -1.05933002 2.9453438 -1.09895197 1 P 0 N
A 2.92878996 -1.10535 2.9067 -1.10841998 2.93158484 -1.20646998 1 P 0 N
A 2.96471998 -1.10841004 2.92878002 -1.10536004 2.93215738 -1.27883829 1 P 0 N
L 2.96473002 -1.10841004 2.96473002 -1.09686004 1 P 8191 
L 2.94456004 -1.12288002 2.91853002 -1.12288002 1 P 8191 
L 3.04731004 -1.06001004 3.04191998 -1.07631998 1 P 8191 
L 3.04191998 -1.07631998 3.03648002 -1.06001004 1 P 8191 
L 3.03648002 -1.06001004 3.03243002 -1.06001004 1 P 8191 
L 3.03243002 -1.06001004 3.02698002 -1.08543996 1 P 8191 
L 3.02698002 -1.08543996 3.03226004 -1.08543996 1 P 8191 
L 3.03226004 -1.08543996 3.03501004 -1.06886998 1 P 8191 
L 3.03501004 -1.06886998 3.04086004 -1.08543996 1 P 8191 
L 3.04086004 -1.08543996 3.04308996 -1.08543996 1 P 8191 
L 3.04308996 -1.08543996 3.04888996 -1.06871004 1 P 8191 
L 3.04888996 -1.06871004 3.05171004 -1.08543996 1 P 8191 
L 3.05171004 -1.08543996 3.05713002 -1.08543996 1 P 8191 
L 3.05713002 -1.08543996 3.05163996 -1.06001004 1 P 8191 
L 3.05163996 -1.06001004 3.04731004 -1.06001004 1 P 8191 
L 3.01066998 -1.06508002 3.00223002 -1.06508002 1 P 8191 
L 3.00223002 -1.06508002 3.00223002 -1.06001004 1 P 8191 
L 3.00223002 -1.06001004 3.02461004 -1.06001004 1 P 8191 
L 3.02461004 -1.06001004 3.02461004 -1.06508002 1 P 8191 
L 3.02461004 -1.06508002 3.01615 -1.06508002 1 P 8191 
L 3.01615 -1.06508002 3.01615 -1.08533996 1 P 8191 
L 3.01615 -1.08533996 3.01066998 -1.08533996 1 P 8191 
L 3.01066998 -1.08533996 3.01066998 -1.06508002 1 P 8191 
L 3.81697992 -1.31815217 3.82444665 -1.32440089 0 P 0 ;0,2=9,3=0.000000
L 3.82444665 -1.32440089 3.83284656 -1.32815 0 P 0 ;0,2=9,3=0.000000
L 3.83284656 -1.32815 3.84031339 -1.32815 0 P 0 ;0,2=9,3=0.000000
L 3.84031339 -1.32815 3.84778012 -1.32440089 0 P 0 ;0,2=9,3=0.000000
L 3.84778012 -1.32440089 3.85338061 -1.31815217 0 P 0 ;0,2=9,3=0.000000
L 3.85338061 -1.31815217 3.85618002 -1.30939951 0 P 0 ;0,2=9,3=0.000000
L 3.85618002 -1.30939951 3.85431378 -1.30065138 0 P 0 ;0,2=9,3=0.000000
L 3.85431378 -1.30065138 3.84964646 -1.29315069 0 P 0 ;0,2=9,3=0.000000
L 3.84964646 -1.29315069 3.84124646 -1.28814941 0 P 0 ;0,2=9,3=0.000000
L 3.84124646 -1.28814941 3.83004715 -1.28565 0 P 0 ;0,2=9,3=0.000000
L 3.83004715 -1.28565 3.82351348 -1.28065108 0 P 0 ;0,2=9,3=0.000000
L 3.82351348 -1.28065108 3.8207124 -1.27190059 0 P 0 ;0,2=9,3=0.000000
L 3.8207124 -1.27190059 3.82258041 -1.2631502 0 P 0 ;0,2=9,3=0.000000
L 3.82258041 -1.2631502 3.82724606 -1.25690157 0 P 0 ;0,2=9,3=0.000000
L 3.82724606 -1.25690157 3.83377972 -1.25315 0 P 0 ;0,2=9,3=0.000000
L 3.83377972 -1.25315 3.84031339 -1.25315 0 P 0 ;0,2=9,3=0.000000
L 3.84031339 -1.25315 3.84684705 -1.25564951 0 P 0 ;0,2=9,3=0.000000
L 3.84684705 -1.25564951 3.85244754 -1.26190049 0 P 0 ;0,2=9,3=0.000000
L 3.90037982 -1.25315 3.92277844 -1.25315 0 P 0 ;0,2=9,3=0.000000
L 3.91157913 -1.25315 3.91157913 -1.32815 0 P 0 ;0,2=9,3=0.000000
L 3.90037982 -1.32815 3.92277844 -1.32815 0 P 0 ;0,2=9,3=0.000000
L 3.96791299 -1.25315 3.96791299 -1.32815 0 P 0 ;0,2=9,3=0.000000
L 3.96791299 -1.32815 4.00524695 -1.32815 0 P 0 ;0,2=9,3=0.000000
L 4.04104675 -1.32815 4.04104675 -1.25315 0 P 0 ;0,2=9,3=0.000000
L 4.0765127 -1.25315 4.04104675 -1.29940157 0 P 0 ;0,2=9,3=0.000000
L 4.08211319 -1.32815 4.05691348 -1.27815157 0 P 0 ;0,2=9,3=0.000000
L 4.11697992 -1.31815217 4.12444665 -1.32440089 0 P 0 ;0,2=9,3=0.000000
L 4.12444665 -1.32440089 4.13284656 -1.32815 0 P 0 ;0,2=9,3=0.000000
L 4.13284656 -1.32815 4.14031339 -1.32815 0 P 0 ;0,2=9,3=0.000000
L 4.14031339 -1.32815 4.14778012 -1.32440089 0 P 0 ;0,2=9,3=0.000000
L 4.14778012 -1.32440089 4.15338061 -1.31815217 0 P 0 ;0,2=9,3=0.000000
L 4.15338061 -1.31815217 4.15618002 -1.30939951 0 P 0 ;0,2=9,3=0.000000
L 4.15618002 -1.30939951 4.15431378 -1.30065138 0 P 0 ;0,2=9,3=0.000000
L 4.15431378 -1.30065138 4.14964646 -1.29315069 0 P 0 ;0,2=9,3=0.000000
L 4.14964646 -1.29315069 4.14124646 -1.28814941 0 P 0 ;0,2=9,3=0.000000
L 4.14124646 -1.28814941 4.13004715 -1.28565 0 P 0 ;0,2=9,3=0.000000
L 4.13004715 -1.28565 4.12351348 -1.28065108 0 P 0 ;0,2=9,3=0.000000
L 4.12351348 -1.28065108 4.1207124 -1.27190059 0 P 0 ;0,2=9,3=0.000000
L 4.1207124 -1.27190059 4.12258041 -1.2631502 0 P 0 ;0,2=9,3=0.000000
L 4.12258041 -1.2631502 4.12724606 -1.25690157 0 P 0 ;0,2=9,3=0.000000
L 4.12724606 -1.25690157 4.13377972 -1.25315 0 P 0 ;0,2=9,3=0.000000
L 4.13377972 -1.25315 4.14031339 -1.25315 0 P 0 ;0,2=9,3=0.000000
L 4.14031339 -1.25315 4.14684705 -1.25564951 0 P 0 ;0,2=9,3=0.000000
L 4.14684705 -1.25564951 4.15244754 -1.26190049 0 P 0 ;0,2=9,3=0.000000
L 4.23211319 -1.25940098 4.2265127 -1.25564951 0 P 0 ;0,2=9,3=0.000000
L 4.2265127 -1.25564951 4.21998071 -1.25315 0 P 0 ;0,2=9,3=0.000000
L 4.21998071 -1.25315 4.21251398 -1.25315 0 P 0 ;0,2=9,3=0.000000
L 4.21251398 -1.25315 4.2041123 -1.25690157 0 P 0 ;0,2=9,3=0.000000
L 4.2041123 -1.25690157 4.19758041 -1.2631502 0 P 0 ;0,2=9,3=0.000000
L 4.19758041 -1.2631502 4.19291299 -1.27065089 0 P 0 ;0,2=9,3=0.000000
L 4.19291299 -1.27065089 4.18917874 -1.28315049 0 P 0 ;0,2=9,3=0.000000
L 4.18917874 -1.28315049 4.18824567 -1.29440039 0 P 0 ;0,2=9,3=0.000000
L 4.18824567 -1.29440039 4.19011358 -1.3056503 0 P 0 ;0,2=9,3=0.000000
L 4.19011358 -1.3056503 4.19291299 -1.31315098 0 P 0 ;0,2=9,3=0.000000
L 4.19291299 -1.31315098 4.19851348 -1.32065167 0 P 0 ;0,2=9,3=0.000000
L 4.19851348 -1.32065167 4.20504715 -1.32565059 0 P 0 ;0,2=9,3=0.000000
L 4.20504715 -1.32565059 4.21157913 -1.32815 0 P 0 ;0,2=9,3=0.000000
L 4.21157913 -1.32815 4.2181128 -1.32815 0 P 0 ;0,2=9,3=0.000000
L 4.2181128 -1.32815 4.22464646 -1.32565059 0 P 0 ;0,2=9,3=0.000000
L 4.22464646 -1.32565059 4.23024695 -1.32190138 0 P 0 ;0,2=9,3=0.000000
L 4.23024695 -1.32190138 4.23491427 -1.31690246 0 P 0 ;0,2=9,3=0.000000
L 4.26791299 -1.32815 4.26791299 -1.25315 0 P 0 ;0,2=9,3=0.000000
L 4.26791299 -1.25315 4.29124646 -1.25315 0 P 0 ;0,2=9,3=0.000000
L 4.29124646 -1.25315 4.29871329 -1.25690157 0 P 0 ;0,2=9,3=0.000000
L 4.29871329 -1.25690157 4.30338061 -1.26190049 0 P 0 ;0,2=9,3=0.000000
L 4.30338061 -1.26190049 4.30524695 -1.27190059 0 P 0 ;0,2=9,3=0.000000
L 4.30524695 -1.27190059 4.30338061 -1.28190079 0 P 0 ;0,2=9,3=0.000000
L 4.30338061 -1.28190079 4.29778012 -1.28814941 0 P 0 ;0,2=9,3=0.000000
L 4.29778012 -1.28814941 4.29124646 -1.29190089 0 P 0 ;0,2=9,3=0.000000
L 4.29124646 -1.29190089 4.26791299 -1.29190089 0 P 0 ;0,2=9,3=0.000000
L 4.29124646 -1.29190089 4.30524695 -1.32815 0 P 0 ;0,2=9,3=0.000000
L 4.38024695 -1.32815 4.34291299 -1.32815 0 P 0 ;0,2=9,3=0.000000
L 4.34291299 -1.32815 4.34291299 -1.25315 0 P 0 ;0,2=9,3=0.000000
L 4.34291299 -1.25315 4.38024695 -1.25315 0 P 0 ;0,2=9,3=0.000000
L 4.36531339 -1.28939921 4.34291299 -1.28939921 0 P 0 ;0,2=9,3=0.000000
L 4.45524695 -1.32815 4.41791299 -1.32815 0 P 0 ;0,2=9,3=0.000000
L 4.41791299 -1.32815 4.41791299 -1.25315 0 P 0 ;0,2=9,3=0.000000
L 4.41791299 -1.25315 4.45524695 -1.25315 0 P 0 ;0,2=9,3=0.000000
L 4.44031339 -1.28939921 4.41791299 -1.28939921 0 P 0 ;0,2=9,3=0.000000
L 4.49011358 -1.32815 4.49011358 -1.25315 0 P 0 ;0,2=9,3=0.000000
L 4.49011358 -1.25315 4.53304636 -1.32815 0 P 0 ;0,2=9,3=0.000000
L 4.53304636 -1.32815 4.53304636 -1.25315 0 P 0 ;0,2=9,3=0.000000
L 4.66904587 -1.28814941 4.67278012 -1.2844002 0 P 0 ;0,2=9,3=0.000000
L 4.67278012 -1.2844002 4.67557953 -1.27815157 0 P 0 ;0,2=9,3=0.000000
L 4.67557953 -1.27815157 4.67744754 -1.26939882 0 P 0 ;0,2=9,3=0.000000
L 4.67744754 -1.26939882 4.67557953 -1.26190049 0 P 0 ;0,2=9,3=0.000000
L 4.67557953 -1.26190049 4.67184705 -1.25690157 0 P 0 ;0,2=9,3=0.000000
L 4.67184705 -1.25690157 4.66531339 -1.25315 0 P 0 ;0,2=9,3=0.000000
L 4.66531339 -1.25315 4.64011358 -1.25315 0 P 0 ;0,2=9,3=0.000000
L 4.64011358 -1.25315 4.64011358 -1.32815 0 P 0 ;0,2=9,3=0.000000
L 4.64011358 -1.32815 4.67091388 -1.32815 0 P 0 ;0,2=9,3=0.000000
L 4.67091388 -1.32815 4.67744754 -1.32315108 0 P 0 ;0,2=9,3=0.000000
L 4.67744754 -1.32315108 4.68118002 -1.31565039 0 P 0 ;0,2=9,3=0.000000
L 4.68118002 -1.31565039 4.68304636 -1.3069 0 P 0 ;0,2=9,3=0.000000
L 4.68304636 -1.3069 4.68118002 -1.29815187 0 P 0 ;0,2=9,3=0.000000
L 4.68118002 -1.29815187 4.67557953 -1.29065118 0 P 0 ;0,2=9,3=0.000000
L 4.67557953 -1.29065118 4.66904587 -1.28814941 0 P 0 ;0,2=9,3=0.000000
L 4.66904587 -1.28814941 4.64011358 -1.28814941 0 P 0 ;0,2=9,3=0.000000
L 4.73657913 -1.32815 4.7291123 -1.3269003 0 P 0 ;0,2=9,3=0.000000
L 4.7291123 -1.3269003 4.72258041 -1.32190138 0 P 0 ;0,2=9,3=0.000000
L 4.72258041 -1.32190138 4.71697992 -1.31440069 0 P 0 ;0,2=9,3=0.000000
L 4.71697992 -1.31440069 4.71324567 -1.3056503 0 P 0 ;0,2=9,3=0.000000
L 4.71324567 -1.3056503 4.71137933 -1.2956501 0 P 0 ;0,2=9,3=0.000000
L 4.71137933 -1.2956501 4.71137933 -1.28565 0 P 0 ;0,2=9,3=0.000000
L 4.71137933 -1.28565 4.71324567 -1.2756498 0 P 0 ;0,2=9,3=0.000000
L 4.71324567 -1.2756498 4.71697992 -1.26689941 0 P 0 ;0,2=9,3=0.000000
L 4.71697992 -1.26689941 4.72258041 -1.25940098 0 P 0 ;0,2=9,3=0.000000
L 4.72258041 -1.25940098 4.7291123 -1.2543998 0 P 0 ;0,2=9,3=0.000000
L 4.7291123 -1.2543998 4.73657913 -1.25315 0 P 0 ;0,2=9,3=0.000000
L 4.73657913 -1.25315 4.74404587 -1.2543998 0 P 0 ;0,2=9,3=0.000000
L 4.74404587 -1.2543998 4.75057953 -1.25940098 0 P 0 ;0,2=9,3=0.000000
L 4.75057953 -1.25940098 4.75618002 -1.26689941 0 P 0 ;0,2=9,3=0.000000
L 4.75618002 -1.26689941 4.75991427 -1.2756498 0 P 0 ;0,2=9,3=0.000000
L 4.75991427 -1.2756498 4.76178061 -1.28565 0 P 0 ;0,2=9,3=0.000000
L 4.76178061 -1.28565 4.76178061 -1.2956501 0 P 0 ;0,2=9,3=0.000000
L 4.76178061 -1.2956501 4.75991427 -1.3056503 0 P 0 ;0,2=9,3=0.000000
L 4.75991427 -1.3056503 4.75618002 -1.31440069 0 P 0 ;0,2=9,3=0.000000
L 4.75618002 -1.31440069 4.75057953 -1.32190138 0 P 0 ;0,2=9,3=0.000000
L 4.75057953 -1.32190138 4.74404587 -1.3269003 0 P 0 ;0,2=9,3=0.000000
L 4.74404587 -1.3269003 4.73657913 -1.32815 0 P 0 ;0,2=9,3=0.000000
L 4.81157913 -1.25315 4.81157913 -1.32815 0 P 0 ;0,2=9,3=0.000000
L 4.79011358 -1.25315 4.83304636 -1.25315 0 P 0 ;0,2=9,3=0.000000
L 3.36933297 -0.955 3.36933297 -0.88 0 P 0 ;0,2=10,3=0.000000
L 3.36933297 -0.88 3.39173337 -0.88 0 P 0 ;0,2=10,3=0.000000
L 3.39173337 -0.88 3.3992001 -0.88375157 0 P 0 ;0,2=10,3=0.000000
L 3.3992001 -0.88375157 3.40480059 -0.8924997 0 P 0 ;0,2=10,3=0.000000
L 3.40480059 -0.8924997 3.40666693 -0.9024998 0 P 0 ;0,2=10,3=0.000000
L 3.40666693 -0.9024998 3.40480059 -0.9125 0 P 0 ;0,2=10,3=0.000000
L 3.40480059 -0.9125 3.40013327 -0.92000069 0 P 0 ;0,2=10,3=0.000000
L 3.40013327 -0.92000069 3.39173337 -0.92375217 0 P 0 ;0,2=10,3=0.000000
L 3.39173337 -0.92375217 3.36933297 -0.92375217 0 P 0 ;0,2=10,3=0.000000
L 3.44619931 -0.95749941 3.47980059 -0.88 0 P 0 ;0,2=10,3=0.000000
L 3.51653356 -0.955 3.51653356 -0.88 0 P 0 ;0,2=10,3=0.000000
L 3.51653356 -0.88 3.55946634 -0.955 0 P 0 ;0,2=10,3=0.000000
L 3.55946634 -0.955 3.55946634 -0.88 0 P 0 ;0,2=10,3=0.000000
L 3.68799911 -0.95749941 3.68613287 -0.9562497 0 P 0 ;0,2=10,3=0.000000
L 3.68613287 -0.9562497 3.68613287 -0.9537503 0 P 0 ;0,2=10,3=0.000000
L 3.68613287 -0.9537503 3.68799911 -0.95250059 0 P 0 ;0,2=10,3=0.000000
L 3.68799911 -0.95250059 3.68986703 -0.9537503 0 P 0 ;0,2=10,3=0.000000
L 3.68986703 -0.9537503 3.68986703 -0.9562497 0 P 0 ;0,2=10,3=0.000000
L 3.68986703 -0.9562497 3.68799911 -0.95749941 0 P 0 ;0,2=10,3=0.000000
L 3.68799911 -0.92375217 3.68613287 -0.9225001 0 P 0 ;0,2=10,3=0.000000
L 3.68613287 -0.9225001 3.68613287 -0.92000069 0 P 0 ;0,2=10,3=0.000000
L 3.68613287 -0.92000069 3.68799911 -0.91875089 0 P 0 ;0,2=10,3=0.000000
L 3.68799911 -0.91875089 3.68986703 -0.92000069 0 P 0 ;0,2=10,3=0.000000
L 3.68986703 -0.92000069 3.68986703 -0.9225001 0 P 0 ;0,2=10,3=0.000000
L 3.68986703 -0.9225001 3.68799911 -0.92375217 0 P 0 ;0,2=10,3=0.000000
L 3.81933297 -0.955 3.81933297 -0.88 0 P 0 ;0,2=10,3=0.000000
L 3.81933297 -0.88 3.84266644 -0.88 0 P 0 ;0,2=10,3=0.000000
L 3.84266644 -0.88 3.85013327 -0.88375157 0 P 0 ;0,2=10,3=0.000000
L 3.85013327 -0.88375157 3.85480059 -0.88875049 0 P 0 ;0,2=10,3=0.000000
L 3.85480059 -0.88875049 3.85666693 -0.89875059 0 P 0 ;0,2=10,3=0.000000
L 3.85666693 -0.89875059 3.85480059 -0.90875079 0 P 0 ;0,2=10,3=0.000000
L 3.85480059 -0.90875079 3.8492001 -0.91499941 0 P 0 ;0,2=10,3=0.000000
L 3.8492001 -0.91499941 3.84266644 -0.91875089 0 P 0 ;0,2=10,3=0.000000
L 3.84266644 -0.91875089 3.81933297 -0.91875089 0 P 0 ;0,2=10,3=0.000000
L 3.84266644 -0.91875089 3.85666693 -0.955 0 P 0 ;0,2=10,3=0.000000
L 3.9242001 -0.955 3.9242001 -0.88 0 P 0 ;0,2=10,3=0.000000
L 3.9242001 -0.88 3.88966565 -0.93375 0 P 0 ;0,2=10,3=0.000000
L 3.88966565 -0.93375 3.93633425 -0.93375 0 P 0 ;0,2=10,3=0.000000
L 3.98799911 -0.88 3.98053228 -0.88249951 0 P 0 ;0,2=10,3=0.000000
L 3.98053228 -0.88249951 3.97493346 -0.88875049 0 P 0 ;0,2=10,3=0.000000
L 3.97493346 -0.88875049 3.97119931 -0.89624882 0 P 0 ;0,2=10,3=0.000000
L 3.97119931 -0.89624882 3.9683999 -0.90625128 0 P 0 ;0,2=10,3=0.000000
L 3.9683999 -0.90625128 3.96746673 -0.91750118 0 P 0 ;0,2=10,3=0.000000
L 3.96746673 -0.91750118 3.9683999 -0.92875108 0 P 0 ;0,2=10,3=0.000000
L 3.9683999 -0.92875108 3.97119931 -0.93875128 0 P 0 ;0,2=10,3=0.000000
L 3.97119931 -0.93875128 3.97493346 -0.94625187 0 P 0 ;0,2=10,3=0.000000
L 3.97493346 -0.94625187 3.98053228 -0.95250059 0 P 0 ;0,2=10,3=0.000000
L 3.98053228 -0.95250059 3.98799911 -0.955 0 P 0 ;0,2=10,3=0.000000
L 3.98799911 -0.955 3.99546585 -0.95250059 0 P 0 ;0,2=10,3=0.000000
L 3.99546585 -0.95250059 4.00106644 -0.94625187 0 P 0 ;0,2=10,3=0.000000
L 4.00106644 -0.94625187 4.00480059 -0.93875128 0 P 0 ;0,2=10,3=0.000000
L 4.00480059 -0.93875128 4.0076 -0.92875108 0 P 0 ;0,2=10,3=0.000000
L 4.0076 -0.92875108 4.00853317 -0.91750118 0 P 0 ;0,2=10,3=0.000000
L 4.00853317 -0.91750118 4.0076 -0.90625128 0 P 0 ;0,2=10,3=0.000000
L 4.0076 -0.90625128 4.00480059 -0.89624882 0 P 0 ;0,2=10,3=0.000000
L 4.00480059 -0.89624882 4.00106644 -0.88875049 0 P 0 ;0,2=10,3=0.000000
L 4.00106644 -0.88875049 3.99546585 -0.88249951 0 P 0 ;0,2=10,3=0.000000
L 3.99546585 -0.88249951 3.98799911 -0.88 0 P 0 ;0,2=10,3=0.000000
L 4.06299911 -0.88 4.05553228 -0.88249951 0 P 0 ;0,2=10,3=0.000000
L 4.05553228 -0.88249951 4.04993346 -0.88875049 0 P 0 ;0,2=10,3=0.000000
L 4.04993346 -0.88875049 4.04619931 -0.89624882 0 P 0 ;0,2=10,3=0.000000
L 4.04619931 -0.89624882 4.0433999 -0.90625128 0 P 0 ;0,2=10,3=0.000000
L 4.0433999 -0.90625128 4.04246673 -0.91750118 0 P 0 ;0,2=10,3=0.000000
L 4.04246673 -0.91750118 4.0433999 -0.92875108 0 P 0 ;0,2=10,3=0.000000
L 4.0433999 -0.92875108 4.04619931 -0.93875128 0 P 0 ;0,2=10,3=0.000000
L 4.04619931 -0.93875128 4.04993346 -0.94625187 0 P 0 ;0,2=10,3=0.000000
L 4.04993346 -0.94625187 4.05553228 -0.95250059 0 P 0 ;0,2=10,3=0.000000
L 4.05553228 -0.95250059 4.06299911 -0.955 0 P 0 ;0,2=10,3=0.000000
L 4.06299911 -0.955 4.07046585 -0.95250059 0 P 0 ;0,2=10,3=0.000000
L 4.07046585 -0.95250059 4.07606644 -0.94625187 0 P 0 ;0,2=10,3=0.000000
L 4.07606644 -0.94625187 4.07980059 -0.93875128 0 P 0 ;0,2=10,3=0.000000
L 4.07980059 -0.93875128 4.0826 -0.92875108 0 P 0 ;0,2=10,3=0.000000
L 4.0826 -0.92875108 4.08353317 -0.91750118 0 P 0 ;0,2=10,3=0.000000
L 4.08353317 -0.91750118 4.0826 -0.90625128 0 P 0 ;0,2=10,3=0.000000
L 4.0826 -0.90625128 4.07980059 -0.89624882 0 P 0 ;0,2=10,3=0.000000
L 4.07980059 -0.89624882 4.07606644 -0.88875049 0 P 0 ;0,2=10,3=0.000000
L 4.07606644 -0.88875049 4.07046585 -0.88249951 0 P 0 ;0,2=10,3=0.000000
L 4.07046585 -0.88249951 4.06299911 -0.88 0 P 0 ;0,2=10,3=0.000000
L 4.12026614 -0.92375217 4.1267998 -0.91499941 0 P 0 ;0,2=10,3=0.000000
L 4.1267998 -0.91499941 4.1324003 -0.91000049 0 P 0 ;0,2=10,3=0.000000
L 4.1324003 -0.91000049 4.13986703 -0.90750108 0 P 0 ;0,2=10,3=0.000000
L 4.13986703 -0.90750108 4.14640069 -0.91000049 0 P 0 ;0,2=10,3=0.000000
L 4.14640069 -0.91000049 4.15106644 -0.91499941 0 P 0 ;0,2=10,3=0.000000
L 4.15106644 -0.91499941 4.15480059 -0.9225001 0 P 0 ;0,2=10,3=0.000000
L 4.15480059 -0.9225001 4.15573376 -0.93125059 0 P 0 ;0,2=10,3=0.000000
L 4.15573376 -0.93125059 4.15480059 -0.93875128 0 P 0 ;0,2=10,3=0.000000
L 4.15480059 -0.93875128 4.15106644 -0.94625187 0 P 0 ;0,2=10,3=0.000000
L 4.15106644 -0.94625187 4.14546585 -0.95250059 0 P 0 ;0,2=10,3=0.000000
L 4.14546585 -0.95250059 4.13893396 -0.955 0 P 0 ;0,2=10,3=0.000000
L 4.13893396 -0.955 4.13146713 -0.95250059 0 P 0 ;0,2=10,3=0.000000
L 4.13146713 -0.95250059 4.12493346 -0.94500217 0 P 0 ;0,2=10,3=0.000000
L 4.12493346 -0.94500217 4.12119931 -0.93375 0 P 0 ;0,2=10,3=0.000000
L 4.12119931 -0.93375 4.12026614 -0.92125039 0 P 0 ;0,2=10,3=0.000000
L 4.12026614 -0.92125039 4.12213238 -0.90500157 0 P 0 ;0,2=10,3=0.000000
L 4.12213238 -0.90500157 4.12493346 -0.89624882 0 P 0 ;0,2=10,3=0.000000
L 4.12493346 -0.89624882 4.12959921 -0.88750069 0 P 0 ;0,2=10,3=0.000000
L 4.12959921 -0.88750069 4.13613287 -0.8812498 0 P 0 ;0,2=10,3=0.000000
L 4.13613287 -0.8812498 4.14266644 -0.88 0 P 0 ;0,2=10,3=0.000000
L 4.14266644 -0.88 4.1492001 -0.88249951 0 P 0 ;0,2=10,3=0.000000
L 4.1492001 -0.88249951 4.15386752 -0.88875049 0 P 0 ;0,2=10,3=0.000000
L 4.20086663 -0.93000079 4.22513327 -0.93000079 0 P 0 ;0,2=10,3=0.000000
L 4.29546585 -0.91499941 4.2992001 -0.9112502 0 P 0 ;0,2=10,3=0.000000
L 4.2992001 -0.9112502 4.30199951 -0.90500157 0 P 0 ;0,2=10,3=0.000000
L 4.30199951 -0.90500157 4.30386752 -0.89624882 0 P 0 ;0,2=10,3=0.000000
L 4.30386752 -0.89624882 4.30199951 -0.88875049 0 P 0 ;0,2=10,3=0.000000
L 4.30199951 -0.88875049 4.29826703 -0.88375157 0 P 0 ;0,2=10,3=0.000000
L 4.29826703 -0.88375157 4.29173337 -0.88 0 P 0 ;0,2=10,3=0.000000
L 4.29173337 -0.88 4.26653356 -0.88 0 P 0 ;0,2=10,3=0.000000
L 4.26653356 -0.88 4.26653356 -0.955 0 P 0 ;0,2=10,3=0.000000
L 4.26653356 -0.955 4.29733386 -0.955 0 P 0 ;0,2=10,3=0.000000
L 4.29733386 -0.955 4.30386752 -0.95000108 0 P 0 ;0,2=10,3=0.000000
L 4.30386752 -0.95000108 4.3076 -0.94250039 0 P 0 ;0,2=10,3=0.000000
L 4.3076 -0.94250039 4.30946634 -0.93375 0 P 0 ;0,2=10,3=0.000000
L 4.30946634 -0.93375 4.3076 -0.92500187 0 P 0 ;0,2=10,3=0.000000
L 4.3076 -0.92500187 4.30199951 -0.91750118 0 P 0 ;0,2=10,3=0.000000
L 4.30199951 -0.91750118 4.29546585 -0.91499941 0 P 0 ;0,2=10,3=0.000000
L 4.29546585 -0.91499941 4.26653356 -0.91499941 0 P 0 ;0,2=10,3=0.000000
L 4.36299911 -0.88 4.35553228 -0.88249951 0 P 0 ;0,2=10,3=0.000000
L 4.35553228 -0.88249951 4.34993346 -0.88875049 0 P 0 ;0,2=10,3=0.000000
L 4.34993346 -0.88875049 4.34619931 -0.89624882 0 P 0 ;0,2=10,3=0.000000
L 4.34619931 -0.89624882 4.3433999 -0.90625128 0 P 0 ;0,2=10,3=0.000000
L 4.3433999 -0.90625128 4.34246673 -0.91750118 0 P 0 ;0,2=10,3=0.000000
L 4.34246673 -0.91750118 4.3433999 -0.92875108 0 P 0 ;0,2=10,3=0.000000
L 4.3433999 -0.92875108 4.34619931 -0.93875128 0 P 0 ;0,2=10,3=0.000000
L 4.34619931 -0.93875128 4.34993346 -0.94625187 0 P 0 ;0,2=10,3=0.000000
L 4.34993346 -0.94625187 4.35553228 -0.95250059 0 P 0 ;0,2=10,3=0.000000
L 4.35553228 -0.95250059 4.36299911 -0.955 0 P 0 ;0,2=10,3=0.000000
L 4.36299911 -0.955 4.37046585 -0.95250059 0 P 0 ;0,2=10,3=0.000000
L 4.37046585 -0.95250059 4.37606644 -0.94625187 0 P 0 ;0,2=10,3=0.000000
L 4.37606644 -0.94625187 4.37980059 -0.93875128 0 P 0 ;0,2=10,3=0.000000
L 4.37980059 -0.93875128 4.3826 -0.92875108 0 P 0 ;0,2=10,3=0.000000
L 4.3826 -0.92875108 4.38353317 -0.91750118 0 P 0 ;0,2=10,3=0.000000
L 4.38353317 -0.91750118 4.3826 -0.90625128 0 P 0 ;0,2=10,3=0.000000
L 4.3826 -0.90625128 4.37980059 -0.89624882 0 P 0 ;0,2=10,3=0.000000
L 4.37980059 -0.89624882 4.37606644 -0.88875049 0 P 0 ;0,2=10,3=0.000000
L 4.37606644 -0.88875049 4.37046585 -0.88249951 0 P 0 ;0,2=10,3=0.000000
L 4.37046585 -0.88249951 4.36299911 -0.88 0 P 0 ;0,2=10,3=0.000000
L 4.43799911 -0.88 4.43053228 -0.88249951 0 P 0 ;0,2=10,3=0.000000
L 4.43053228 -0.88249951 4.42493346 -0.88875049 0 P 0 ;0,2=10,3=0.000000
L 4.42493346 -0.88875049 4.42119931 -0.89624882 0 P 0 ;0,2=10,3=0.000000
L 4.42119931 -0.89624882 4.4183999 -0.90625128 0 P 0 ;0,2=10,3=0.000000
L 4.4183999 -0.90625128 4.41746673 -0.91750118 0 P 0 ;0,2=10,3=0.000000
L 4.41746673 -0.91750118 4.4183999 -0.92875108 0 P 0 ;0,2=10,3=0.000000
L 4.4183999 -0.92875108 4.42119931 -0.93875128 0 P 0 ;0,2=10,3=0.000000
L 4.42119931 -0.93875128 4.42493346 -0.94625187 0 P 0 ;0,2=10,3=0.000000
L 4.42493346 -0.94625187 4.43053228 -0.95250059 0 P 0 ;0,2=10,3=0.000000
L 4.43053228 -0.95250059 4.43799911 -0.955 0 P 0 ;0,2=10,3=0.000000
L 4.43799911 -0.955 4.44546585 -0.95250059 0 P 0 ;0,2=10,3=0.000000
L 4.44546585 -0.95250059 4.45106644 -0.94625187 0 P 0 ;0,2=10,3=0.000000
L 4.45106644 -0.94625187 4.45480059 -0.93875128 0 P 0 ;0,2=10,3=0.000000
L 4.45480059 -0.93875128 4.4576 -0.92875108 0 P 0 ;0,2=10,3=0.000000
L 4.4576 -0.92875108 4.45853317 -0.91750118 0 P 0 ;0,2=10,3=0.000000
L 4.45853317 -0.91750118 4.4576 -0.90625128 0 P 0 ;0,2=10,3=0.000000
L 4.4576 -0.90625128 4.45480059 -0.89624882 0 P 0 ;0,2=10,3=0.000000
L 4.45480059 -0.89624882 4.45106644 -0.88875049 0 P 0 ;0,2=10,3=0.000000
L 4.45106644 -0.88875049 4.44546585 -0.88249951 0 P 0 ;0,2=10,3=0.000000
L 4.44546585 -0.88249951 4.43799911 -0.88 0 P 0 ;0,2=10,3=0.000000
L 4.51299911 -0.88 4.50553228 -0.88249951 0 P 0 ;0,2=10,3=0.000000
L 4.50553228 -0.88249951 4.49993346 -0.88875049 0 P 0 ;0,2=10,3=0.000000
L 4.49993346 -0.88875049 4.49619931 -0.89624882 0 P 0 ;0,2=10,3=0.000000
L 4.49619931 -0.89624882 4.4933999 -0.90625128 0 P 0 ;0,2=10,3=0.000000
L 4.4933999 -0.90625128 4.49246673 -0.91750118 0 P 0 ;0,2=10,3=0.000000
L 4.49246673 -0.91750118 4.4933999 -0.92875108 0 P 0 ;0,2=10,3=0.000000
L 4.4933999 -0.92875108 4.49619931 -0.93875128 0 P 0 ;0,2=10,3=0.000000
L 4.49619931 -0.93875128 4.49993346 -0.94625187 0 P 0 ;0,2=10,3=0.000000
L 4.49993346 -0.94625187 4.50553228 -0.95250059 0 P 0 ;0,2=10,3=0.000000
L 4.50553228 -0.95250059 4.51299911 -0.955 0 P 0 ;0,2=10,3=0.000000
L 4.51299911 -0.955 4.52046585 -0.95250059 0 P 0 ;0,2=10,3=0.000000
L 4.52046585 -0.95250059 4.52606644 -0.94625187 0 P 0 ;0,2=10,3=0.000000
L 4.52606644 -0.94625187 4.52980059 -0.93875128 0 P 0 ;0,2=10,3=0.000000
L 4.52980059 -0.93875128 4.5326 -0.92875108 0 P 0 ;0,2=10,3=0.000000
L 4.5326 -0.92875108 4.53353317 -0.91750118 0 P 0 ;0,2=10,3=0.000000
L 4.53353317 -0.91750118 4.5326 -0.90625128 0 P 0 ;0,2=10,3=0.000000
L 4.5326 -0.90625128 4.52980059 -0.89624882 0 P 0 ;0,2=10,3=0.000000
L 4.52980059 -0.89624882 4.52606644 -0.88875049 0 P 0 ;0,2=10,3=0.000000
L 4.52606644 -0.88875049 4.52046585 -0.88249951 0 P 0 ;0,2=10,3=0.000000
L 4.52046585 -0.88249951 4.51299911 -0.88 0 P 0 ;0,2=10,3=0.000000
L 4.58799911 -0.955 4.58799911 -0.88 0 P 0 ;0,2=10,3=0.000000
L 4.58799911 -0.88 4.5767998 -0.89499911 0 P 0 ;0,2=10,3=0.000000
L 4.5767998 -0.955 4.59919843 -0.955 0 P 0 ;0,2=10,3=0.000000
L 4.65086663 -0.93000079 4.67513327 -0.93000079 0 P 0 ;0,2=10,3=0.000000
L 4.73799911 -0.88 4.73053228 -0.88249951 0 P 0 ;0,2=10,3=0.000000
L 4.73053228 -0.88249951 4.72493346 -0.88875049 0 P 0 ;0,2=10,3=0.000000
L 4.72493346 -0.88875049 4.72119931 -0.89624882 0 P 0 ;0,2=10,3=0.000000
L 4.72119931 -0.89624882 4.7183999 -0.90625128 0 P 0 ;0,2=10,3=0.000000
L 4.7183999 -0.90625128 4.71746673 -0.91750118 0 P 0 ;0,2=10,3=0.000000
L 4.71746673 -0.91750118 4.7183999 -0.92875108 0 P 0 ;0,2=10,3=0.000000
L 4.7183999 -0.92875108 4.72119931 -0.93875128 0 P 0 ;0,2=10,3=0.000000
L 4.72119931 -0.93875128 4.72493346 -0.94625187 0 P 0 ;0,2=10,3=0.000000
L 4.72493346 -0.94625187 4.73053228 -0.95250059 0 P 0 ;0,2=10,3=0.000000
L 4.73053228 -0.95250059 4.73799911 -0.955 0 P 0 ;0,2=10,3=0.000000
L 4.73799911 -0.955 4.74546585 -0.95250059 0 P 0 ;0,2=10,3=0.000000
L 4.74546585 -0.95250059 4.75106644 -0.94625187 0 P 0 ;0,2=10,3=0.000000
L 4.75106644 -0.94625187 4.75480059 -0.93875128 0 P 0 ;0,2=10,3=0.000000
L 4.75480059 -0.93875128 4.7576 -0.92875108 0 P 0 ;0,2=10,3=0.000000
L 4.7576 -0.92875108 4.75853317 -0.91750118 0 P 0 ;0,2=10,3=0.000000
L 4.75853317 -0.91750118 4.7576 -0.90625128 0 P 0 ;0,2=10,3=0.000000
L 4.7576 -0.90625128 4.75480059 -0.89624882 0 P 0 ;0,2=10,3=0.000000
L 4.75480059 -0.89624882 4.75106644 -0.88875049 0 P 0 ;0,2=10,3=0.000000
L 4.75106644 -0.88875049 4.74546585 -0.88249951 0 P 0 ;0,2=10,3=0.000000
L 4.74546585 -0.88249951 4.73799911 -0.88 0 P 0 ;0,2=10,3=0.000000
L 4.79526614 -0.8924997 4.80086663 -0.88500128 0 P 0 ;0,2=10,3=0.000000
L 4.80086663 -0.88500128 4.8074003 -0.8812498 0 P 0 ;0,2=10,3=0.000000
L 4.8074003 -0.8812498 4.81486703 -0.88 0 P 0 ;0,2=10,3=0.000000
L 4.81486703 -0.88 4.8242001 -0.88249951 0 P 0 ;0,2=10,3=0.000000
L 4.8242001 -0.88249951 4.83073376 -0.88875049 0 P 0 ;0,2=10,3=0.000000
L 4.83073376 -0.88875049 4.8326 -0.89624882 0 P 0 ;0,2=10,3=0.000000
L 4.8326 -0.89624882 4.83166693 -0.90375187 0 P 0 ;0,2=10,3=0.000000
L 4.83166693 -0.90375187 4.82793268 -0.91000049 0 P 0 ;0,2=10,3=0.000000
L 4.82793268 -0.91000049 4.80926654 -0.9225001 0 P 0 ;0,2=10,3=0.000000
L 4.80926654 -0.9225001 4.80086663 -0.93125059 0 P 0 ;0,2=10,3=0.000000
L 4.80086663 -0.93125059 4.79526614 -0.94375246 0 P 0 ;0,2=10,3=0.000000
L 4.79526614 -0.94375246 4.7933999 -0.955 0 P 0 ;0,2=10,3=0.000000
L 4.7933999 -0.955 4.8326 -0.955 0 P 0 ;0,2=10,3=0.000000
L 3.36746673 -1.205 3.36746673 -1.13 0 P 0 ;0,2=11,3=0.000000
L 3.36746673 -1.13 3.38613287 -1.13 0 P 0 ;0,2=11,3=0.000000
L 3.38613287 -1.13 3.39359961 -1.13375157 0 P 0 ;0,2=11,3=0.000000
L 3.39359961 -1.13375157 3.3992001 -1.13875049 0 P 0 ;0,2=11,3=0.000000
L 3.3992001 -1.13875049 3.40386752 -1.14624882 0 P 0 ;0,2=11,3=0.000000
L 3.40386752 -1.14624882 3.4076 -1.15500157 0 P 0 ;0,2=11,3=0.000000
L 3.4076 -1.15500157 3.40853317 -1.16750118 0 P 0 ;0,2=11,3=0.000000
L 3.40853317 -1.16750118 3.4076 -1.18000079 0 P 0 ;0,2=11,3=0.000000
L 3.4076 -1.18000079 3.40386752 -1.18875128 0 P 0 ;0,2=11,3=0.000000
L 3.40386752 -1.18875128 3.3992001 -1.19625187 0 P 0 ;0,2=11,3=0.000000
L 3.3992001 -1.19625187 3.39359961 -1.20125089 0 P 0 ;0,2=11,3=0.000000
L 3.39359961 -1.20125089 3.38613287 -1.205 0 P 0 ;0,2=11,3=0.000000
L 3.38613287 -1.205 3.36746673 -1.205 0 P 0 ;0,2=11,3=0.000000
L 3.47980059 -1.205 3.47980059 -1.15500157 0 P 0 ;0,2=11,3=0.000000
L 3.47980059 -1.1637497 3.47606644 -1.15875079 0 P 0 ;0,2=11,3=0.000000
L 3.47606644 -1.15875079 3.47046585 -1.15625128 0 P 0 ;0,2=11,3=0.000000
L 3.47046585 -1.15625128 3.46393396 -1.15500157 0 P 0 ;0,2=11,3=0.000000
L 3.46393396 -1.15500157 3.4574003 -1.15750108 0 P 0 ;0,2=11,3=0.000000
L 3.4574003 -1.15750108 3.4517998 -1.1625 0 P 0 ;0,2=11,3=0.000000
L 3.4517998 -1.1625 3.44806555 -1.17000069 0 P 0 ;0,2=11,3=0.000000
L 3.44806555 -1.17000069 3.44619931 -1.18000079 0 P 0 ;0,2=11,3=0.000000
L 3.44619931 -1.18000079 3.44806555 -1.19000098 0 P 0 ;0,2=11,3=0.000000
L 3.44806555 -1.19000098 3.4517998 -1.19750167 0 P 0 ;0,2=11,3=0.000000
L 3.4517998 -1.19750167 3.4574003 -1.20250059 0 P 0 ;0,2=11,3=0.000000
L 3.4574003 -1.20250059 3.46393396 -1.205 0 P 0 ;0,2=11,3=0.000000
L 3.46393396 -1.205 3.47046585 -1.2037503 0 P 0 ;0,2=11,3=0.000000
L 3.47046585 -1.2037503 3.47606644 -1.20000108 0 P 0 ;0,2=11,3=0.000000
L 3.47606644 -1.20000108 3.47980059 -1.19500217 0 P 0 ;0,2=11,3=0.000000
L 3.53799911 -1.13 3.53799911 -1.205 0 P 0 ;0,2=11,3=0.000000
L 3.52493346 -1.15500157 3.55106644 -1.15500157 0 P 0 ;0,2=11,3=0.000000
L 3.59900039 -1.17125039 3.62886752 -1.17125039 0 P 0 ;0,2=11,3=0.000000
L 3.62886752 -1.17125039 3.62606644 -1.1625 0 P 0 ;0,2=11,3=0.000000
L 3.62606644 -1.1625 3.62140069 -1.15750108 0 P 0 ;0,2=11,3=0.000000
L 3.62140069 -1.15750108 3.61486703 -1.15500157 0 P 0 ;0,2=11,3=0.000000
L 3.61486703 -1.15500157 3.60833346 -1.15625128 0 P 0 ;0,2=11,3=0.000000
L 3.60833346 -1.15625128 3.60273287 -1.16000049 0 P 0 ;0,2=11,3=0.000000
L 3.60273287 -1.16000049 3.59900039 -1.16875089 0 P 0 ;0,2=11,3=0.000000
L 3.59900039 -1.16875089 3.59713238 -1.17625157 0 P 0 ;0,2=11,3=0.000000
L 3.59713238 -1.17625157 3.59713238 -1.18375 0 P 0 ;0,2=11,3=0.000000
L 3.59713238 -1.18375 3.59900039 -1.19125069 0 P 0 ;0,2=11,3=0.000000
L 3.59900039 -1.19125069 3.60366604 -1.19875138 0 P 0 ;0,2=11,3=0.000000
L 3.60366604 -1.19875138 3.60926654 -1.2037503 0 P 0 ;0,2=11,3=0.000000
L 3.60926654 -1.2037503 3.6158002 -1.205 0 P 0 ;0,2=11,3=0.000000
L 3.6158002 -1.205 3.62233386 -1.20250059 0 P 0 ;0,2=11,3=0.000000
L 3.62233386 -1.20250059 3.62886752 -1.19500217 0 P 0 ;0,2=11,3=0.000000
L 3.68799911 -1.20749941 3.68613287 -1.2062497 0 P 0 ;0,2=11,3=0.000000
L 3.68613287 -1.2062497 3.68613287 -1.2037503 0 P 0 ;0,2=11,3=0.000000
L 3.68613287 -1.2037503 3.68799911 -1.20250059 0 P 0 ;0,2=11,3=0.000000
L 3.68799911 -1.20250059 3.68986703 -1.2037503 0 P 0 ;0,2=11,3=0.000000
L 3.68986703 -1.2037503 3.68986703 -1.2062497 0 P 0 ;0,2=11,3=0.000000
L 3.68986703 -1.2062497 3.68799911 -1.20749941 0 P 0 ;0,2=11,3=0.000000
L 3.68799911 -1.17375217 3.68613287 -1.1725001 0 P 0 ;0,2=11,3=0.000000
L 3.68613287 -1.1725001 3.68613287 -1.17000069 0 P 0 ;0,2=11,3=0.000000
L 3.68613287 -1.17000069 3.68799911 -1.16875089 0 P 0 ;0,2=11,3=0.000000
L 3.68799911 -1.16875089 3.68986703 -1.17000069 0 P 0 ;0,2=11,3=0.000000
L 3.68986703 -1.17000069 3.68986703 -1.1725001 0 P 0 ;0,2=11,3=0.000000
L 3.68986703 -1.1725001 3.68799911 -1.17375217 0 P 0 ;0,2=11,3=0.000000
L 3.82026614 -1.1424997 3.82586663 -1.13500128 0 P 0 ;0,2=11,3=0.000000
L 3.82586663 -1.13500128 3.8324003 -1.1312498 0 P 0 ;0,2=11,3=0.000000
L 3.8324003 -1.1312498 3.83986703 -1.13 0 P 0 ;0,2=11,3=0.000000
L 3.83986703 -1.13 3.8492001 -1.13249951 0 P 0 ;0,2=11,3=0.000000
L 3.8492001 -1.13249951 3.85573376 -1.13875049 0 P 0 ;0,2=11,3=0.000000
L 3.85573376 -1.13875049 3.8576 -1.14624882 0 P 0 ;0,2=11,3=0.000000
L 3.8576 -1.14624882 3.85666693 -1.15375187 0 P 0 ;0,2=11,3=0.000000
L 3.85666693 -1.15375187 3.85293268 -1.16000049 0 P 0 ;0,2=11,3=0.000000
L 3.85293268 -1.16000049 3.83426654 -1.1725001 0 P 0 ;0,2=11,3=0.000000
L 3.83426654 -1.1725001 3.82586663 -1.18125059 0 P 0 ;0,2=11,3=0.000000
L 3.82586663 -1.18125059 3.82026614 -1.19375246 0 P 0 ;0,2=11,3=0.000000
L 3.82026614 -1.19375246 3.8183999 -1.205 0 P 0 ;0,2=11,3=0.000000
L 3.8183999 -1.205 3.8576 -1.205 0 P 0 ;0,2=11,3=0.000000
L 3.91299911 -1.13 3.90553228 -1.13249951 0 P 0 ;0,2=11,3=0.000000
L 3.90553228 -1.13249951 3.89993346 -1.13875049 0 P 0 ;0,2=11,3=0.000000
L 3.89993346 -1.13875049 3.89619931 -1.14624882 0 P 0 ;0,2=11,3=0.000000
L 3.89619931 -1.14624882 3.8933999 -1.15625128 0 P 0 ;0,2=11,3=0.000000
L 3.8933999 -1.15625128 3.89246673 -1.16750118 0 P 0 ;0,2=11,3=0.000000
L 3.89246673 -1.16750118 3.8933999 -1.17875108 0 P 0 ;0,2=11,3=0.000000
L 3.8933999 -1.17875108 3.89619931 -1.18875128 0 P 0 ;0,2=11,3=0.000000
L 3.89619931 -1.18875128 3.89993346 -1.19625187 0 P 0 ;0,2=11,3=0.000000
L 3.89993346 -1.19625187 3.90553228 -1.20250059 0 P 0 ;0,2=11,3=0.000000
L 3.90553228 -1.20250059 3.91299911 -1.205 0 P 0 ;0,2=11,3=0.000000
L 3.91299911 -1.205 3.92046585 -1.20250059 0 P 0 ;0,2=11,3=0.000000
L 3.92046585 -1.20250059 3.92606644 -1.19625187 0 P 0 ;0,2=11,3=0.000000
L 3.92606644 -1.19625187 3.92980059 -1.18875128 0 P 0 ;0,2=11,3=0.000000
L 3.92980059 -1.18875128 3.9326 -1.17875108 0 P 0 ;0,2=11,3=0.000000
L 3.9326 -1.17875108 3.93353317 -1.16750118 0 P 0 ;0,2=11,3=0.000000
L 3.93353317 -1.16750118 3.9326 -1.15625128 0 P 0 ;0,2=11,3=0.000000
L 3.9326 -1.15625128 3.92980059 -1.14624882 0 P 0 ;0,2=11,3=0.000000
L 3.92980059 -1.14624882 3.92606644 -1.13875049 0 P 0 ;0,2=11,3=0.000000
L 3.92606644 -1.13875049 3.92046585 -1.13249951 0 P 0 ;0,2=11,3=0.000000
L 3.92046585 -1.13249951 3.91299911 -1.13 0 P 0 ;0,2=11,3=0.000000
L 3.97026614 -1.1424997 3.97586663 -1.13500128 0 P 0 ;0,2=11,3=0.000000
L 3.97586663 -1.13500128 3.9824003 -1.1312498 0 P 0 ;0,2=11,3=0.000000
L 3.9824003 -1.1312498 3.98986703 -1.13 0 P 0 ;0,2=11,3=0.000000
L 3.98986703 -1.13 3.9992001 -1.13249951 0 P 0 ;0,2=11,3=0.000000
L 3.9992001 -1.13249951 4.00573376 -1.13875049 0 P 0 ;0,2=11,3=0.000000
L 4.00573376 -1.13875049 4.0076 -1.14624882 0 P 0 ;0,2=11,3=0.000000
L 4.0076 -1.14624882 4.00666693 -1.15375187 0 P 0 ;0,2=11,3=0.000000
L 4.00666693 -1.15375187 4.00293268 -1.16000049 0 P 0 ;0,2=11,3=0.000000
L 4.00293268 -1.16000049 3.98426654 -1.1725001 0 P 0 ;0,2=11,3=0.000000
L 3.98426654 -1.1725001 3.97586663 -1.18125059 0 P 0 ;0,2=11,3=0.000000
L 3.97586663 -1.18125059 3.97026614 -1.19375246 0 P 0 ;0,2=11,3=0.000000
L 3.97026614 -1.19375246 3.9683999 -1.205 0 P 0 ;0,2=11,3=0.000000
L 3.9683999 -1.205 4.0076 -1.205 0 P 0 ;0,2=11,3=0.000000
L 4.04526614 -1.1424997 4.05086663 -1.13500128 0 P 0 ;0,2=11,3=0.000000
L 4.05086663 -1.13500128 4.0574003 -1.1312498 0 P 0 ;0,2=11,3=0.000000
L 4.0574003 -1.1312498 4.06486703 -1.13 0 P 0 ;0,2=11,3=0.000000
L 4.06486703 -1.13 4.0742001 -1.13249951 0 P 0 ;0,2=11,3=0.000000
L 4.0742001 -1.13249951 4.08073376 -1.13875049 0 P 0 ;0,2=11,3=0.000000
L 4.08073376 -1.13875049 4.0826 -1.14624882 0 P 0 ;0,2=11,3=0.000000
L 4.0826 -1.14624882 4.08166693 -1.15375187 0 P 0 ;0,2=11,3=0.000000
L 4.08166693 -1.15375187 4.07793268 -1.16000049 0 P 0 ;0,2=11,3=0.000000
L 4.07793268 -1.16000049 4.05926654 -1.1725001 0 P 0 ;0,2=11,3=0.000000
L 4.05926654 -1.1725001 4.05086663 -1.18125059 0 P 0 ;0,2=11,3=0.000000
L 4.05086663 -1.18125059 4.04526614 -1.19375246 0 P 0 ;0,2=11,3=0.000000
L 4.04526614 -1.19375246 4.0433999 -1.205 0 P 0 ;0,2=11,3=0.000000
L 4.0433999 -1.205 4.0826 -1.205 0 P 0 ;0,2=11,3=0.000000
L 4.12586663 -1.18000079 4.15013327 -1.18000079 0 P 0 ;0,2=11,3=0.000000
L 4.21299911 -1.13 4.20553228 -1.13249951 0 P 0 ;0,2=11,3=0.000000
L 4.20553228 -1.13249951 4.19993346 -1.13875049 0 P 0 ;0,2=11,3=0.000000
L 4.19993346 -1.13875049 4.19619931 -1.14624882 0 P 0 ;0,2=11,3=0.000000
L 4.19619931 -1.14624882 4.1933999 -1.15625128 0 P 0 ;0,2=11,3=0.000000
L 4.1933999 -1.15625128 4.19246673 -1.16750118 0 P 0 ;0,2=11,3=0.000000
L 4.19246673 -1.16750118 4.1933999 -1.17875108 0 P 0 ;0,2=11,3=0.000000
L 4.1933999 -1.17875108 4.19619931 -1.18875128 0 P 0 ;0,2=11,3=0.000000
L 4.19619931 -1.18875128 4.19993346 -1.19625187 0 P 0 ;0,2=11,3=0.000000
L 4.19993346 -1.19625187 4.20553228 -1.20250059 0 P 0 ;0,2=11,3=0.000000
L 4.20553228 -1.20250059 4.21299911 -1.205 0 P 0 ;0,2=11,3=0.000000
L 4.21299911 -1.205 4.22046585 -1.20250059 0 P 0 ;0,2=11,3=0.000000
L 4.22046585 -1.20250059 4.22606644 -1.19625187 0 P 0 ;0,2=11,3=0.000000
L 4.22606644 -1.19625187 4.22980059 -1.18875128 0 P 0 ;0,2=11,3=0.000000
L 4.22980059 -1.18875128 4.2326 -1.17875108 0 P 0 ;0,2=11,3=0.000000
L 4.2326 -1.17875108 4.23353317 -1.16750118 0 P 0 ;0,2=11,3=0.000000
L 4.23353317 -1.16750118 4.2326 -1.15625128 0 P 0 ;0,2=11,3=0.000000
L 4.2326 -1.15625128 4.22980059 -1.14624882 0 P 0 ;0,2=11,3=0.000000
L 4.22980059 -1.14624882 4.22606644 -1.13875049 0 P 0 ;0,2=11,3=0.000000
L 4.22606644 -1.13875049 4.22046585 -1.13249951 0 P 0 ;0,2=11,3=0.000000
L 4.22046585 -1.13249951 4.21299911 -1.13 0 P 0 ;0,2=11,3=0.000000
L 4.27026614 -1.1424997 4.27586663 -1.13500128 0 P 0 ;0,2=11,3=0.000000
L 4.27586663 -1.13500128 4.2824003 -1.1312498 0 P 0 ;0,2=11,3=0.000000
L 4.2824003 -1.1312498 4.28986703 -1.13 0 P 0 ;0,2=11,3=0.000000
L 4.28986703 -1.13 4.2992001 -1.13249951 0 P 0 ;0,2=11,3=0.000000
L 4.2992001 -1.13249951 4.30573376 -1.13875049 0 P 0 ;0,2=11,3=0.000000
L 4.30573376 -1.13875049 4.3076 -1.14624882 0 P 0 ;0,2=11,3=0.000000
L 4.3076 -1.14624882 4.30666693 -1.15375187 0 P 0 ;0,2=11,3=0.000000
L 4.30666693 -1.15375187 4.30293268 -1.16000049 0 P 0 ;0,2=11,3=0.000000
L 4.30293268 -1.16000049 4.28426654 -1.1725001 0 P 0 ;0,2=11,3=0.000000
L 4.28426654 -1.1725001 4.27586663 -1.18125059 0 P 0 ;0,2=11,3=0.000000
L 4.27586663 -1.18125059 4.27026614 -1.19375246 0 P 0 ;0,2=11,3=0.000000
L 4.27026614 -1.19375246 4.2683999 -1.205 0 P 0 ;0,2=11,3=0.000000
L 4.2683999 -1.205 4.3076 -1.205 0 P 0 ;0,2=11,3=0.000000
L 4.35086663 -1.18000079 4.37513327 -1.18000079 0 P 0 ;0,2=11,3=0.000000
L 4.42026614 -1.1424997 4.42586663 -1.13500128 0 P 0 ;0,2=11,3=0.000000
L 4.42586663 -1.13500128 4.4324003 -1.1312498 0 P 0 ;0,2=11,3=0.000000
L 4.4324003 -1.1312498 4.43986703 -1.13 0 P 0 ;0,2=11,3=0.000000
L 4.43986703 -1.13 4.4492001 -1.13249951 0 P 0 ;0,2=11,3=0.000000
L 4.4492001 -1.13249951 4.45573376 -1.13875049 0 P 0 ;0,2=11,3=0.000000
L 4.45573376 -1.13875049 4.4576 -1.14624882 0 P 0 ;0,2=11,3=0.000000
L 4.4576 -1.14624882 4.45666693 -1.15375187 0 P 0 ;0,2=11,3=0.000000
L 4.45666693 -1.15375187 4.45293268 -1.16000049 0 P 0 ;0,2=11,3=0.000000
L 4.45293268 -1.16000049 4.43426654 -1.1725001 0 P 0 ;0,2=11,3=0.000000
L 4.43426654 -1.1725001 4.42586663 -1.18125059 0 P 0 ;0,2=11,3=0.000000
L 4.42586663 -1.18125059 4.42026614 -1.19375246 0 P 0 ;0,2=11,3=0.000000
L 4.42026614 -1.19375246 4.4183999 -1.205 0 P 0 ;0,2=11,3=0.000000
L 4.4183999 -1.205 4.4576 -1.205 0 P 0 ;0,2=11,3=0.000000
L 4.49246673 -1.19375246 4.49806555 -1.20000108 0 P 0 ;0,2=11,3=0.000000
L 4.49806555 -1.20000108 4.50459921 -1.2037503 0 P 0 ;0,2=11,3=0.000000
L 4.50459921 -1.2037503 4.51299911 -1.205 0 P 0 ;0,2=11,3=0.000000
L 4.51299911 -1.205 4.52140069 -1.20250059 0 P 0 ;0,2=11,3=0.000000
L 4.52140069 -1.20250059 4.52793268 -1.19750167 0 P 0 ;0,2=11,3=0.000000
L 4.52793268 -1.19750167 4.5326 -1.18875128 0 P 0 ;0,2=11,3=0.000000
L 4.5326 -1.18875128 4.53353317 -1.17875108 0 P 0 ;0,2=11,3=0.000000
L 4.53353317 -1.17875108 4.53166693 -1.16875089 0 P 0 ;0,2=11,3=0.000000
L 4.53166693 -1.16875089 4.52699951 -1.1625 0 P 0 ;0,2=11,3=0.000000
L 4.52699951 -1.1625 4.52046585 -1.15750108 0 P 0 ;0,2=11,3=0.000000
L 4.52046585 -1.15750108 4.51393396 -1.15625128 0 P 0 ;0,2=11,3=0.000000
L 4.51393396 -1.15625128 4.5074003 -1.15750108 0 P 0 ;0,2=11,3=0.000000
L 4.5074003 -1.15750108 4.49900039 -1.1625 0 P 0 ;0,2=11,3=0.000000
L 4.49900039 -1.1625 4.5017998 -1.13 0 P 0 ;0,2=11,3=0.000000
L 4.5017998 -1.13 4.52699951 -1.13 0 P 0 ;0,2=11,3=0.000000
L 3.29433297 -1.255 3.29433297 -1.33 0 P 0 ;0,2=12,3=0.000000
L 3.29433297 -1.33 3.33166693 -1.33 0 P 0 ;0,2=12,3=0.000000
L 3.40480059 -1.33 3.40480059 -1.28000157 0 P 0 ;0,2=12,3=0.000000
L 3.40480059 -1.2887497 3.40106644 -1.28375079 0 P 0 ;0,2=12,3=0.000000
L 3.40106644 -1.28375079 3.39546585 -1.28125128 0 P 0 ;0,2=12,3=0.000000
L 3.39546585 -1.28125128 3.38893396 -1.28000157 0 P 0 ;0,2=12,3=0.000000
L 3.38893396 -1.28000157 3.3824003 -1.28250108 0 P 0 ;0,2=12,3=0.000000
L 3.3824003 -1.28250108 3.3767998 -1.2875 0 P 0 ;0,2=12,3=0.000000
L 3.3767998 -1.2875 3.37306555 -1.29500069 0 P 0 ;0,2=12,3=0.000000
L 3.37306555 -1.29500069 3.37119931 -1.30500079 0 P 0 ;0,2=12,3=0.000000
L 3.37119931 -1.30500079 3.37306555 -1.31500098 0 P 0 ;0,2=12,3=0.000000
L 3.37306555 -1.31500098 3.3767998 -1.32250167 0 P 0 ;0,2=12,3=0.000000
L 3.3767998 -1.32250167 3.3824003 -1.32750059 0 P 0 ;0,2=12,3=0.000000
L 3.3824003 -1.32750059 3.38893396 -1.33 0 P 0 ;0,2=12,3=0.000000
L 3.38893396 -1.33 3.39546585 -1.3287503 0 P 0 ;0,2=12,3=0.000000
L 3.39546585 -1.3287503 3.40106644 -1.32500108 0 P 0 ;0,2=12,3=0.000000
L 3.40106644 -1.32500108 3.40480059 -1.32000217 0 P 0 ;0,2=12,3=0.000000
L 3.4433999 -1.3524997 3.44900039 -1.35499921 0 P 0 ;0,2=12,3=0.000000
L 3.44900039 -1.35499921 3.45646713 -1.3524997 0 P 0 ;0,2=12,3=0.000000
L 3.45646713 -1.3524997 3.46113287 -1.34750079 0 P 0 ;0,2=12,3=0.000000
L 3.46113287 -1.34750079 3.46486703 -1.3412498 0 P 0 ;0,2=12,3=0.000000
L 3.46486703 -1.3412498 3.47046585 -1.32125187 0 P 0 ;0,2=12,3=0.000000
L 3.47046585 -1.32125187 3.4826 -1.28000157 0 P 0 ;0,2=12,3=0.000000
L 3.45273287 -1.28000157 3.47046585 -1.32125187 0 P 0 ;0,2=12,3=0.000000
L 3.52400039 -1.29625039 3.55386752 -1.29625039 0 P 0 ;0,2=12,3=0.000000
L 3.55386752 -1.29625039 3.55106644 -1.2875 0 P 0 ;0,2=12,3=0.000000
L 3.55106644 -1.2875 3.54640069 -1.28250108 0 P 0 ;0,2=12,3=0.000000
L 3.54640069 -1.28250108 3.53986703 -1.28000157 0 P 0 ;0,2=12,3=0.000000
L 3.53986703 -1.28000157 3.53333346 -1.28125128 0 P 0 ;0,2=12,3=0.000000
L 3.53333346 -1.28125128 3.52773287 -1.28500049 0 P 0 ;0,2=12,3=0.000000
L 3.52773287 -1.28500049 3.52400039 -1.29375089 0 P 0 ;0,2=12,3=0.000000
L 3.52400039 -1.29375089 3.52213238 -1.30125157 0 P 0 ;0,2=12,3=0.000000
L 3.52213238 -1.30125157 3.52213238 -1.30875 0 P 0 ;0,2=12,3=0.000000
L 3.52213238 -1.30875 3.52400039 -1.31625069 0 P 0 ;0,2=12,3=0.000000
L 3.52400039 -1.31625069 3.52866604 -1.32375138 0 P 0 ;0,2=12,3=0.000000
L 3.52866604 -1.32375138 3.53426654 -1.3287503 0 P 0 ;0,2=12,3=0.000000
L 3.53426654 -1.3287503 3.5408002 -1.33 0 P 0 ;0,2=12,3=0.000000
L 3.5408002 -1.33 3.54733386 -1.32750059 0 P 0 ;0,2=12,3=0.000000
L 3.54733386 -1.32750059 3.55386752 -1.32000217 0 P 0 ;0,2=12,3=0.000000
L 3.59993346 -1.33 3.59993346 -1.28000157 0 P 0 ;0,2=12,3=0.000000
L 3.59993346 -1.28999941 3.60459921 -1.28500049 0 P 0 ;0,2=12,3=0.000000
L 3.60459921 -1.28500049 3.60926654 -1.28125128 0 P 0 ;0,2=12,3=0.000000
L 3.60926654 -1.28125128 3.6158002 -1.28000157 0 P 0 ;0,2=12,3=0.000000
L 3.6158002 -1.28000157 3.62046585 -1.28125128 0 P 0 ;0,2=12,3=0.000000
L 3.62046585 -1.28125128 3.62606644 -1.28500049 0 P 0 ;0,2=12,3=0.000000
L 3.68799911 -1.33249941 3.68613287 -1.3312497 0 P 0 ;0,2=12,3=0.000000
L 3.68613287 -1.3312497 3.68613287 -1.3287503 0 P 0 ;0,2=12,3=0.000000
L 3.68613287 -1.3287503 3.68799911 -1.32750059 0 P 0 ;0,2=12,3=0.000000
L 3.68799911 -1.32750059 3.68986703 -1.3287503 0 P 0 ;0,2=12,3=0.000000
L 3.68986703 -1.3287503 3.68986703 -1.3312497 0 P 0 ;0,2=12,3=0.000000
L 3.68986703 -1.3312497 3.68799911 -1.33249941 0 P 0 ;0,2=12,3=0.000000
L 3.68799911 -1.29875217 3.68613287 -1.2975001 0 P 0 ;0,2=12,3=0.000000
L 3.68613287 -1.2975001 3.68613287 -1.29500069 0 P 0 ;0,2=12,3=0.000000
L 3.68613287 -1.29500069 3.68799911 -1.29375089 0 P 0 ;0,2=12,3=0.000000
L 3.68799911 -1.29375089 3.68986703 -1.29500069 0 P 0 ;0,2=12,3=0.000000
L 3.68986703 -1.29500069 3.68986703 -1.2975001 0 P 0 ;0,2=12,3=0.000000
L 3.68986703 -1.2975001 3.68799911 -1.29875217 0 P 0 ;0,2=12,3=0.000000
L 3.36933297 -1.08 3.36933297 -1.005 0 P 0 ;0,2=13,3=0.000000
L 3.36933297 -1.005 3.39266644 -1.005 0 P 0 ;0,2=13,3=0.000000
L 3.39266644 -1.005 3.40013327 -1.00875157 0 P 0 ;0,2=13,3=0.000000
L 3.40013327 -1.00875157 3.40480059 -1.01375049 0 P 0 ;0,2=13,3=0.000000
L 3.40480059 -1.01375049 3.40666693 -1.02375059 0 P 0 ;0,2=13,3=0.000000
L 3.40666693 -1.02375059 3.40480059 -1.03375079 0 P 0 ;0,2=13,3=0.000000
L 3.40480059 -1.03375079 3.3992001 -1.03999941 0 P 0 ;0,2=13,3=0.000000
L 3.3992001 -1.03999941 3.39266644 -1.04375089 0 P 0 ;0,2=13,3=0.000000
L 3.39266644 -1.04375089 3.36933297 -1.04375089 0 P 0 ;0,2=13,3=0.000000
L 3.39266644 -1.04375089 3.40666693 -1.08 0 P 0 ;0,2=13,3=0.000000
L 3.44900039 -1.04625039 3.47886752 -1.04625039 0 P 0 ;0,2=13,3=0.000000
L 3.47886752 -1.04625039 3.47606644 -1.0375 0 P 0 ;0,2=13,3=0.000000
L 3.47606644 -1.0375 3.47140069 -1.03250108 0 P 0 ;0,2=13,3=0.000000
L 3.47140069 -1.03250108 3.46486703 -1.03000157 0 P 0 ;0,2=13,3=0.000000
L 3.46486703 -1.03000157 3.45833346 -1.03125128 0 P 0 ;0,2=13,3=0.000000
L 3.45833346 -1.03125128 3.45273287 -1.03500049 0 P 0 ;0,2=13,3=0.000000
L 3.45273287 -1.03500049 3.44900039 -1.04375089 0 P 0 ;0,2=13,3=0.000000
L 3.44900039 -1.04375089 3.44713238 -1.05125157 0 P 0 ;0,2=13,3=0.000000
L 3.44713238 -1.05125157 3.44713238 -1.05875 0 P 0 ;0,2=13,3=0.000000
L 3.44713238 -1.05875 3.44900039 -1.06625069 0 P 0 ;0,2=13,3=0.000000
L 3.44900039 -1.06625069 3.45366604 -1.07375138 0 P 0 ;0,2=13,3=0.000000
L 3.45366604 -1.07375138 3.45926654 -1.0787503 0 P 0 ;0,2=13,3=0.000000
L 3.45926654 -1.0787503 3.4658002 -1.08 0 P 0 ;0,2=13,3=0.000000
L 3.4658002 -1.08 3.47233386 -1.07750059 0 P 0 ;0,2=13,3=0.000000
L 3.47233386 -1.07750059 3.47886752 -1.07000217 0 P 0 ;0,2=13,3=0.000000
L 3.52119931 -1.03000157 3.53799911 -1.08 0 P 0 ;0,2=13,3=0.000000
L 3.53799911 -1.08 3.55480059 -1.03000157 0 P 0 ;0,2=13,3=0.000000
L 3.68799911 -1.08249941 3.68613287 -1.0812497 0 P 0 ;0,2=13,3=0.000000
L 3.68613287 -1.0812497 3.68613287 -1.0787503 0 P 0 ;0,2=13,3=0.000000
L 3.68613287 -1.0787503 3.68799911 -1.07750059 0 P 0 ;0,2=13,3=0.000000
L 3.68799911 -1.07750059 3.68986703 -1.0787503 0 P 0 ;0,2=13,3=0.000000
L 3.68986703 -1.0787503 3.68986703 -1.0812497 0 P 0 ;0,2=13,3=0.000000
L 3.68986703 -1.0812497 3.68799911 -1.08249941 0 P 0 ;0,2=13,3=0.000000
L 3.68799911 -1.04875217 3.68613287 -1.0475001 0 P 0 ;0,2=13,3=0.000000
L 3.68613287 -1.0475001 3.68613287 -1.04500069 0 P 0 ;0,2=13,3=0.000000
L 3.68613287 -1.04500069 3.68799911 -1.04375089 0 P 0 ;0,2=13,3=0.000000
L 3.68799911 -1.04375089 3.68986703 -1.04500069 0 P 0 ;0,2=13,3=0.000000
L 3.68986703 -1.04500069 3.68986703 -1.0475001 0 P 0 ;0,2=13,3=0.000000
L 3.68986703 -1.0475001 3.68799911 -1.04875217 0 P 0 ;0,2=13,3=0.000000
L 3.83799911 -1.005 3.83053228 -1.00749951 0 P 0 ;0,2=13,3=0.000000
L 3.83053228 -1.00749951 3.82493346 -1.01375049 0 P 0 ;0,2=13,3=0.000000
L 3.82493346 -1.01375049 3.82119931 -1.02124882 0 P 0 ;0,2=13,3=0.000000
L 3.82119931 -1.02124882 3.8183999 -1.03125128 0 P 0 ;0,2=13,3=0.000000
L 3.8183999 -1.03125128 3.81746673 -1.04250118 0 P 0 ;0,2=13,3=0.000000
L 3.81746673 -1.04250118 3.8183999 -1.05375108 0 P 0 ;0,2=13,3=0.000000
L 3.8183999 -1.05375108 3.82119931 -1.06375128 0 P 0 ;0,2=13,3=0.000000
L 3.82119931 -1.06375128 3.82493346 -1.07125187 0 P 0 ;0,2=13,3=0.000000
L 3.82493346 -1.07125187 3.83053228 -1.07750059 0 P 0 ;0,2=13,3=0.000000
L 3.83053228 -1.07750059 3.83799911 -1.08 0 P 0 ;0,2=13,3=0.000000
L 3.83799911 -1.08 3.84546585 -1.07750059 0 P 0 ;0,2=13,3=0.000000
L 3.84546585 -1.07750059 3.85106644 -1.07125187 0 P 0 ;0,2=13,3=0.000000
L 3.85106644 -1.07125187 3.85480059 -1.06375128 0 P 0 ;0,2=13,3=0.000000
L 3.85480059 -1.06375128 3.8576 -1.05375108 0 P 0 ;0,2=13,3=0.000000
L 3.8576 -1.05375108 3.85853317 -1.04250118 0 P 0 ;0,2=13,3=0.000000
L 3.85853317 -1.04250118 3.8576 -1.03125128 0 P 0 ;0,2=13,3=0.000000
L 3.8576 -1.03125128 3.85480059 -1.02124882 0 P 0 ;0,2=13,3=0.000000
L 3.85480059 -1.02124882 3.85106644 -1.01375049 0 P 0 ;0,2=13,3=0.000000
L 3.85106644 -1.01375049 3.84546585 -1.00749951 0 P 0 ;0,2=13,3=0.000000
L 3.84546585 -1.00749951 3.83799911 -1.005 0 P 0 ;0,2=13,3=0.000000
L 3.91299911 -1.08 3.91299911 -1.005 0 P 0 ;0,2=13,3=0.000000
L 3.91299911 -1.005 3.9017998 -1.01999911 0 P 0 ;0,2=13,3=0.000000
L 3.9017998 -1.08 3.92419843 -1.08 0 P 0 ;0,2=13,3=0.000000
L 4.10696998 1.4706 4.10696998 1.5076 1 P 0 
L 4.03058996 1.4706 4.10696998 1.4706 1 P 0 
L 4.03058996 1.5076 4.03058996 1.4706 1 P 0 
L 4.10696998 1.5076 4.03058996 1.5076 1 P 0 
L 2.45833346 1.4225 2.45833346 1.4475 1 P 0 ;0,1,2=14,3=0.000000
L 2.45833346 1.4475 2.45166673 1.4475 1 P 0 ;0,1,2=14,3=0.000000
L 2.45166673 1.4475 2.44953337 1.44624941 1 P 0 ;0,1,2=14,3=0.000000
L 2.44953337 1.44624941 2.4481999 1.44458317 1 P 0 ;0,1,2=14,3=0.000000
L 2.4481999 1.44458317 2.44766663 1.4412498 1 P 0 ;0,1,2=14,3=0.000000
L 2.44766663 1.4412498 2.4481999 1.43791634 1 P 0 ;0,1,2=14,3=0.000000
L 2.4481999 1.43791634 2.4498 1.43583346 1 P 0 ;0,1,2=14,3=0.000000
L 2.4498 1.43583346 2.45166673 1.43458297 1 P 0 ;0,1,2=14,3=0.000000
L 2.45166673 1.43458297 2.45833346 1.43458297 1 P 0 ;0,1,2=14,3=0.000000
L 2.45166673 1.43458297 2.44766663 1.4225 1 P 0 ;0,1,2=14,3=0.000000
L 2.4310003 1.4225 2.4310003 1.4475 1 P 0 ;0,1,2=14,3=0.000000
L 2.4310003 1.4475 2.4342001 1.4425003 1 P 0 ;0,1,2=14,3=0.000000
L 2.4342001 1.4225 2.42780049 1.4225 1 P 0 ;0,1,2=14,3=0.000000
L 2.41353366 1.42541604 2.41166683 1.42333307 1 P 0 ;0,1,2=14,3=0.000000
L 2.41166683 1.42333307 2.40953346 1.4225 1 P 0 ;0,1,2=14,3=0.000000
L 2.40953346 1.4225 2.4074001 1.42333307 1 P 0 ;0,1,2=14,3=0.000000
L 2.4074001 1.42333307 2.40553337 1.42583258 1 P 0 ;0,1,2=14,3=0.000000
L 2.40553337 1.42583258 2.4041999 1.42958327 1 P 0 ;0,1,2=14,3=0.000000
L 2.4041999 1.42958327 2.40366663 1.43333327 1 P 0 ;0,1,2=14,3=0.000000
L 2.40366663 1.43333327 2.40366663 1.43791634 1 P 0 ;0,1,2=14,3=0.000000
L 2.40366663 1.43791634 2.4041999 1.44166634 1 P 0 ;0,1,2=14,3=0.000000
L 2.4041999 1.44166634 2.40553337 1.4449997 1 P 0 ;0,1,2=14,3=0.000000
L 2.40553337 1.4449997 2.40713356 1.44666683 1 P 0 ;0,1,2=14,3=0.000000
L 2.40713356 1.44666683 2.4090003 1.4475 1 P 0 ;0,1,2=14,3=0.000000
L 2.4090003 1.4475 2.41113366 1.44666683 1 P 0 ;0,1,2=14,3=0.000000
L 2.41113366 1.44666683 2.41273337 1.4449997 1 P 0 ;0,1,2=14,3=0.000000
L 2.41273337 1.4449997 2.4138002 1.4425003 1 P 0 ;0,1,2=14,3=0.000000
L 2.4138002 1.4425003 2.41433346 1.43916614 1 P 0 ;0,1,2=14,3=0.000000
L 2.41433346 1.43916614 2.4138002 1.4362501 1 P 0 ;0,1,2=14,3=0.000000
L 2.4138002 1.4362501 2.41246673 1.43333327 1 P 0 ;0,1,2=14,3=0.000000
L 2.41246673 1.43333327 2.41086654 1.43166614 1 P 0 ;0,1,2=14,3=0.000000
L 2.41086654 1.43166614 2.4090003 1.43124961 1 P 0 ;0,1,2=14,3=0.000000
L 2.4090003 1.43124961 2.40686693 1.43208278 1 P 0 ;0,1,2=14,3=0.000000
L 2.40686693 1.43208278 2.40526673 1.43416644 1 P 0 ;0,1,2=14,3=0.000000
L 2.40526673 1.43416644 2.40366663 1.43791634 1 P 0 ;0,1,2=14,3=0.000000
L 2.38753346 1.4225 2.3870003 1.42791624 1 P 0 ;0,1,2=14,3=0.000000
L 2.3870003 1.42791624 2.3862 1.43249931 1 P 0 ;0,1,2=14,3=0.000000
L 2.3862 1.43249931 2.38513356 1.43666663 1 P 0 ;0,1,2=14,3=0.000000
L 2.38513356 1.43666663 2.3838 1.4412498 1 P 0 ;0,1,2=14,3=0.000000
L 2.3838 1.4412498 2.38166663 1.4475 1 P 0 ;0,1,2=14,3=0.000000
L 2.38166663 1.4475 2.39233346 1.4475 1 P 0 ;0,1,2=14,3=0.000000
L 4.10696998 1.66745 4.10696998 1.70445 1 P 0 
L 4.03058996 1.66745 4.10696998 1.66745 1 P 0 
L 4.03058996 1.70445 4.03058996 1.66745 1 P 0 
L 4.10696998 1.70445 4.03058996 1.70445 1 P 0 
L 2.46833346 1.6375 2.46833346 1.6625 1 P 0 ;0,1,2=15,3=0.000000
L 2.46833346 1.6625 2.46166673 1.6625 1 P 0 ;0,1,2=15,3=0.000000
L 2.46166673 1.6625 2.45953337 1.66124941 1 P 0 ;0,1,2=15,3=0.000000
L 2.45953337 1.66124941 2.4581999 1.65958317 1 P 0 ;0,1,2=15,3=0.000000
L 2.4581999 1.65958317 2.45766663 1.6562498 1 P 0 ;0,1,2=15,3=0.000000
L 2.45766663 1.6562498 2.4581999 1.65291634 1 P 0 ;0,1,2=15,3=0.000000
L 2.4581999 1.65291634 2.4598 1.65083346 1 P 0 ;0,1,2=15,3=0.000000
L 2.4598 1.65083346 2.46166673 1.64958297 1 P 0 ;0,1,2=15,3=0.000000
L 2.46166673 1.64958297 2.46833346 1.64958297 1 P 0 ;0,1,2=15,3=0.000000
L 2.46166673 1.64958297 2.45766663 1.6375 1 P 0 ;0,1,2=15,3=0.000000
L 2.4410003 1.6375 2.4410003 1.6625 1 P 0 ;0,1,2=15,3=0.000000
L 2.4410003 1.6625 2.4442001 1.6575003 1 P 0 ;0,1,2=15,3=0.000000
L 2.4442001 1.6375 2.43780049 1.6375 1 P 0 ;0,1,2=15,3=0.000000
L 2.42353366 1.64041604 2.42166683 1.63833307 1 P 0 ;0,1,2=15,3=0.000000
L 2.42166683 1.63833307 2.41953346 1.6375 1 P 0 ;0,1,2=15,3=0.000000
L 2.41953346 1.6375 2.4174001 1.63833307 1 P 0 ;0,1,2=15,3=0.000000
L 2.4174001 1.63833307 2.41553337 1.64083258 1 P 0 ;0,1,2=15,3=0.000000
L 2.41553337 1.64083258 2.4141999 1.64458327 1 P 0 ;0,1,2=15,3=0.000000
L 2.4141999 1.64458327 2.41366663 1.64833327 1 P 0 ;0,1,2=15,3=0.000000
L 2.41366663 1.64833327 2.41366663 1.65291634 1 P 0 ;0,1,2=15,3=0.000000
L 2.41366663 1.65291634 2.4141999 1.65666634 1 P 0 ;0,1,2=15,3=0.000000
L 2.4141999 1.65666634 2.41553337 1.6599997 1 P 0 ;0,1,2=15,3=0.000000
L 2.41553337 1.6599997 2.41713356 1.66166683 1 P 0 ;0,1,2=15,3=0.000000
L 2.41713356 1.66166683 2.4190003 1.6625 1 P 0 ;0,1,2=15,3=0.000000
L 2.4190003 1.6625 2.42113366 1.66166683 1 P 0 ;0,1,2=15,3=0.000000
L 2.42113366 1.66166683 2.42273337 1.6599997 1 P 0 ;0,1,2=15,3=0.000000
L 2.42273337 1.6599997 2.4238002 1.6575003 1 P 0 ;0,1,2=15,3=0.000000
L 2.4238002 1.6575003 2.42433346 1.65416614 1 P 0 ;0,1,2=15,3=0.000000
L 2.42433346 1.65416614 2.4238002 1.6512501 1 P 0 ;0,1,2=15,3=0.000000
L 2.4238002 1.6512501 2.42246673 1.64833327 1 P 0 ;0,1,2=15,3=0.000000
L 2.42246673 1.64833327 2.42086654 1.64666614 1 P 0 ;0,1,2=15,3=0.000000
L 2.42086654 1.64666614 2.4190003 1.64624961 1 P 0 ;0,1,2=15,3=0.000000
L 2.4190003 1.64624961 2.41686693 1.64708278 1 P 0 ;0,1,2=15,3=0.000000
L 2.41686693 1.64708278 2.41526673 1.64916644 1 P 0 ;0,1,2=15,3=0.000000
L 2.41526673 1.64916644 2.41366663 1.65291634 1 P 0 ;0,1,2=15,3=0.000000
L 2.3970003 1.6375 2.39513356 1.63791654 1 P 0 ;0,1,2=15,3=0.000000
L 2.39513356 1.63791654 2.3930002 1.63916624 1 P 0 ;0,1,2=15,3=0.000000
L 2.3930002 1.63916624 2.39166663 1.64124911 1 P 0 ;0,1,2=15,3=0.000000
L 2.39166663 1.64124911 2.39113337 1.64416673 1 P 0 ;0,1,2=15,3=0.000000
L 2.39113337 1.64416673 2.39166663 1.64708278 1 P 0 ;0,1,2=15,3=0.000000
L 2.39166663 1.64708278 2.39326673 1.64958297 1 P 0 ;0,1,2=15,3=0.000000
L 2.39326673 1.64958297 2.39566673 1.65083346 1 P 0 ;0,1,2=15,3=0.000000
L 2.39566673 1.65083346 2.39833337 1.65083346 1 P 0 ;0,1,2=15,3=0.000000
L 2.39833337 1.65083346 2.39993346 1.65166663 1 P 0 ;0,1,2=15,3=0.000000
L 2.39993346 1.65166663 2.40126703 1.65374951 1 P 0 ;0,1,2=15,3=0.000000
L 2.40126703 1.65374951 2.4018002 1.65666634 1 P 0 ;0,1,2=15,3=0.000000
L 2.4018002 1.65666634 2.4009999 1.65958317 1 P 0 ;0,1,2=15,3=0.000000
L 2.4009999 1.65958317 2.39913366 1.66166683 1 P 0 ;0,1,2=15,3=0.000000
L 2.39913366 1.66166683 2.3970003 1.6625 1 P 0 ;0,1,2=15,3=0.000000
L 2.3970003 1.6625 2.39486693 1.66166683 1 P 0 ;0,1,2=15,3=0.000000
L 2.39486693 1.66166683 2.3930002 1.65958317 1 P 0 ;0,1,2=15,3=0.000000
L 2.3930002 1.65958317 2.3921999 1.65666634 1 P 0 ;0,1,2=15,3=0.000000
L 2.3921999 1.65666634 2.39273356 1.65374951 1 P 0 ;0,1,2=15,3=0.000000
L 2.39273356 1.65374951 2.39406663 1.65166663 1 P 0 ;0,1,2=15,3=0.000000
L 2.39406663 1.65166663 2.39566673 1.65083346 1 P 0 ;0,1,2=15,3=0.000000
L 2.39566673 1.65083346 2.39833337 1.65083346 1 P 0 ;0,1,2=15,3=0.000000
L 2.39833337 1.65083346 2.40073337 1.64958297 1 P 0 ;0,1,2=15,3=0.000000
L 2.40073337 1.64958297 2.40233346 1.64708278 1 P 0 ;0,1,2=15,3=0.000000
L 2.40233346 1.64708278 2.40286673 1.64416673 1 P 0 ;0,1,2=15,3=0.000000
L 2.40286673 1.64416673 2.40233346 1.64124911 1 P 0 ;0,1,2=15,3=0.000000
L 2.40233346 1.64124911 2.4009999 1.63916624 1 P 0 ;0,1,2=15,3=0.000000
L 2.4009999 1.63916624 2.39886654 1.63791654 1 P 0 ;0,1,2=15,3=0.000000
L 2.39886654 1.63791654 2.3970003 1.6375 1 P 0 ;0,1,2=15,3=0.000000
L 4.7369 2.06115 4.7369 2.09815 1 P 0 
L 4.66051998 2.06115 4.7369 2.06115 1 P 0 
L 4.7369 2.09815 4.66051998 2.09815 1 P 0 
L 4.66051998 2.09815 4.66051998 2.06115 1 P 0 
L 4.64833346 2.0675 4.64833346 2.0925 1 P 0 ;0,1,2=16,3=0.000000
L 4.64833346 2.0925 4.64166673 2.0925 1 P 0 ;0,1,2=16,3=0.000000
L 4.64166673 2.0925 4.63953337 2.09124941 1 P 0 ;0,1,2=16,3=0.000000
L 4.63953337 2.09124941 4.6381999 2.08958317 1 P 0 ;0,1,2=16,3=0.000000
L 4.6381999 2.08958317 4.63766663 2.0862498 1 P 0 ;0,1,2=16,3=0.000000
L 4.63766663 2.0862498 4.6381999 2.08291634 1 P 0 ;0,1,2=16,3=0.000000
L 4.6381999 2.08291634 4.6398 2.08083346 1 P 0 ;0,1,2=16,3=0.000000
L 4.6398 2.08083346 4.64166673 2.07958297 1 P 0 ;0,1,2=16,3=0.000000
L 4.64166673 2.07958297 4.64833346 2.07958297 1 P 0 ;0,1,2=16,3=0.000000
L 4.64166673 2.07958297 4.63766663 2.0675 1 P 0 ;0,1,2=16,3=0.000000
L 4.62686673 2.07124911 4.62526703 2.06916624 1 P 0 ;0,1,2=16,3=0.000000
L 4.62526703 2.06916624 4.6234003 2.06791654 1 P 0 ;0,1,2=16,3=0.000000
L 4.6234003 2.06791654 4.6210003 2.0675 1 P 0 ;0,1,2=16,3=0.000000
L 4.6210003 2.0675 4.6185998 2.06833307 1 P 0 ;0,1,2=16,3=0.000000
L 4.6185998 2.06833307 4.61673356 2.06999941 1 P 0 ;0,1,2=16,3=0.000000
L 4.61673356 2.06999941 4.6154 2.07291624 1 P 0 ;0,1,2=16,3=0.000000
L 4.6154 2.07291624 4.61513337 2.07624961 1 P 0 ;0,1,2=16,3=0.000000
L 4.61513337 2.07624961 4.61566663 2.07958297 1 P 0 ;0,1,2=16,3=0.000000
L 4.61566663 2.07958297 4.6170002 2.08166663 1 P 0 ;0,1,2=16,3=0.000000
L 4.6170002 2.08166663 4.61886693 2.08333297 1 P 0 ;0,1,2=16,3=0.000000
L 4.61886693 2.08333297 4.62073317 2.08374951 1 P 0 ;0,1,2=16,3=0.000000
L 4.62073317 2.08374951 4.6226 2.08333297 1 P 0 ;0,1,2=16,3=0.000000
L 4.6226 2.08333297 4.6249999 2.08166663 1 P 0 ;0,1,2=16,3=0.000000
L 4.6249999 2.08166663 4.6242001 2.0925 1 P 0 ;0,1,2=16,3=0.000000
L 4.6242001 2.0925 4.6170002 2.0925 1 P 0 ;0,1,2=16,3=0.000000
L 4.5990003 2.0925 4.60113366 2.09166683 1 P 0 ;0,1,2=16,3=0.000000
L 4.60113366 2.09166683 4.60273337 2.08958317 1 P 0 ;0,1,2=16,3=0.000000
L 4.60273337 2.08958317 4.6038002 2.08708366 1 P 0 ;0,1,2=16,3=0.000000
L 4.6038002 2.08708366 4.6046001 2.08374951 1 P 0 ;0,1,2=16,3=0.000000
L 4.6046001 2.08374951 4.60486673 2.07999961 1 P 0 ;0,1,2=16,3=0.000000
L 4.60486673 2.07999961 4.6046001 2.07624961 1 P 0 ;0,1,2=16,3=0.000000
L 4.6046001 2.07624961 4.6038002 2.07291624 1 P 0 ;0,1,2=16,3=0.000000
L 4.6038002 2.07291624 4.60273337 2.07041604 1 P 0 ;0,1,2=16,3=0.000000
L 4.60273337 2.07041604 4.60113366 2.06833307 1 P 0 ;0,1,2=16,3=0.000000
L 4.60113366 2.06833307 4.5990003 2.0675 1 P 0 ;0,1,2=16,3=0.000000
L 4.5990003 2.0675 4.59686693 2.06833307 1 P 0 ;0,1,2=16,3=0.000000
L 4.59686693 2.06833307 4.59526673 2.07041604 1 P 0 ;0,1,2=16,3=0.000000
L 4.59526673 2.07041604 4.5941999 2.07291624 1 P 0 ;0,1,2=16,3=0.000000
L 4.5941999 2.07291624 4.5934 2.07624961 1 P 0 ;0,1,2=16,3=0.000000
L 4.5934 2.07624961 4.59313337 2.07999961 1 P 0 ;0,1,2=16,3=0.000000
L 4.59313337 2.07999961 4.5934 2.08374951 1 P 0 ;0,1,2=16,3=0.000000
L 4.5934 2.08374951 4.5941999 2.08708366 1 P 0 ;0,1,2=16,3=0.000000
L 4.5941999 2.08708366 4.59526673 2.08958317 1 P 0 ;0,1,2=16,3=0.000000
L 4.59526673 2.08958317 4.59686693 2.09166683 1 P 0 ;0,1,2=16,3=0.000000
L 4.59686693 2.09166683 4.5990003 2.0925 1 P 0 ;0,1,2=16,3=0.000000
L 4.58286673 2.07249961 4.58126703 2.06958287 1 P 0 ;0,1,2=16,3=0.000000
L 4.58126703 2.06958287 4.57913366 2.06791654 1 P 0 ;0,1,2=16,3=0.000000
L 4.57913366 2.06791654 4.57673317 2.0675 1 P 0 ;0,1,2=16,3=0.000000
L 4.57673317 2.0675 4.5745998 2.06791654 1 P 0 ;0,1,2=16,3=0.000000
L 4.5745998 2.06791654 4.57246644 2.06999941 1 P 0 ;0,1,2=16,3=0.000000
L 4.57246644 2.06999941 4.57113337 2.07249961 1 P 0 ;0,1,2=16,3=0.000000
L 4.57113337 2.07249961 4.57086683 2.0749999 1 P 0 ;0,1,2=16,3=0.000000
L 4.57086683 2.0749999 4.5714 2.07791594 1 P 0 ;0,1,2=16,3=0.000000
L 4.5714 2.07791594 4.57326673 2.07999961 1 P 0 ;0,1,2=16,3=0.000000
L 4.57326673 2.07999961 4.57513356 2.08083346 1 P 0 ;0,1,2=16,3=0.000000
L 4.57513356 2.08083346 4.57753346 2.08083346 1 P 0 ;0,1,2=16,3=0.000000
L 4.57513356 2.08083346 4.57353337 2.08208327 1 P 0 ;0,1,2=16,3=0.000000
L 4.57353337 2.08208327 4.5721999 2.08416614 1 P 0 ;0,1,2=16,3=0.000000
L 4.5721999 2.08416614 4.57166663 2.08666634 1 P 0 ;0,1,2=16,3=0.000000
L 4.57166663 2.08666634 4.5721999 2.08916654 1 P 0 ;0,1,2=16,3=0.000000
L 4.5721999 2.08916654 4.57353337 2.09124941 1 P 0 ;0,1,2=16,3=0.000000
L 4.57353337 2.09124941 4.57593337 2.0925 1 P 0 ;0,1,2=16,3=0.000000
L 4.57593337 2.0925 4.57833337 2.09208337 1 P 0 ;0,1,2=16,3=0.000000
L 4.57833337 2.09208337 4.58073337 2.09041634 1 P 0 ;0,1,2=16,3=0.000000
L 4.73688996 2.10051998 4.73688996 2.1769 1 P 0 
L 4.73688996 2.1769 4.69988996 2.1769 1 P 0 
L 4.69988996 2.1769 4.69988996 2.10051998 1 P 0 
L 4.69988996 2.10051998 4.73688996 2.10051998 1 P 0 
L 4.7045 2.22083317 4.7355 2.22083317 1 P 0 ;0,1,2=17,3=90.000000
L 4.7355 2.22083317 4.7355 2.23041654 1 P 0 ;0,1,2=17,3=90.000000
L 4.7355 2.23041654 4.73394931 2.23348327 1 P 0 ;0,1,2=17,3=90.000000
L 4.73394931 2.23348327 4.73188307 2.2354002 1 P 0 ;0,1,2=17,3=90.000000
L 4.73188307 2.2354002 4.7277497 2.23616673 1 P 0 ;0,1,2=17,3=90.000000
L 4.7277497 2.23616673 4.72361634 2.2354002 1 P 0 ;0,1,2=17,3=90.000000
L 4.72361634 2.2354002 4.72103356 2.2331 1 P 0 ;0,1,2=17,3=90.000000
L 4.72103356 2.2331 4.71948287 2.23041654 1 P 0 ;0,1,2=17,3=90.000000
L 4.71948287 2.23041654 4.71948287 2.22083317 1 P 0 ;0,1,2=17,3=90.000000
L 4.71948287 2.23041654 4.7045 2.23616673 1 P 0 ;0,1,2=17,3=90.000000
L 4.70914892 2.25106663 4.70656614 2.25336614 1 P 0 ;0,1,2=17,3=90.000000
L 4.70656614 2.25336614 4.70501654 2.25604961 1 P 0 ;0,1,2=17,3=90.000000
L 4.70501654 2.25604961 4.7045 2.25949961 1 P 0 ;0,1,2=17,3=90.000000
L 4.7045 2.25949961 4.70553307 2.2629503 1 P 0 ;0,1,2=17,3=90.000000
L 4.70553307 2.2629503 4.70759931 2.26563307 1 P 0 ;0,1,2=17,3=90.000000
L 4.70759931 2.26563307 4.71121614 2.26755 1 P 0 ;0,1,2=17,3=90.000000
L 4.71121614 2.26755 4.71534951 2.26793327 1 P 0 ;0,1,2=17,3=90.000000
L 4.71534951 2.26793327 4.71948287 2.26716673 1 P 0 ;0,1,2=17,3=90.000000
L 4.71948287 2.26716673 4.72206663 2.2652498 1 P 0 ;0,1,2=17,3=90.000000
L 4.72206663 2.2652498 4.72413287 2.26256634 1 P 0 ;0,1,2=17,3=90.000000
L 4.72413287 2.26256634 4.72464941 2.25988356 1 P 0 ;0,1,2=17,3=90.000000
L 4.72464941 2.25988356 4.72413287 2.2572001 1 P 0 ;0,1,2=17,3=90.000000
L 4.72413287 2.2572001 4.72206663 2.2537501 1 P 0 ;0,1,2=17,3=90.000000
L 4.72206663 2.2537501 4.7355 2.2548999 1 P 0 ;0,1,2=17,3=90.000000
L 4.7355 2.2548999 4.7355 2.2652498 1 P 0 ;0,1,2=17,3=90.000000
L 4.7355 2.29049961 4.73446683 2.28743287 1 P 0 ;0,1,2=17,3=90.000000
L 4.73446683 2.28743287 4.73188307 2.28513337 1 P 0 ;0,1,2=17,3=90.000000
L 4.73188307 2.28513337 4.72878376 2.2835997 1 P 0 ;0,1,2=17,3=90.000000
L 4.72878376 2.2835997 4.72464941 2.2824499 1 P 0 ;0,1,2=17,3=90.000000
L 4.72464941 2.2824499 4.71999951 2.28206663 1 P 0 ;0,1,2=17,3=90.000000
L 4.71999951 2.28206663 4.71534951 2.2824499 1 P 0 ;0,1,2=17,3=90.000000
L 4.71534951 2.2824499 4.71121614 2.2835997 1 P 0 ;0,1,2=17,3=90.000000
L 4.71121614 2.2835997 4.70811585 2.28513337 1 P 0 ;0,1,2=17,3=90.000000
L 4.70811585 2.28513337 4.70553307 2.28743287 1 P 0 ;0,1,2=17,3=90.000000
L 4.70553307 2.28743287 4.7045 2.29049961 1 P 0 ;0,1,2=17,3=90.000000
L 4.7045 2.29049961 4.70553307 2.29356634 1 P 0 ;0,1,2=17,3=90.000000
L 4.70553307 2.29356634 4.70811585 2.29586654 1 P 0 ;0,1,2=17,3=90.000000
L 4.70811585 2.29586654 4.71121614 2.2974002 1 P 0 ;0,1,2=17,3=90.000000
L 4.71121614 2.2974002 4.71534951 2.29855 1 P 0 ;0,1,2=17,3=90.000000
L 4.71534951 2.29855 4.71999951 2.29893327 1 P 0 ;0,1,2=17,3=90.000000
L 4.71999951 2.29893327 4.72464941 2.29855 1 P 0 ;0,1,2=17,3=90.000000
L 4.72464941 2.29855 4.72878376 2.2974002 1 P 0 ;0,1,2=17,3=90.000000
L 4.72878376 2.2974002 4.73188307 2.29586654 1 P 0 ;0,1,2=17,3=90.000000
L 4.73188307 2.29586654 4.73446683 2.29356634 1 P 0 ;0,1,2=17,3=90.000000
L 4.73446683 2.29356634 4.7355 2.29049961 1 P 0 ;0,1,2=17,3=90.000000
L 4.7045 2.3261 4.7355 2.3261 1 P 0 ;0,1,2=17,3=90.000000
L 4.7355 2.3261 4.71328327 2.31191624 1 P 0 ;0,1,2=17,3=90.000000
L 4.71328327 2.31191624 4.71328327 2.33108366 1 P 0 ;0,1,2=17,3=90.000000
L 4.73688996 1.66745 4.73688996 1.70445 1 P 0 
L 4.73688996 1.70445 4.66051004 1.70445 1 P 0 
L 4.66051004 1.70445 4.66051004 1.66745 1 P 0 
L 4.66051004 1.66745 4.73688996 1.66745 1 P 0 
L 4.7975 1.61666654 4.8225 1.61666654 1 P 0 ;0,1,2=18,3=90.000000
L 4.8225 1.61666654 4.8225 1.62333327 1 P 0 ;0,1,2=18,3=90.000000
L 4.8225 1.62333327 4.82124941 1.62546663 1 P 0 ;0,1,2=18,3=90.000000
L 4.82124941 1.62546663 4.81958317 1.6268001 1 P 0 ;0,1,2=18,3=90.000000
L 4.81958317 1.6268001 4.8162498 1.62733337 1 P 0 ;0,1,2=18,3=90.000000
L 4.8162498 1.62733337 4.81291634 1.6268001 1 P 0 ;0,1,2=18,3=90.000000
L 4.81291634 1.6268001 4.81083346 1.6252 1 P 0 ;0,1,2=18,3=90.000000
L 4.81083346 1.6252 4.80958297 1.62333327 1 P 0 ;0,1,2=18,3=90.000000
L 4.80958297 1.62333327 4.80958297 1.61666654 1 P 0 ;0,1,2=18,3=90.000000
L 4.80958297 1.62333327 4.7975 1.62733337 1 P 0 ;0,1,2=18,3=90.000000
L 4.80124911 1.63813327 4.79916624 1.63973297 1 P 0 ;0,1,2=18,3=90.000000
L 4.79916624 1.63973297 4.79791654 1.6415997 1 P 0 ;0,1,2=18,3=90.000000
L 4.79791654 1.6415997 4.7975 1.6439997 1 P 0 ;0,1,2=18,3=90.000000
L 4.7975 1.6439997 4.79833307 1.6464002 1 P 0 ;0,1,2=18,3=90.000000
L 4.79833307 1.6464002 4.79999941 1.64826644 1 P 0 ;0,1,2=18,3=90.000000
L 4.79999941 1.64826644 4.80291624 1.6496 1 P 0 ;0,1,2=18,3=90.000000
L 4.80291624 1.6496 4.80624961 1.64986663 1 P 0 ;0,1,2=18,3=90.000000
L 4.80624961 1.64986663 4.80958297 1.64933337 1 P 0 ;0,1,2=18,3=90.000000
L 4.80958297 1.64933337 4.81166663 1.6479998 1 P 0 ;0,1,2=18,3=90.000000
L 4.81166663 1.6479998 4.81333297 1.64613307 1 P 0 ;0,1,2=18,3=90.000000
L 4.81333297 1.64613307 4.81374951 1.64426683 1 P 0 ;0,1,2=18,3=90.000000
L 4.81374951 1.64426683 4.81333297 1.6424 1 P 0 ;0,1,2=18,3=90.000000
L 4.81333297 1.6424 4.81166663 1.6400001 1 P 0 ;0,1,2=18,3=90.000000
L 4.81166663 1.6400001 4.8225 1.6407999 1 P 0 ;0,1,2=18,3=90.000000
L 4.8225 1.6407999 4.8225 1.6479998 1 P 0 ;0,1,2=18,3=90.000000
L 4.8225 1.6659997 4.82166683 1.66386634 1 P 0 ;0,1,2=18,3=90.000000
L 4.82166683 1.66386634 4.81958317 1.66226663 1 P 0 ;0,1,2=18,3=90.000000
L 4.81958317 1.66226663 4.81708366 1.6611998 1 P 0 ;0,1,2=18,3=90.000000
L 4.81708366 1.6611998 4.81374951 1.6603999 1 P 0 ;0,1,2=18,3=90.000000
L 4.81374951 1.6603999 4.80999961 1.66013327 1 P 0 ;0,1,2=18,3=90.000000
L 4.80999961 1.66013327 4.80624961 1.6603999 1 P 0 ;0,1,2=18,3=90.000000
L 4.80624961 1.6603999 4.80291624 1.6611998 1 P 0 ;0,1,2=18,3=90.000000
L 4.80291624 1.6611998 4.80041604 1.66226663 1 P 0 ;0,1,2=18,3=90.000000
L 4.80041604 1.66226663 4.79833307 1.66386634 1 P 0 ;0,1,2=18,3=90.000000
L 4.79833307 1.66386634 4.7975 1.6659997 1 P 0 ;0,1,2=18,3=90.000000
L 4.7975 1.6659997 4.79833307 1.66813307 1 P 0 ;0,1,2=18,3=90.000000
L 4.79833307 1.66813307 4.80041604 1.66973327 1 P 0 ;0,1,2=18,3=90.000000
L 4.80041604 1.66973327 4.80291624 1.6708001 1 P 0 ;0,1,2=18,3=90.000000
L 4.80291624 1.6708001 4.80624961 1.6716 1 P 0 ;0,1,2=18,3=90.000000
L 4.80624961 1.6716 4.80999961 1.67186663 1 P 0 ;0,1,2=18,3=90.000000
L 4.80999961 1.67186663 4.81374951 1.6716 1 P 0 ;0,1,2=18,3=90.000000
L 4.81374951 1.6716 4.81708366 1.6708001 1 P 0 ;0,1,2=18,3=90.000000
L 4.81708366 1.6708001 4.81958317 1.66973327 1 P 0 ;0,1,2=18,3=90.000000
L 4.81958317 1.66973327 4.82166683 1.66813307 1 P 0 ;0,1,2=18,3=90.000000
L 4.82166683 1.66813307 4.8225 1.6659997 1 P 0 ;0,1,2=18,3=90.000000
L 4.8225 1.6879997 4.82166683 1.68586634 1 P 0 ;0,1,2=18,3=90.000000
L 4.82166683 1.68586634 4.81958317 1.68426663 1 P 0 ;0,1,2=18,3=90.000000
L 4.81958317 1.68426663 4.81708366 1.6831998 1 P 0 ;0,1,2=18,3=90.000000
L 4.81708366 1.6831998 4.81374951 1.6823999 1 P 0 ;0,1,2=18,3=90.000000
L 4.81374951 1.6823999 4.80999961 1.68213327 1 P 0 ;0,1,2=18,3=90.000000
L 4.80999961 1.68213327 4.80624961 1.6823999 1 P 0 ;0,1,2=18,3=90.000000
L 4.80624961 1.6823999 4.80291624 1.6831998 1 P 0 ;0,1,2=18,3=90.000000
L 4.80291624 1.6831998 4.80041604 1.68426663 1 P 0 ;0,1,2=18,3=90.000000
L 4.80041604 1.68426663 4.79833307 1.68586634 1 P 0 ;0,1,2=18,3=90.000000
L 4.79833307 1.68586634 4.7975 1.6879997 1 P 0 ;0,1,2=18,3=90.000000
L 4.7975 1.6879997 4.79833307 1.69013307 1 P 0 ;0,1,2=18,3=90.000000
L 4.79833307 1.69013307 4.80041604 1.69173327 1 P 0 ;0,1,2=18,3=90.000000
L 4.80041604 1.69173327 4.80291624 1.6928001 1 P 0 ;0,1,2=18,3=90.000000
L 4.80291624 1.6928001 4.80624961 1.6936 1 P 0 ;0,1,2=18,3=90.000000
L 4.80624961 1.6936 4.80999961 1.69386663 1 P 0 ;0,1,2=18,3=90.000000
L 4.80999961 1.69386663 4.81374951 1.6936 1 P 0 ;0,1,2=18,3=90.000000
L 4.81374951 1.6936 4.81708366 1.6928001 1 P 0 ;0,1,2=18,3=90.000000
L 4.81708366 1.6928001 4.81958317 1.69173327 1 P 0 ;0,1,2=18,3=90.000000
L 4.81958317 1.69173327 4.82166683 1.69013307 1 P 0 ;0,1,2=18,3=90.000000
L 4.82166683 1.69013307 4.8225 1.6879997 1 P 0 ;0,1,2=18,3=90.000000
L 4.69751998 1.82493002 4.69751998 1.90131004 1 P 0 
L 4.69751998 1.90131004 4.66051998 1.90131004 1 P 0 
L 4.66051998 1.90131004 4.66051998 1.82493002 1 P 0 
L 4.66051998 1.82493002 4.69751998 1.82493002 1 P 0 
L 4.7375 1.89166654 4.7625 1.89166654 1 P 0 ;0,1,2=19,3=90.000000
L 4.7625 1.89166654 4.7625 1.89833327 1 P 0 ;0,1,2=19,3=90.000000
L 4.7625 1.89833327 4.76124941 1.90046663 1 P 0 ;0,1,2=19,3=90.000000
L 4.76124941 1.90046663 4.75958317 1.9018001 1 P 0 ;0,1,2=19,3=90.000000
L 4.75958317 1.9018001 4.7562498 1.90233337 1 P 0 ;0,1,2=19,3=90.000000
L 4.7562498 1.90233337 4.75291634 1.9018001 1 P 0 ;0,1,2=19,3=90.000000
L 4.75291634 1.9018001 4.75083346 1.9002 1 P 0 ;0,1,2=19,3=90.000000
L 4.75083346 1.9002 4.74958297 1.89833327 1 P 0 ;0,1,2=19,3=90.000000
L 4.74958297 1.89833327 4.74958297 1.89166654 1 P 0 ;0,1,2=19,3=90.000000
L 4.74958297 1.89833327 4.7375 1.90233337 1 P 0 ;0,1,2=19,3=90.000000
L 4.75833337 1.91393317 4.76083287 1.91553327 1 P 0 ;0,1,2=19,3=90.000000
L 4.76083287 1.91553327 4.76208337 1.9174 1 P 0 ;0,1,2=19,3=90.000000
L 4.76208337 1.9174 4.7625 1.91953337 1 P 0 ;0,1,2=19,3=90.000000
L 4.7625 1.91953337 4.76166683 1.9222 1 P 0 ;0,1,2=19,3=90.000000
L 4.76166683 1.9222 4.75958317 1.92406673 1 P 0 ;0,1,2=19,3=90.000000
L 4.75958317 1.92406673 4.75708366 1.9246 1 P 0 ;0,1,2=19,3=90.000000
L 4.75708366 1.9246 4.75458268 1.92433337 1 P 0 ;0,1,2=19,3=90.000000
L 4.75458268 1.92433337 4.7524998 1.92326644 1 P 0 ;0,1,2=19,3=90.000000
L 4.7524998 1.92326644 4.74833327 1.91793327 1 P 0 ;0,1,2=19,3=90.000000
L 4.74833327 1.91793327 4.74541644 1.91553327 1 P 0 ;0,1,2=19,3=90.000000
L 4.74541644 1.91553327 4.74124911 1.91393317 1 P 0 ;0,1,2=19,3=90.000000
L 4.74124911 1.91393317 4.7375 1.9133999 1 P 0 ;0,1,2=19,3=90.000000
L 4.7375 1.9133999 4.7375 1.9246 1 P 0 ;0,1,2=19,3=90.000000
L 4.7375 1.94046654 4.74291624 1.9409997 1 P 0 ;0,1,2=19,3=90.000000
L 4.74291624 1.9409997 4.74749931 1.9418 1 P 0 ;0,1,2=19,3=90.000000
L 4.74749931 1.9418 4.75166663 1.94286644 1 P 0 ;0,1,2=19,3=90.000000
L 4.75166663 1.94286644 4.7562498 1.9442 1 P 0 ;0,1,2=19,3=90.000000
L 4.7562498 1.9442 4.7625 1.94633337 1 P 0 ;0,1,2=19,3=90.000000
L 4.7625 1.94633337 4.7625 1.93566654 1 P 0 ;0,1,2=19,3=90.000000
L 4.7375 1.9629997 4.7625 1.9629997 1 P 0 ;0,1,2=19,3=90.000000
L 4.7625 1.9629997 4.7575003 1.9597999 1 P 0 ;0,1,2=19,3=90.000000
L 4.7375 1.9597999 4.7375 1.96619951 1 P 0 ;0,1,2=19,3=90.000000
L 4.54241004 1.8643 4.61878996 1.8643 1 P 0 
L 4.61878996 1.8643 4.61878996 1.9013 1 P 0 
L 4.61878996 1.9013 4.54241004 1.9013 1 P 0 
L 4.54241004 1.9013 4.54241004 1.8643 1 P 0 
L 2.92833346 1.7645 2.92833346 1.7895 1 P 0 ;0,1,2=20,3=0.000000
L 2.92833346 1.7895 2.92166673 1.7895 1 P 0 ;0,1,2=20,3=0.000000
L 2.92166673 1.7895 2.91953337 1.78824941 1 P 0 ;0,1,2=20,3=0.000000
L 2.91953337 1.78824941 2.9181999 1.78658317 1 P 0 ;0,1,2=20,3=0.000000
L 2.9181999 1.78658317 2.91766663 1.7832498 1 P 0 ;0,1,2=20,3=0.000000
L 2.91766663 1.7832498 2.9181999 1.77991634 1 P 0 ;0,1,2=20,3=0.000000
L 2.9181999 1.77991634 2.9198 1.77783346 1 P 0 ;0,1,2=20,3=0.000000
L 2.9198 1.77783346 2.92166673 1.77658297 1 P 0 ;0,1,2=20,3=0.000000
L 2.92166673 1.77658297 2.92833346 1.77658297 1 P 0 ;0,1,2=20,3=0.000000
L 2.92166673 1.77658297 2.91766663 1.7645 1 P 0 ;0,1,2=20,3=0.000000
L 2.90606683 1.78533337 2.90446673 1.78783287 1 P 0 ;0,1,2=20,3=0.000000
L 2.90446673 1.78783287 2.9026 1.78908337 1 P 0 ;0,1,2=20,3=0.000000
L 2.9026 1.78908337 2.90046663 1.7895 1 P 0 ;0,1,2=20,3=0.000000
L 2.90046663 1.7895 2.8978 1.78866683 1 P 0 ;0,1,2=20,3=0.000000
L 2.8978 1.78866683 2.89593327 1.78658317 1 P 0 ;0,1,2=20,3=0.000000
L 2.89593327 1.78658317 2.8954 1.78408366 1 P 0 ;0,1,2=20,3=0.000000
L 2.8954 1.78408366 2.89566663 1.78158268 1 P 0 ;0,1,2=20,3=0.000000
L 2.89566663 1.78158268 2.89673356 1.7794998 1 P 0 ;0,1,2=20,3=0.000000
L 2.89673356 1.7794998 2.90206673 1.77533327 1 P 0 ;0,1,2=20,3=0.000000
L 2.90206673 1.77533327 2.90446673 1.77241644 1 P 0 ;0,1,2=20,3=0.000000
L 2.90446673 1.77241644 2.90606683 1.76824911 1 P 0 ;0,1,2=20,3=0.000000
L 2.90606683 1.76824911 2.9066001 1.7645 1 P 0 ;0,1,2=20,3=0.000000
L 2.9066001 1.7645 2.8954 1.7645 1 P 0 ;0,1,2=20,3=0.000000
L 2.87953346 1.7645 2.8790003 1.76991624 1 P 0 ;0,1,2=20,3=0.000000
L 2.8790003 1.76991624 2.8782 1.77449931 1 P 0 ;0,1,2=20,3=0.000000
L 2.8782 1.77449931 2.87713356 1.77866663 1 P 0 ;0,1,2=20,3=0.000000
L 2.87713356 1.77866663 2.8758 1.7832498 1 P 0 ;0,1,2=20,3=0.000000
L 2.8758 1.7832498 2.87366663 1.7895 1 P 0 ;0,1,2=20,3=0.000000
L 2.87366663 1.7895 2.88433346 1.7895 1 P 0 ;0,1,2=20,3=0.000000
L 2.8570003 1.7895 2.85913366 1.78866683 1 P 0 ;0,1,2=20,3=0.000000
L 2.85913366 1.78866683 2.86073337 1.78658317 1 P 0 ;0,1,2=20,3=0.000000
L 2.86073337 1.78658317 2.8618002 1.78408366 1 P 0 ;0,1,2=20,3=0.000000
L 2.8618002 1.78408366 2.8626001 1.78074951 1 P 0 ;0,1,2=20,3=0.000000
L 2.8626001 1.78074951 2.86286673 1.77699961 1 P 0 ;0,1,2=20,3=0.000000
L 2.86286673 1.77699961 2.8626001 1.77324961 1 P 0 ;0,1,2=20,3=0.000000
L 2.8626001 1.77324961 2.8618002 1.76991624 1 P 0 ;0,1,2=20,3=0.000000
L 2.8618002 1.76991624 2.86073337 1.76741604 1 P 0 ;0,1,2=20,3=0.000000
L 2.86073337 1.76741604 2.85913366 1.76533307 1 P 0 ;0,1,2=20,3=0.000000
L 2.85913366 1.76533307 2.8570003 1.7645 1 P 0 ;0,1,2=20,3=0.000000
L 2.8570003 1.7645 2.85486693 1.76533307 1 P 0 ;0,1,2=20,3=0.000000
L 2.85486693 1.76533307 2.85326673 1.76741604 1 P 0 ;0,1,2=20,3=0.000000
L 2.85326673 1.76741604 2.8521999 1.76991624 1 P 0 ;0,1,2=20,3=0.000000
L 2.8521999 1.76991624 2.8514 1.77324961 1 P 0 ;0,1,2=20,3=0.000000
L 2.8514 1.77324961 2.85113337 1.77699961 1 P 0 ;0,1,2=20,3=0.000000
L 2.85113337 1.77699961 2.8514 1.78074951 1 P 0 ;0,1,2=20,3=0.000000
L 2.8514 1.78074951 2.8521999 1.78408366 1 P 0 ;0,1,2=20,3=0.000000
L 2.8521999 1.78408366 2.85326673 1.78658317 1 P 0 ;0,1,2=20,3=0.000000
L 2.85326673 1.78658317 2.85486693 1.78866683 1 P 0 ;0,1,2=20,3=0.000000
L 2.85486693 1.78866683 2.8570003 1.7895 1 P 0 ;0,1,2=20,3=0.000000
L 4.61878002 1.86193002 4.5424 1.86193002 1 P 0 
L 4.5424 1.86193002 4.5424 1.82493002 1 P 0 
L 4.5424 1.82493002 4.61878002 1.82493002 1 P 0 
L 4.61878002 1.82493002 4.61878002 1.86193002 1 P 0 
L 2.92833346 1.7275 2.92833346 1.7525 1 P 0 ;0,1,2=21,3=0.000000
L 2.92833346 1.7525 2.92166673 1.7525 1 P 0 ;0,1,2=21,3=0.000000
L 2.92166673 1.7525 2.91953337 1.75124941 1 P 0 ;0,1,2=21,3=0.000000
L 2.91953337 1.75124941 2.9181999 1.74958317 1 P 0 ;0,1,2=21,3=0.000000
L 2.9181999 1.74958317 2.91766663 1.7462498 1 P 0 ;0,1,2=21,3=0.000000
L 2.91766663 1.7462498 2.9181999 1.74291634 1 P 0 ;0,1,2=21,3=0.000000
L 2.9181999 1.74291634 2.9198 1.74083346 1 P 0 ;0,1,2=21,3=0.000000
L 2.9198 1.74083346 2.92166673 1.73958297 1 P 0 ;0,1,2=21,3=0.000000
L 2.92166673 1.73958297 2.92833346 1.73958297 1 P 0 ;0,1,2=21,3=0.000000
L 2.92166673 1.73958297 2.91766663 1.7275 1 P 0 ;0,1,2=21,3=0.000000
L 2.90686673 1.73124911 2.90526703 1.72916624 1 P 0 ;0,1,2=21,3=0.000000
L 2.90526703 1.72916624 2.9034003 1.72791654 1 P 0 ;0,1,2=21,3=0.000000
L 2.9034003 1.72791654 2.9010003 1.7275 1 P 0 ;0,1,2=21,3=0.000000
L 2.9010003 1.7275 2.8985998 1.72833307 1 P 0 ;0,1,2=21,3=0.000000
L 2.8985998 1.72833307 2.89673356 1.72999941 1 P 0 ;0,1,2=21,3=0.000000
L 2.89673356 1.72999941 2.8954 1.73291624 1 P 0 ;0,1,2=21,3=0.000000
L 2.8954 1.73291624 2.89513337 1.73624961 1 P 0 ;0,1,2=21,3=0.000000
L 2.89513337 1.73624961 2.89566663 1.73958297 1 P 0 ;0,1,2=21,3=0.000000
L 2.89566663 1.73958297 2.8970002 1.74166663 1 P 0 ;0,1,2=21,3=0.000000
L 2.8970002 1.74166663 2.89886693 1.74333297 1 P 0 ;0,1,2=21,3=0.000000
L 2.89886693 1.74333297 2.90073317 1.74374951 1 P 0 ;0,1,2=21,3=0.000000
L 2.90073317 1.74374951 2.9026 1.74333297 1 P 0 ;0,1,2=21,3=0.000000
L 2.9026 1.74333297 2.9049999 1.74166663 1 P 0 ;0,1,2=21,3=0.000000
L 2.9049999 1.74166663 2.9042001 1.7525 1 P 0 ;0,1,2=21,3=0.000000
L 2.9042001 1.7525 2.8970002 1.7525 1 P 0 ;0,1,2=21,3=0.000000
L 2.8790003 1.7525 2.88113366 1.75166683 1 P 0 ;0,1,2=21,3=0.000000
L 2.88113366 1.75166683 2.88273337 1.74958317 1 P 0 ;0,1,2=21,3=0.000000
L 2.88273337 1.74958317 2.8838002 1.74708366 1 P 0 ;0,1,2=21,3=0.000000
L 2.8838002 1.74708366 2.8846001 1.74374951 1 P 0 ;0,1,2=21,3=0.000000
L 2.8846001 1.74374951 2.88486673 1.73999961 1 P 0 ;0,1,2=21,3=0.000000
L 2.88486673 1.73999961 2.8846001 1.73624961 1 P 0 ;0,1,2=21,3=0.000000
L 2.8846001 1.73624961 2.8838002 1.73291624 1 P 0 ;0,1,2=21,3=0.000000
L 2.8838002 1.73291624 2.88273337 1.73041604 1 P 0 ;0,1,2=21,3=0.000000
L 2.88273337 1.73041604 2.88113366 1.72833307 1 P 0 ;0,1,2=21,3=0.000000
L 2.88113366 1.72833307 2.8790003 1.7275 1 P 0 ;0,1,2=21,3=0.000000
L 2.8790003 1.7275 2.87686693 1.72833307 1 P 0 ;0,1,2=21,3=0.000000
L 2.87686693 1.72833307 2.87526673 1.73041604 1 P 0 ;0,1,2=21,3=0.000000
L 2.87526673 1.73041604 2.8741999 1.73291624 1 P 0 ;0,1,2=21,3=0.000000
L 2.8741999 1.73291624 2.8734 1.73624961 1 P 0 ;0,1,2=21,3=0.000000
L 2.8734 1.73624961 2.87313337 1.73999961 1 P 0 ;0,1,2=21,3=0.000000
L 2.87313337 1.73999961 2.8734 1.74374951 1 P 0 ;0,1,2=21,3=0.000000
L 2.8734 1.74374951 2.8741999 1.74708366 1 P 0 ;0,1,2=21,3=0.000000
L 2.8741999 1.74708366 2.87526673 1.74958317 1 P 0 ;0,1,2=21,3=0.000000
L 2.87526673 1.74958317 2.87686693 1.75166683 1 P 0 ;0,1,2=21,3=0.000000
L 2.87686693 1.75166683 2.8790003 1.7525 1 P 0 ;0,1,2=21,3=0.000000
L 2.86206683 1.74833337 2.86046673 1.75083287 1 P 0 ;0,1,2=21,3=0.000000
L 2.86046673 1.75083287 2.8586 1.75208337 1 P 0 ;0,1,2=21,3=0.000000
L 2.8586 1.75208337 2.85646663 1.7525 1 P 0 ;0,1,2=21,3=0.000000
L 2.85646663 1.7525 2.8538 1.75166683 1 P 0 ;0,1,2=21,3=0.000000
L 2.8538 1.75166683 2.85193327 1.74958317 1 P 0 ;0,1,2=21,3=0.000000
L 2.85193327 1.74958317 2.8514 1.74708366 1 P 0 ;0,1,2=21,3=0.000000
L 2.8514 1.74708366 2.85166663 1.74458268 1 P 0 ;0,1,2=21,3=0.000000
L 2.85166663 1.74458268 2.85273356 1.7424998 1 P 0 ;0,1,2=21,3=0.000000
L 2.85273356 1.7424998 2.85806673 1.73833327 1 P 0 ;0,1,2=21,3=0.000000
L 2.85806673 1.73833327 2.86046673 1.73541644 1 P 0 ;0,1,2=21,3=0.000000
L 2.86046673 1.73541644 2.86206683 1.73124911 1 P 0 ;0,1,2=21,3=0.000000
L 2.86206683 1.73124911 2.8626001 1.7275 1 P 0 ;0,1,2=21,3=0.000000
L 2.8626001 1.7275 2.8514 1.7275 1 P 0 ;0,1,2=21,3=0.000000
L 4.54005 1.43123002 4.54005 1.46823002 1 P 0 
L 4.54005 1.46823002 4.46366998 1.46823002 1 P 0 
L 4.46366998 1.46823002 4.46366998 1.43123002 1 P 0 
L 4.46366998 1.43123002 4.54005 1.43123002 1 P 0 
L 4.54333346 1.4775 4.54333346 1.5025 1 P 0 ;0,1,2=22,3=0.000000
L 4.54333346 1.5025 4.53666673 1.5025 1 P 0 ;0,1,2=22,3=0.000000
L 4.53666673 1.5025 4.53453337 1.50124941 1 P 0 ;0,1,2=22,3=0.000000
L 4.53453337 1.50124941 4.5331999 1.49958317 1 P 0 ;0,1,2=22,3=0.000000
L 4.5331999 1.49958317 4.53266663 1.4962498 1 P 0 ;0,1,2=22,3=0.000000
L 4.53266663 1.4962498 4.5331999 1.49291634 1 P 0 ;0,1,2=22,3=0.000000
L 4.5331999 1.49291634 4.5348 1.49083346 1 P 0 ;0,1,2=22,3=0.000000
L 4.5348 1.49083346 4.53666673 1.48958297 1 P 0 ;0,1,2=22,3=0.000000
L 4.53666673 1.48958297 4.54333346 1.48958297 1 P 0 ;0,1,2=22,3=0.000000
L 4.53666673 1.48958297 4.53266663 1.4775 1 P 0 ;0,1,2=22,3=0.000000
L 4.52106683 1.49833337 4.51946673 1.50083287 1 P 0 ;0,1,2=22,3=0.000000
L 4.51946673 1.50083287 4.5176 1.50208337 1 P 0 ;0,1,2=22,3=0.000000
L 4.5176 1.50208337 4.51546663 1.5025 1 P 0 ;0,1,2=22,3=0.000000
L 4.51546663 1.5025 4.5128 1.50166683 1 P 0 ;0,1,2=22,3=0.000000
L 4.5128 1.50166683 4.51093327 1.49958317 1 P 0 ;0,1,2=22,3=0.000000
L 4.51093327 1.49958317 4.5104 1.49708366 1 P 0 ;0,1,2=22,3=0.000000
L 4.5104 1.49708366 4.51066663 1.49458268 1 P 0 ;0,1,2=22,3=0.000000
L 4.51066663 1.49458268 4.51173356 1.4924998 1 P 0 ;0,1,2=22,3=0.000000
L 4.51173356 1.4924998 4.51706673 1.48833327 1 P 0 ;0,1,2=22,3=0.000000
L 4.51706673 1.48833327 4.51946673 1.48541644 1 P 0 ;0,1,2=22,3=0.000000
L 4.51946673 1.48541644 4.52106683 1.48124911 1 P 0 ;0,1,2=22,3=0.000000
L 4.52106683 1.48124911 4.5216001 1.4775 1 P 0 ;0,1,2=22,3=0.000000
L 4.5216001 1.4775 4.5104 1.4775 1 P 0 ;0,1,2=22,3=0.000000
L 4.49453346 1.4775 4.4940003 1.48291624 1 P 0 ;0,1,2=22,3=0.000000
L 4.4940003 1.48291624 4.4932 1.48749931 1 P 0 ;0,1,2=22,3=0.000000
L 4.4932 1.48749931 4.49213356 1.49166663 1 P 0 ;0,1,2=22,3=0.000000
L 4.49213356 1.49166663 4.4908 1.4962498 1 P 0 ;0,1,2=22,3=0.000000
L 4.4908 1.4962498 4.48866663 1.5025 1 P 0 ;0,1,2=22,3=0.000000
L 4.48866663 1.5025 4.49933346 1.5025 1 P 0 ;0,1,2=22,3=0.000000
L 4.4720003 1.4775 4.47013356 1.47791654 1 P 0 ;0,1,2=22,3=0.000000
L 4.47013356 1.47791654 4.4680002 1.47916624 1 P 0 ;0,1,2=22,3=0.000000
L 4.4680002 1.47916624 4.46666663 1.48124911 1 P 0 ;0,1,2=22,3=0.000000
L 4.46666663 1.48124911 4.46613337 1.48416673 1 P 0 ;0,1,2=22,3=0.000000
L 4.46613337 1.48416673 4.46666663 1.48708278 1 P 0 ;0,1,2=22,3=0.000000
L 4.46666663 1.48708278 4.46826673 1.48958297 1 P 0 ;0,1,2=22,3=0.000000
L 4.46826673 1.48958297 4.47066673 1.49083346 1 P 0 ;0,1,2=22,3=0.000000
L 4.47066673 1.49083346 4.47333337 1.49083346 1 P 0 ;0,1,2=22,3=0.000000
L 4.47333337 1.49083346 4.47493346 1.49166663 1 P 0 ;0,1,2=22,3=0.000000
L 4.47493346 1.49166663 4.47626703 1.49374951 1 P 0 ;0,1,2=22,3=0.000000
L 4.47626703 1.49374951 4.4768002 1.49666634 1 P 0 ;0,1,2=22,3=0.000000
L 4.4768002 1.49666634 4.4759999 1.49958317 1 P 0 ;0,1,2=22,3=0.000000
L 4.4759999 1.49958317 4.47413366 1.50166683 1 P 0 ;0,1,2=22,3=0.000000
L 4.47413366 1.50166683 4.4720003 1.5025 1 P 0 ;0,1,2=22,3=0.000000
L 4.4720003 1.5025 4.46986693 1.50166683 1 P 0 ;0,1,2=22,3=0.000000
L 4.46986693 1.50166683 4.4680002 1.49958317 1 P 0 ;0,1,2=22,3=0.000000
L 4.4680002 1.49958317 4.4671999 1.49666634 1 P 0 ;0,1,2=22,3=0.000000
L 4.4671999 1.49666634 4.46773356 1.49374951 1 P 0 ;0,1,2=22,3=0.000000
L 4.46773356 1.49374951 4.46906663 1.49166663 1 P 0 ;0,1,2=22,3=0.000000
L 4.46906663 1.49166663 4.47066673 1.49083346 1 P 0 ;0,1,2=22,3=0.000000
L 4.47066673 1.49083346 4.47333337 1.49083346 1 P 0 ;0,1,2=22,3=0.000000
L 4.47333337 1.49083346 4.47573337 1.48958297 1 P 0 ;0,1,2=22,3=0.000000
L 4.47573337 1.48958297 4.47733346 1.48708278 1 P 0 ;0,1,2=22,3=0.000000
L 4.47733346 1.48708278 4.47786673 1.48416673 1 P 0 ;0,1,2=22,3=0.000000
L 4.47786673 1.48416673 4.47733346 1.48124911 1 P 0 ;0,1,2=22,3=0.000000
L 4.47733346 1.48124911 4.4759999 1.47916624 1 P 0 ;0,1,2=22,3=0.000000
L 4.4759999 1.47916624 4.47386654 1.47791654 1 P 0 ;0,1,2=22,3=0.000000
L 4.47386654 1.47791654 4.4720003 1.4775 1 P 0 ;0,1,2=22,3=0.000000
L 4.65815 1.31073996 4.58176998 1.31073996 1 P 0 
L 4.58176998 1.27373996 4.65815 1.27373996 1 P 0 
L 4.65815 1.27373996 4.65815 1.31073996 1 P 0 
L 4.58176998 1.31073996 4.58176998 1.27373996 1 P 0 
L 4.67833346 1.2325 4.67833346 1.2575 1 P 0 ;0,1,2=23,3=0.000000
L 4.67833346 1.2575 4.67166673 1.2575 1 P 0 ;0,1,2=23,3=0.000000
L 4.67166673 1.2575 4.66953337 1.25624941 1 P 0 ;0,1,2=23,3=0.000000
L 4.66953337 1.25624941 4.6681999 1.25458317 1 P 0 ;0,1,2=23,3=0.000000
L 4.6681999 1.25458317 4.66766663 1.2512498 1 P 0 ;0,1,2=23,3=0.000000
L 4.66766663 1.2512498 4.6681999 1.24791634 1 P 0 ;0,1,2=23,3=0.000000
L 4.6681999 1.24791634 4.6698 1.24583346 1 P 0 ;0,1,2=23,3=0.000000
L 4.6698 1.24583346 4.67166673 1.24458297 1 P 0 ;0,1,2=23,3=0.000000
L 4.67166673 1.24458297 4.67833346 1.24458297 1 P 0 ;0,1,2=23,3=0.000000
L 4.67166673 1.24458297 4.66766663 1.2325 1 P 0 ;0,1,2=23,3=0.000000
L 4.65606683 1.25333337 4.65446673 1.25583287 1 P 0 ;0,1,2=23,3=0.000000
L 4.65446673 1.25583287 4.6526 1.25708337 1 P 0 ;0,1,2=23,3=0.000000
L 4.6526 1.25708337 4.65046663 1.2575 1 P 0 ;0,1,2=23,3=0.000000
L 4.65046663 1.2575 4.6478 1.25666683 1 P 0 ;0,1,2=23,3=0.000000
L 4.6478 1.25666683 4.64593327 1.25458317 1 P 0 ;0,1,2=23,3=0.000000
L 4.64593327 1.25458317 4.6454 1.25208366 1 P 0 ;0,1,2=23,3=0.000000
L 4.6454 1.25208366 4.64566663 1.24958268 1 P 0 ;0,1,2=23,3=0.000000
L 4.64566663 1.24958268 4.64673356 1.2474998 1 P 0 ;0,1,2=23,3=0.000000
L 4.64673356 1.2474998 4.65206673 1.24333327 1 P 0 ;0,1,2=23,3=0.000000
L 4.65206673 1.24333327 4.65446673 1.24041644 1 P 0 ;0,1,2=23,3=0.000000
L 4.65446673 1.24041644 4.65606683 1.23624911 1 P 0 ;0,1,2=23,3=0.000000
L 4.65606683 1.23624911 4.6566001 1.2325 1 P 0 ;0,1,2=23,3=0.000000
L 4.6566001 1.2325 4.6454 1.2325 1 P 0 ;0,1,2=23,3=0.000000
L 4.62953346 1.2325 4.6290003 1.23791624 1 P 0 ;0,1,2=23,3=0.000000
L 4.6290003 1.23791624 4.6282 1.24249931 1 P 0 ;0,1,2=23,3=0.000000
L 4.6282 1.24249931 4.62713356 1.24666663 1 P 0 ;0,1,2=23,3=0.000000
L 4.62713356 1.24666663 4.6258 1.2512498 1 P 0 ;0,1,2=23,3=0.000000
L 4.6258 1.2512498 4.62366663 1.2575 1 P 0 ;0,1,2=23,3=0.000000
L 4.62366663 1.2575 4.63433346 1.2575 1 P 0 ;0,1,2=23,3=0.000000
L 4.61286673 1.23624911 4.61126703 1.23416624 1 P 0 ;0,1,2=23,3=0.000000
L 4.61126703 1.23416624 4.6094003 1.23291654 1 P 0 ;0,1,2=23,3=0.000000
L 4.6094003 1.23291654 4.6070003 1.2325 1 P 0 ;0,1,2=23,3=0.000000
L 4.6070003 1.2325 4.6045998 1.23333307 1 P 0 ;0,1,2=23,3=0.000000
L 4.6045998 1.23333307 4.60273356 1.23499941 1 P 0 ;0,1,2=23,3=0.000000
L 4.60273356 1.23499941 4.6014 1.23791624 1 P 0 ;0,1,2=23,3=0.000000
L 4.6014 1.23791624 4.60113337 1.24124961 1 P 0 ;0,1,2=23,3=0.000000
L 4.60113337 1.24124961 4.60166663 1.24458297 1 P 0 ;0,1,2=23,3=0.000000
L 4.60166663 1.24458297 4.6030002 1.24666663 1 P 0 ;0,1,2=23,3=0.000000
L 4.6030002 1.24666663 4.60486693 1.24833297 1 P 0 ;0,1,2=23,3=0.000000
L 4.60486693 1.24833297 4.60673317 1.24874951 1 P 0 ;0,1,2=23,3=0.000000
L 4.60673317 1.24874951 4.6086 1.24833297 1 P 0 ;0,1,2=23,3=0.000000
L 4.6086 1.24833297 4.6109999 1.24666663 1 P 0 ;0,1,2=23,3=0.000000
L 4.6109999 1.24666663 4.6102001 1.2575 1 P 0 ;0,1,2=23,3=0.000000
L 4.6102001 1.2575 4.6030002 1.2575 1 P 0 ;0,1,2=23,3=0.000000
L 4.50066998 1.86193002 4.46366998 1.86193002 1 P 0 
L 4.50066998 1.78555 4.50066998 1.86193002 1 P 0 
L 4.46366998 1.86193002 4.46366998 1.78555 1 P 0 
L 4.46366998 1.78555 4.50066998 1.78555 1 P 0 
L 2.7725 1.70666654 2.7975 1.70666654 1 P 0 ;0,1,2=24,3=90.000000
L 2.7975 1.70666654 2.7975 1.71333327 1 P 0 ;0,1,2=24,3=90.000000
L 2.7975 1.71333327 2.79624941 1.71546663 1 P 0 ;0,1,2=24,3=90.000000
L 2.79624941 1.71546663 2.79458317 1.7168001 1 P 0 ;0,1,2=24,3=90.000000
L 2.79458317 1.7168001 2.7912498 1.71733337 1 P 0 ;0,1,2=24,3=90.000000
L 2.7912498 1.71733337 2.78791634 1.7168001 1 P 0 ;0,1,2=24,3=90.000000
L 2.78791634 1.7168001 2.78583346 1.7152 1 P 0 ;0,1,2=24,3=90.000000
L 2.78583346 1.7152 2.78458297 1.71333327 1 P 0 ;0,1,2=24,3=90.000000
L 2.78458297 1.71333327 2.78458297 1.70666654 1 P 0 ;0,1,2=24,3=90.000000
L 2.78458297 1.71333327 2.7725 1.71733337 1 P 0 ;0,1,2=24,3=90.000000
L 2.7725 1.7372 2.7975 1.7372 1 P 0 ;0,1,2=24,3=90.000000
L 2.7975 1.7372 2.77958327 1.72733297 1 P 0 ;0,1,2=24,3=90.000000
L 2.77958327 1.72733297 2.77958327 1.74066693 1 P 0 ;0,1,2=24,3=90.000000
L 2.77749961 1.75013327 2.77458287 1.75173297 1 P 0 ;0,1,2=24,3=90.000000
L 2.77458287 1.75173297 2.77291654 1.75386634 1 P 0 ;0,1,2=24,3=90.000000
L 2.77291654 1.75386634 2.7725 1.75626683 1 P 0 ;0,1,2=24,3=90.000000
L 2.7725 1.75626683 2.77291654 1.7584002 1 P 0 ;0,1,2=24,3=90.000000
L 2.77291654 1.7584002 2.77499941 1.76053356 1 P 0 ;0,1,2=24,3=90.000000
L 2.77499941 1.76053356 2.77749961 1.76186663 1 P 0 ;0,1,2=24,3=90.000000
L 2.77749961 1.76186663 2.7799999 1.76213317 1 P 0 ;0,1,2=24,3=90.000000
L 2.7799999 1.76213317 2.78291594 1.7616 1 P 0 ;0,1,2=24,3=90.000000
L 2.78291594 1.7616 2.78499961 1.75973327 1 P 0 ;0,1,2=24,3=90.000000
L 2.78499961 1.75973327 2.78583346 1.75786644 1 P 0 ;0,1,2=24,3=90.000000
L 2.78583346 1.75786644 2.78583346 1.75546654 1 P 0 ;0,1,2=24,3=90.000000
L 2.78583346 1.75786644 2.78708327 1.75946663 1 P 0 ;0,1,2=24,3=90.000000
L 2.78708327 1.75946663 2.78916614 1.7608001 1 P 0 ;0,1,2=24,3=90.000000
L 2.78916614 1.7608001 2.79166634 1.76133337 1 P 0 ;0,1,2=24,3=90.000000
L 2.79166634 1.76133337 2.79416654 1.7608001 1 P 0 ;0,1,2=24,3=90.000000
L 2.79416654 1.7608001 2.79624941 1.75946663 1 P 0 ;0,1,2=24,3=90.000000
L 2.79624941 1.75946663 2.7975 1.75706663 1 P 0 ;0,1,2=24,3=90.000000
L 2.7975 1.75706663 2.79708337 1.75466663 1 P 0 ;0,1,2=24,3=90.000000
L 2.79708337 1.75466663 2.79541634 1.75226663 1 P 0 ;0,1,2=24,3=90.000000
L 2.7725 1.77746654 2.77791624 1.7779997 1 P 0 ;0,1,2=24,3=90.000000
L 2.77791624 1.7779997 2.78249931 1.7788 1 P 0 ;0,1,2=24,3=90.000000
L 2.78249931 1.7788 2.78666663 1.77986644 1 P 0 ;0,1,2=24,3=90.000000
L 2.78666663 1.77986644 2.7912498 1.7812 1 P 0 ;0,1,2=24,3=90.000000
L 2.7912498 1.7812 2.7975 1.78333337 1 P 0 ;0,1,2=24,3=90.000000
L 2.7975 1.78333337 2.7975 1.77266654 1 P 0 ;0,1,2=24,3=90.000000
L 4.4613 1.86193002 4.4243 1.86193002 1 P 0 
L 4.4613 1.78555 4.4613 1.86193002 1 P 0 
L 4.4243 1.86193002 4.4243 1.78555 1 P 0 
L 4.4243 1.78555 4.4613 1.78555 1 P 0 
L 2.73746004 1.7054065 2.76246004 1.7054065 1 P 0 ;0,1,2=25,3=90.000000
L 2.76246004 1.7054065 2.76246004 1.71207323 1 P 0 ;0,1,2=25,3=90.000000
L 2.76246004 1.71207323 2.76120945 1.71420659 1 P 0 ;0,1,2=25,3=90.000000
L 2.76120945 1.71420659 2.75954321 1.71554006 1 P 0 ;0,1,2=25,3=90.000000
L 2.75954321 1.71554006 2.75620984 1.71607333 1 P 0 ;0,1,2=25,3=90.000000
L 2.75620984 1.71607333 2.75287638 1.71554006 1 P 0 ;0,1,2=25,3=90.000000
L 2.75287638 1.71554006 2.7507935 1.71393996 1 P 0 ;0,1,2=25,3=90.000000
L 2.7507935 1.71393996 2.74954301 1.71207323 1 P 0 ;0,1,2=25,3=90.000000
L 2.74954301 1.71207323 2.74954301 1.7054065 1 P 0 ;0,1,2=25,3=90.000000
L 2.74954301 1.71207323 2.73746004 1.71607333 1 P 0 ;0,1,2=25,3=90.000000
L 2.73746004 1.73593996 2.76246004 1.73593996 1 P 0 ;0,1,2=25,3=90.000000
L 2.76246004 1.73593996 2.74454331 1.72607293 1 P 0 ;0,1,2=25,3=90.000000
L 2.74454331 1.72607293 2.74454331 1.73940689 1 P 0 ;0,1,2=25,3=90.000000
L 2.74245965 1.74887323 2.73954291 1.75047293 1 P 0 ;0,1,2=25,3=90.000000
L 2.73954291 1.75047293 2.73787657 1.7526063 1 P 0 ;0,1,2=25,3=90.000000
L 2.73787657 1.7526063 2.73746004 1.75500679 1 P 0 ;0,1,2=25,3=90.000000
L 2.73746004 1.75500679 2.73787657 1.75714016 1 P 0 ;0,1,2=25,3=90.000000
L 2.73787657 1.75714016 2.73995945 1.75927352 1 P 0 ;0,1,2=25,3=90.000000
L 2.73995945 1.75927352 2.74245965 1.76060659 1 P 0 ;0,1,2=25,3=90.000000
L 2.74245965 1.76060659 2.74495994 1.76087313 1 P 0 ;0,1,2=25,3=90.000000
L 2.74495994 1.76087313 2.74787598 1.76033996 1 P 0 ;0,1,2=25,3=90.000000
L 2.74787598 1.76033996 2.74995965 1.75847323 1 P 0 ;0,1,2=25,3=90.000000
L 2.74995965 1.75847323 2.7507935 1.7566064 1 P 0 ;0,1,2=25,3=90.000000
L 2.7507935 1.7566064 2.7507935 1.7542065 1 P 0 ;0,1,2=25,3=90.000000
L 2.7507935 1.7566064 2.75204331 1.75820659 1 P 0 ;0,1,2=25,3=90.000000
L 2.75204331 1.75820659 2.75412618 1.75954006 1 P 0 ;0,1,2=25,3=90.000000
L 2.75412618 1.75954006 2.75662638 1.76007333 1 P 0 ;0,1,2=25,3=90.000000
L 2.75662638 1.76007333 2.75912657 1.75954006 1 P 0 ;0,1,2=25,3=90.000000
L 2.75912657 1.75954006 2.76120945 1.75820659 1 P 0 ;0,1,2=25,3=90.000000
L 2.76120945 1.75820659 2.76246004 1.75580659 1 P 0 ;0,1,2=25,3=90.000000
L 2.76246004 1.75580659 2.76204341 1.75340659 1 P 0 ;0,1,2=25,3=90.000000
L 2.76204341 1.75340659 2.76037638 1.75100659 1 P 0 ;0,1,2=25,3=90.000000
L 2.74787598 1.77167313 2.7507935 1.77353986 1 P 0 ;0,1,2=25,3=90.000000
L 2.7507935 1.77353986 2.75245984 1.77513996 1 P 0 ;0,1,2=25,3=90.000000
L 2.75245984 1.77513996 2.75329301 1.77727333 1 P 0 ;0,1,2=25,3=90.000000
L 2.75329301 1.77727333 2.75245984 1.77914016 1 P 0 ;0,1,2=25,3=90.000000
L 2.75245984 1.77914016 2.7507935 1.78047323 1 P 0 ;0,1,2=25,3=90.000000
L 2.7507935 1.78047323 2.74829331 1.78154006 1 P 0 ;0,1,2=25,3=90.000000
L 2.74829331 1.78154006 2.74537648 1.78180669 1 P 0 ;0,1,2=25,3=90.000000
L 2.74537648 1.78180669 2.74287628 1.78154006 1 P 0 ;0,1,2=25,3=90.000000
L 2.74287628 1.78154006 2.74037608 1.78047323 1 P 0 ;0,1,2=25,3=90.000000
L 2.74037608 1.78047323 2.73829311 1.77887303 1 P 0 ;0,1,2=25,3=90.000000
L 2.73829311 1.77887303 2.73746004 1.77700679 1 P 0 ;0,1,2=25,3=90.000000
L 2.73746004 1.77700679 2.73829311 1.77487343 1 P 0 ;0,1,2=25,3=90.000000
L 2.73829311 1.77487343 2.74079262 1.77300659 1 P 0 ;0,1,2=25,3=90.000000
L 2.74079262 1.77300659 2.74454331 1.77193976 1 P 0 ;0,1,2=25,3=90.000000
L 2.74454331 1.77193976 2.74870984 1.77167313 1 P 0 ;0,1,2=25,3=90.000000
L 2.74870984 1.77167313 2.75412618 1.7722063 1 P 0 ;0,1,2=25,3=90.000000
L 2.75412618 1.7722063 2.7570437 1.77300659 1 P 0 ;0,1,2=25,3=90.000000
L 2.7570437 1.77300659 2.75995974 1.77433967 1 P 0 ;0,1,2=25,3=90.000000
L 2.75995974 1.77433967 2.76204341 1.7762065 1 P 0 ;0,1,2=25,3=90.000000
L 2.76204341 1.7762065 2.76246004 1.77807323 1 P 0 ;0,1,2=25,3=90.000000
L 2.76246004 1.77807323 2.76162687 1.77993996 1 P 0 ;0,1,2=25,3=90.000000
L 2.76162687 1.77993996 2.75954321 1.78127352 1 P 0 ;0,1,2=25,3=90.000000
L 3.99123002 1.50996998 4.02823002 1.50996998 1 P 0 
L 3.99123002 1.58635 3.99123002 1.50996998 1 P 0 
L 4.02823002 1.58635 3.99123002 1.58635 1 P 0 
L 4.02823002 1.50996998 4.02823002 1.58635 1 P 0 
L 2.36711634 1.47106663 2.36836683 1.46946644 1 P 0 ;0,1,2=26,3=90.000000
L 2.36836683 1.46946644 2.3692 1.4676002 1 P 0 ;0,1,2=26,3=90.000000
L 2.3692 1.4676002 2.3692 1.46546683 1 P 0 ;0,1,2=26,3=90.000000
L 2.3692 1.46546683 2.36794941 1.46306634 1 P 0 ;0,1,2=26,3=90.000000
L 2.36794941 1.46306634 2.36586654 1.4612001 1 P 0 ;0,1,2=26,3=90.000000
L 2.36586654 1.4612001 2.36336634 1.45986654 1 P 0 ;0,1,2=26,3=90.000000
L 2.36336634 1.45986654 2.3591998 1.45879961 1 P 0 ;0,1,2=26,3=90.000000
L 2.3591998 1.45879961 2.3554498 1.45853297 1 P 0 ;0,1,2=26,3=90.000000
L 2.3554498 1.45853297 2.3516999 1.45906673 1 P 0 ;0,1,2=26,3=90.000000
L 2.3516999 1.45906673 2.34919961 1.45986654 1 P 0 ;0,1,2=26,3=90.000000
L 2.34919961 1.45986654 2.34669941 1.46146663 1 P 0 ;0,1,2=26,3=90.000000
L 2.34669941 1.46146663 2.34503307 1.46333346 1 P 0 ;0,1,2=26,3=90.000000
L 2.34503307 1.46333346 2.3442 1.4651997 1 P 0 ;0,1,2=26,3=90.000000
L 2.3442 1.4651997 2.3442 1.46706644 1 P 0 ;0,1,2=26,3=90.000000
L 2.3442 1.46706644 2.34503307 1.46893327 1 P 0 ;0,1,2=26,3=90.000000
L 2.34503307 1.46893327 2.34628287 1.47053337 1 P 0 ;0,1,2=26,3=90.000000
L 2.34628287 1.47053337 2.34794911 1.47186693 1 P 0 ;0,1,2=26,3=90.000000
L 2.36503337 1.48213317 2.36753287 1.48373327 1 P 0 ;0,1,2=26,3=90.000000
L 2.36753287 1.48373327 2.36878337 1.4856 1 P 0 ;0,1,2=26,3=90.000000
L 2.36878337 1.4856 2.3692 1.48773337 1 P 0 ;0,1,2=26,3=90.000000
L 2.3692 1.48773337 2.36836683 1.4904 1 P 0 ;0,1,2=26,3=90.000000
L 2.36836683 1.4904 2.36628317 1.49226673 1 P 0 ;0,1,2=26,3=90.000000
L 2.36628317 1.49226673 2.36378366 1.4928 1 P 0 ;0,1,2=26,3=90.000000
L 2.36378366 1.4928 2.36128268 1.49253337 1 P 0 ;0,1,2=26,3=90.000000
L 2.36128268 1.49253337 2.3591998 1.49146644 1 P 0 ;0,1,2=26,3=90.000000
L 2.3591998 1.49146644 2.35503327 1.48613327 1 P 0 ;0,1,2=26,3=90.000000
L 2.35503327 1.48613327 2.35211644 1.48373327 1 P 0 ;0,1,2=26,3=90.000000
L 2.35211644 1.48373327 2.34794911 1.48213317 1 P 0 ;0,1,2=26,3=90.000000
L 2.34794911 1.48213317 2.3442 1.4815999 1 P 0 ;0,1,2=26,3=90.000000
L 2.3442 1.4815999 2.3442 1.4928 1 P 0 ;0,1,2=26,3=90.000000
L 2.3442 1.5091997 2.3692 1.5091997 1 P 0 ;0,1,2=26,3=90.000000
L 2.3692 1.5091997 2.3642003 1.5059999 1 P 0 ;0,1,2=26,3=90.000000
L 2.3442 1.5059999 2.3442 1.51239951 1 P 0 ;0,1,2=26,3=90.000000
L 2.3442 1.5311997 2.34461654 1.53306644 1 P 0 ;0,1,2=26,3=90.000000
L 2.34461654 1.53306644 2.34586624 1.5351998 1 P 0 ;0,1,2=26,3=90.000000
L 2.34586624 1.5351998 2.34794911 1.53653337 1 P 0 ;0,1,2=26,3=90.000000
L 2.34794911 1.53653337 2.35086673 1.53706663 1 P 0 ;0,1,2=26,3=90.000000
L 2.35086673 1.53706663 2.35378278 1.53653337 1 P 0 ;0,1,2=26,3=90.000000
L 2.35378278 1.53653337 2.35628297 1.53493327 1 P 0 ;0,1,2=26,3=90.000000
L 2.35628297 1.53493327 2.35753346 1.53253327 1 P 0 ;0,1,2=26,3=90.000000
L 2.35753346 1.53253327 2.35753346 1.52986663 1 P 0 ;0,1,2=26,3=90.000000
L 2.35753346 1.52986663 2.35836663 1.52826654 1 P 0 ;0,1,2=26,3=90.000000
L 2.35836663 1.52826654 2.36044951 1.52693297 1 P 0 ;0,1,2=26,3=90.000000
L 2.36044951 1.52693297 2.36336634 1.5263998 1 P 0 ;0,1,2=26,3=90.000000
L 2.36336634 1.5263998 2.36628317 1.5272001 1 P 0 ;0,1,2=26,3=90.000000
L 2.36628317 1.5272001 2.36836683 1.52906634 1 P 0 ;0,1,2=26,3=90.000000
L 2.36836683 1.52906634 2.3692 1.5311997 1 P 0 ;0,1,2=26,3=90.000000
L 2.3692 1.5311997 2.36836683 1.53333307 1 P 0 ;0,1,2=26,3=90.000000
L 2.36836683 1.53333307 2.36628317 1.5351998 1 P 0 ;0,1,2=26,3=90.000000
L 2.36628317 1.5351998 2.36336634 1.5360001 1 P 0 ;0,1,2=26,3=90.000000
L 2.36336634 1.5360001 2.36044951 1.53546644 1 P 0 ;0,1,2=26,3=90.000000
L 2.36044951 1.53546644 2.35836663 1.53413337 1 P 0 ;0,1,2=26,3=90.000000
L 2.35836663 1.53413337 2.35753346 1.53253327 1 P 0 ;0,1,2=26,3=90.000000
L 2.35753346 1.53253327 2.35753346 1.52986663 1 P 0 ;0,1,2=26,3=90.000000
L 2.35753346 1.52986663 2.35628297 1.52746663 1 P 0 ;0,1,2=26,3=90.000000
L 2.35628297 1.52746663 2.35378278 1.52586654 1 P 0 ;0,1,2=26,3=90.000000
L 2.35378278 1.52586654 2.35086673 1.52533327 1 P 0 ;0,1,2=26,3=90.000000
L 2.35086673 1.52533327 2.34794911 1.52586654 1 P 0 ;0,1,2=26,3=90.000000
L 2.34794911 1.52586654 2.34586624 1.5272001 1 P 0 ;0,1,2=26,3=90.000000
L 2.34586624 1.5272001 2.34461654 1.52933346 1 P 0 ;0,1,2=26,3=90.000000
L 2.34461654 1.52933346 2.3442 1.5311997 1 P 0 ;0,1,2=26,3=90.000000
L 4.06996998 1.58633996 4.06996998 1.54933996 1 P 0 
L 4.14635 1.58633996 4.06996998 1.58633996 1 P 0 
L 4.14635 1.54933996 4.14635 1.58633996 1 P 0 
L 4.06996998 1.54933996 4.14635 1.54933996 1 P 0 
L 2.50533337 1.53021634 2.50693356 1.53146683 1 P 0 ;0,1,2=27,3=0.000000
L 2.50693356 1.53146683 2.5087998 1.5323 1 P 0 ;0,1,2=27,3=0.000000
L 2.5087998 1.5323 2.51093317 1.5323 1 P 0 ;0,1,2=27,3=0.000000
L 2.51093317 1.5323 2.51333366 1.53104941 1 P 0 ;0,1,2=27,3=0.000000
L 2.51333366 1.53104941 2.5151999 1.52896654 1 P 0 ;0,1,2=27,3=0.000000
L 2.5151999 1.52896654 2.51653346 1.52646634 1 P 0 ;0,1,2=27,3=0.000000
L 2.51653346 1.52646634 2.51760039 1.5222998 1 P 0 ;0,1,2=27,3=0.000000
L 2.51760039 1.5222998 2.51786703 1.5185498 1 P 0 ;0,1,2=27,3=0.000000
L 2.51786703 1.5185498 2.51733327 1.5147999 1 P 0 ;0,1,2=27,3=0.000000
L 2.51733327 1.5147999 2.51653346 1.51229961 1 P 0 ;0,1,2=27,3=0.000000
L 2.51653346 1.51229961 2.51493337 1.50979941 1 P 0 ;0,1,2=27,3=0.000000
L 2.51493337 1.50979941 2.51306654 1.50813307 1 P 0 ;0,1,2=27,3=0.000000
L 2.51306654 1.50813307 2.5112003 1.5073 1 P 0 ;0,1,2=27,3=0.000000
L 2.5112003 1.5073 2.50933356 1.5073 1 P 0 ;0,1,2=27,3=0.000000
L 2.50933356 1.5073 2.50746673 1.50813307 1 P 0 ;0,1,2=27,3=0.000000
L 2.50746673 1.50813307 2.50586663 1.50938287 1 P 0 ;0,1,2=27,3=0.000000
L 2.50586663 1.50938287 2.50453307 1.51104911 1 P 0 ;0,1,2=27,3=0.000000
L 2.4892003 1.5073 2.4892003 1.5323 1 P 0 ;0,1,2=27,3=0.000000
L 2.4892003 1.5323 2.4924001 1.5273003 1 P 0 ;0,1,2=27,3=0.000000
L 2.4924001 1.5073 2.48600049 1.5073 1 P 0 ;0,1,2=27,3=0.000000
L 2.4672003 1.5073 2.4672003 1.5323 1 P 0 ;0,1,2=27,3=0.000000
L 2.4672003 1.5323 2.4704001 1.5273003 1 P 0 ;0,1,2=27,3=0.000000
L 2.4704001 1.5073 2.46400049 1.5073 1 P 0 ;0,1,2=27,3=0.000000
L 2.4452003 1.5073 2.44333356 1.50771654 1 P 0 ;0,1,2=27,3=0.000000
L 2.44333356 1.50771654 2.4412002 1.50896624 1 P 0 ;0,1,2=27,3=0.000000
L 2.4412002 1.50896624 2.43986663 1.51104911 1 P 0 ;0,1,2=27,3=0.000000
L 2.43986663 1.51104911 2.43933337 1.51396673 1 P 0 ;0,1,2=27,3=0.000000
L 2.43933337 1.51396673 2.43986663 1.51688278 1 P 0 ;0,1,2=27,3=0.000000
L 2.43986663 1.51688278 2.44146673 1.51938297 1 P 0 ;0,1,2=27,3=0.000000
L 2.44146673 1.51938297 2.44386673 1.52063346 1 P 0 ;0,1,2=27,3=0.000000
L 2.44386673 1.52063346 2.44653337 1.52063346 1 P 0 ;0,1,2=27,3=0.000000
L 2.44653337 1.52063346 2.44813346 1.52146663 1 P 0 ;0,1,2=27,3=0.000000
L 2.44813346 1.52146663 2.44946703 1.52354951 1 P 0 ;0,1,2=27,3=0.000000
L 2.44946703 1.52354951 2.4500002 1.52646634 1 P 0 ;0,1,2=27,3=0.000000
L 2.4500002 1.52646634 2.4491999 1.52938317 1 P 0 ;0,1,2=27,3=0.000000
L 2.4491999 1.52938317 2.44733366 1.53146683 1 P 0 ;0,1,2=27,3=0.000000
L 2.44733366 1.53146683 2.4452003 1.5323 1 P 0 ;0,1,2=27,3=0.000000
L 2.4452003 1.5323 2.44306693 1.53146683 1 P 0 ;0,1,2=27,3=0.000000
L 2.44306693 1.53146683 2.4412002 1.52938317 1 P 0 ;0,1,2=27,3=0.000000
L 2.4412002 1.52938317 2.4403999 1.52646634 1 P 0 ;0,1,2=27,3=0.000000
L 2.4403999 1.52646634 2.44093356 1.52354951 1 P 0 ;0,1,2=27,3=0.000000
L 2.44093356 1.52354951 2.44226663 1.52146663 1 P 0 ;0,1,2=27,3=0.000000
L 2.44226663 1.52146663 2.44386673 1.52063346 1 P 0 ;0,1,2=27,3=0.000000
L 2.44386673 1.52063346 2.44653337 1.52063346 1 P 0 ;0,1,2=27,3=0.000000
L 2.44653337 1.52063346 2.44893337 1.51938297 1 P 0 ;0,1,2=27,3=0.000000
L 2.44893337 1.51938297 2.45053346 1.51688278 1 P 0 ;0,1,2=27,3=0.000000
L 2.45053346 1.51688278 2.45106673 1.51396673 1 P 0 ;0,1,2=27,3=0.000000
L 2.45106673 1.51396673 2.45053346 1.51104911 1 P 0 ;0,1,2=27,3=0.000000
L 2.45053346 1.51104911 2.4491999 1.50896624 1 P 0 ;0,1,2=27,3=0.000000
L 2.4491999 1.50896624 2.44706654 1.50771654 1 P 0 ;0,1,2=27,3=0.000000
L 2.44706654 1.50771654 2.4452003 1.5073 1 P 0 ;0,1,2=27,3=0.000000
L 4.0306 1.58871004 4.0676 1.58871004 1 P 0 
L 4.0306 1.66508996 4.0306 1.58871004 1 P 0 
L 4.0676 1.58871004 4.0676 1.66508996 1 P 0 
L 4.0676 1.66508996 4.0306 1.66508996 1 P 0 
L 2.42651634 1.55976663 2.42776683 1.55816644 1 P 0 ;0,1,2=28,3=90.000000
L 2.42776683 1.55816644 2.4286 1.5563002 1 P 0 ;0,1,2=28,3=90.000000
L 2.4286 1.5563002 2.4286 1.55416683 1 P 0 ;0,1,2=28,3=90.000000
L 2.4286 1.55416683 2.42734941 1.55176634 1 P 0 ;0,1,2=28,3=90.000000
L 2.42734941 1.55176634 2.42526654 1.5499001 1 P 0 ;0,1,2=28,3=90.000000
L 2.42526654 1.5499001 2.42276634 1.54856654 1 P 0 ;0,1,2=28,3=90.000000
L 2.42276634 1.54856654 2.4185998 1.54749961 1 P 0 ;0,1,2=28,3=90.000000
L 2.4185998 1.54749961 2.4148498 1.54723297 1 P 0 ;0,1,2=28,3=90.000000
L 2.4148498 1.54723297 2.4110999 1.54776673 1 P 0 ;0,1,2=28,3=90.000000
L 2.4110999 1.54776673 2.40859961 1.54856654 1 P 0 ;0,1,2=28,3=90.000000
L 2.40859961 1.54856654 2.40609941 1.55016663 1 P 0 ;0,1,2=28,3=90.000000
L 2.40609941 1.55016663 2.40443307 1.55203346 1 P 0 ;0,1,2=28,3=90.000000
L 2.40443307 1.55203346 2.4036 1.5538997 1 P 0 ;0,1,2=28,3=90.000000
L 2.4036 1.5538997 2.4036 1.55576644 1 P 0 ;0,1,2=28,3=90.000000
L 2.4036 1.55576644 2.40443307 1.55763327 1 P 0 ;0,1,2=28,3=90.000000
L 2.40443307 1.55763327 2.40568287 1.55923337 1 P 0 ;0,1,2=28,3=90.000000
L 2.40568287 1.55923337 2.40734911 1.56056693 1 P 0 ;0,1,2=28,3=90.000000
L 2.4036 1.5758997 2.4286 1.5758997 1 P 0 ;0,1,2=28,3=90.000000
L 2.4286 1.5758997 2.4236003 1.5726999 1 P 0 ;0,1,2=28,3=90.000000
L 2.4036 1.5726999 2.4036 1.57909951 1 P 0 ;0,1,2=28,3=90.000000
L 2.4286 1.5978997 2.42776683 1.59576634 1 P 0 ;0,1,2=28,3=90.000000
L 2.42776683 1.59576634 2.42568317 1.59416663 1 P 0 ;0,1,2=28,3=90.000000
L 2.42568317 1.59416663 2.42318366 1.5930998 1 P 0 ;0,1,2=28,3=90.000000
L 2.42318366 1.5930998 2.41984951 1.5922999 1 P 0 ;0,1,2=28,3=90.000000
L 2.41984951 1.5922999 2.41609961 1.59203327 1 P 0 ;0,1,2=28,3=90.000000
L 2.41609961 1.59203327 2.41234961 1.5922999 1 P 0 ;0,1,2=28,3=90.000000
L 2.41234961 1.5922999 2.40901624 1.5930998 1 P 0 ;0,1,2=28,3=90.000000
L 2.40901624 1.5930998 2.40651604 1.59416663 1 P 0 ;0,1,2=28,3=90.000000
L 2.40651604 1.59416663 2.40443307 1.59576634 1 P 0 ;0,1,2=28,3=90.000000
L 2.40443307 1.59576634 2.4036 1.5978997 1 P 0 ;0,1,2=28,3=90.000000
L 2.4036 1.5978997 2.40443307 1.60003307 1 P 0 ;0,1,2=28,3=90.000000
L 2.40443307 1.60003307 2.40651604 1.60163327 1 P 0 ;0,1,2=28,3=90.000000
L 2.40651604 1.60163327 2.40901624 1.6027001 1 P 0 ;0,1,2=28,3=90.000000
L 2.40901624 1.6027001 2.41234961 1.6035 1 P 0 ;0,1,2=28,3=90.000000
L 2.41234961 1.6035 2.41609961 1.60376663 1 P 0 ;0,1,2=28,3=90.000000
L 2.41609961 1.60376663 2.41984951 1.6035 1 P 0 ;0,1,2=28,3=90.000000
L 2.41984951 1.6035 2.42318366 1.6027001 1 P 0 ;0,1,2=28,3=90.000000
L 2.42318366 1.6027001 2.42568317 1.60163327 1 P 0 ;0,1,2=28,3=90.000000
L 2.42568317 1.60163327 2.42776683 1.60003307 1 P 0 ;0,1,2=28,3=90.000000
L 2.42776683 1.60003307 2.4286 1.5978997 1 P 0 ;0,1,2=28,3=90.000000
L 2.40734911 1.61403327 2.40526624 1.61563297 1 P 0 ;0,1,2=28,3=90.000000
L 2.40526624 1.61563297 2.40401654 1.6174997 1 P 0 ;0,1,2=28,3=90.000000
L 2.40401654 1.6174997 2.4036 1.6198997 1 P 0 ;0,1,2=28,3=90.000000
L 2.4036 1.6198997 2.40443307 1.6223002 1 P 0 ;0,1,2=28,3=90.000000
L 2.40443307 1.6223002 2.40609941 1.62416644 1 P 0 ;0,1,2=28,3=90.000000
L 2.40609941 1.62416644 2.40901624 1.6255 1 P 0 ;0,1,2=28,3=90.000000
L 2.40901624 1.6255 2.41234961 1.62576663 1 P 0 ;0,1,2=28,3=90.000000
L 2.41234961 1.62576663 2.41568297 1.62523337 1 P 0 ;0,1,2=28,3=90.000000
L 2.41568297 1.62523337 2.41776663 1.6238998 1 P 0 ;0,1,2=28,3=90.000000
L 2.41776663 1.6238998 2.41943297 1.62203307 1 P 0 ;0,1,2=28,3=90.000000
L 2.41943297 1.62203307 2.41984951 1.62016683 1 P 0 ;0,1,2=28,3=90.000000
L 2.41984951 1.62016683 2.41943297 1.6183 1 P 0 ;0,1,2=28,3=90.000000
L 2.41943297 1.6183 2.41776663 1.6159001 1 P 0 ;0,1,2=28,3=90.000000
L 2.41776663 1.6159001 2.4286 1.6166999 1 P 0 ;0,1,2=28,3=90.000000
L 2.4286 1.6166999 2.4286 1.6238998 1 P 0 ;0,1,2=28,3=90.000000
L 4.06996998 1.62571004 4.06996998 1.58871004 1 P 0 
L 4.14635 1.58871004 4.14635 1.62571004 1 P 0 
L 4.06996998 1.58871004 4.14635 1.58871004 1 P 0 
L 4.14635 1.62571004 4.06996998 1.62571004 1 P 0 
L 2.50533337 1.56961634 2.50693356 1.57086683 1 P 0 ;0,1,2=29,3=0.000000
L 2.50693356 1.57086683 2.5087998 1.5717 1 P 0 ;0,1,2=29,3=0.000000
L 2.5087998 1.5717 2.51093317 1.5717 1 P 0 ;0,1,2=29,3=0.000000
L 2.51093317 1.5717 2.51333366 1.57044941 1 P 0 ;0,1,2=29,3=0.000000
L 2.51333366 1.57044941 2.5151999 1.56836654 1 P 0 ;0,1,2=29,3=0.000000
L 2.5151999 1.56836654 2.51653346 1.56586634 1 P 0 ;0,1,2=29,3=0.000000
L 2.51653346 1.56586634 2.51760039 1.5616998 1 P 0 ;0,1,2=29,3=0.000000
L 2.51760039 1.5616998 2.51786703 1.5579498 1 P 0 ;0,1,2=29,3=0.000000
L 2.51786703 1.5579498 2.51733327 1.5541999 1 P 0 ;0,1,2=29,3=0.000000
L 2.51733327 1.5541999 2.51653346 1.55169961 1 P 0 ;0,1,2=29,3=0.000000
L 2.51653346 1.55169961 2.51493337 1.54919941 1 P 0 ;0,1,2=29,3=0.000000
L 2.51493337 1.54919941 2.51306654 1.54753307 1 P 0 ;0,1,2=29,3=0.000000
L 2.51306654 1.54753307 2.5112003 1.5467 1 P 0 ;0,1,2=29,3=0.000000
L 2.5112003 1.5467 2.50933356 1.5467 1 P 0 ;0,1,2=29,3=0.000000
L 2.50933356 1.5467 2.50746673 1.54753307 1 P 0 ;0,1,2=29,3=0.000000
L 2.50746673 1.54753307 2.50586663 1.54878287 1 P 0 ;0,1,2=29,3=0.000000
L 2.50586663 1.54878287 2.50453307 1.55044911 1 P 0 ;0,1,2=29,3=0.000000
L 2.4892003 1.5467 2.4892003 1.5717 1 P 0 ;0,1,2=29,3=0.000000
L 2.4892003 1.5717 2.4924001 1.5667003 1 P 0 ;0,1,2=29,3=0.000000
L 2.4924001 1.5467 2.48600049 1.5467 1 P 0 ;0,1,2=29,3=0.000000
L 2.4672003 1.5467 2.4672003 1.5717 1 P 0 ;0,1,2=29,3=0.000000
L 2.4672003 1.5717 2.4704001 1.5667003 1 P 0 ;0,1,2=29,3=0.000000
L 2.4704001 1.5467 2.46400049 1.5467 1 P 0 ;0,1,2=29,3=0.000000
L 2.4452003 1.5467 2.4452003 1.5717 1 P 0 ;0,1,2=29,3=0.000000
L 2.4452003 1.5717 2.4484001 1.5667003 1 P 0 ;0,1,2=29,3=0.000000
L 2.4484001 1.5467 2.44200049 1.5467 1 P 0 ;0,1,2=29,3=0.000000
L 3.99123002 1.43121998 4.02823002 1.43121998 1 P 0 
L 3.99123002 1.5076 3.99123002 1.43121998 1 P 0 
L 4.02823002 1.5076 3.99123002 1.5076 1 P 0 
L 4.02823002 1.43121998 4.02823002 1.5076 1 P 0 
L 2.36711634 1.38226663 2.36836683 1.38066644 1 P 0 ;0,1,2=30,3=90.000000
L 2.36836683 1.38066644 2.3692 1.3788002 1 P 0 ;0,1,2=30,3=90.000000
L 2.3692 1.3788002 2.3692 1.37666683 1 P 0 ;0,1,2=30,3=90.000000
L 2.3692 1.37666683 2.36794941 1.37426634 1 P 0 ;0,1,2=30,3=90.000000
L 2.36794941 1.37426634 2.36586654 1.3724001 1 P 0 ;0,1,2=30,3=90.000000
L 2.36586654 1.3724001 2.36336634 1.37106654 1 P 0 ;0,1,2=30,3=90.000000
L 2.36336634 1.37106654 2.3591998 1.36999961 1 P 0 ;0,1,2=30,3=90.000000
L 2.3591998 1.36999961 2.3554498 1.36973297 1 P 0 ;0,1,2=30,3=90.000000
L 2.3554498 1.36973297 2.3516999 1.37026673 1 P 0 ;0,1,2=30,3=90.000000
L 2.3516999 1.37026673 2.34919961 1.37106654 1 P 0 ;0,1,2=30,3=90.000000
L 2.34919961 1.37106654 2.34669941 1.37266663 1 P 0 ;0,1,2=30,3=90.000000
L 2.34669941 1.37266663 2.34503307 1.37453346 1 P 0 ;0,1,2=30,3=90.000000
L 2.34503307 1.37453346 2.3442 1.3763997 1 P 0 ;0,1,2=30,3=90.000000
L 2.3442 1.3763997 2.3442 1.37826644 1 P 0 ;0,1,2=30,3=90.000000
L 2.3442 1.37826644 2.34503307 1.38013327 1 P 0 ;0,1,2=30,3=90.000000
L 2.34503307 1.38013327 2.34628287 1.38173337 1 P 0 ;0,1,2=30,3=90.000000
L 2.34628287 1.38173337 2.34794911 1.38306693 1 P 0 ;0,1,2=30,3=90.000000
L 2.3442 1.3983997 2.3692 1.3983997 1 P 0 ;0,1,2=30,3=90.000000
L 2.3692 1.3983997 2.3642003 1.3951999 1 P 0 ;0,1,2=30,3=90.000000
L 2.3442 1.3951999 2.3442 1.40159951 1 P 0 ;0,1,2=30,3=90.000000
L 2.36503337 1.41533317 2.36753287 1.41693327 1 P 0 ;0,1,2=30,3=90.000000
L 2.36753287 1.41693327 2.36878337 1.4188 1 P 0 ;0,1,2=30,3=90.000000
L 2.36878337 1.4188 2.3692 1.42093337 1 P 0 ;0,1,2=30,3=90.000000
L 2.3692 1.42093337 2.36836683 1.4236 1 P 0 ;0,1,2=30,3=90.000000
L 2.36836683 1.4236 2.36628317 1.42546673 1 P 0 ;0,1,2=30,3=90.000000
L 2.36628317 1.42546673 2.36378366 1.426 1 P 0 ;0,1,2=30,3=90.000000
L 2.36378366 1.426 2.36128268 1.42573337 1 P 0 ;0,1,2=30,3=90.000000
L 2.36128268 1.42573337 2.3591998 1.42466644 1 P 0 ;0,1,2=30,3=90.000000
L 2.3591998 1.42466644 2.35503327 1.41933327 1 P 0 ;0,1,2=30,3=90.000000
L 2.35503327 1.41933327 2.35211644 1.41693327 1 P 0 ;0,1,2=30,3=90.000000
L 2.35211644 1.41693327 2.34794911 1.41533317 1 P 0 ;0,1,2=30,3=90.000000
L 2.34794911 1.41533317 2.3442 1.4147999 1 P 0 ;0,1,2=30,3=90.000000
L 2.3442 1.4147999 2.3442 1.426 1 P 0 ;0,1,2=30,3=90.000000
L 2.3442 1.4456 2.3692 1.4456 1 P 0 ;0,1,2=30,3=90.000000
L 2.3692 1.4456 2.35128327 1.43573297 1 P 0 ;0,1,2=30,3=90.000000
L 2.35128327 1.43573297 2.35128327 1.44906693 1 P 0 ;0,1,2=30,3=90.000000
L 4.0306 1.35248002 4.0676 1.35248002 1 P 0 
L 4.0306 1.42886004 4.0306 1.35248002 1 P 0 
L 4.0676 1.42886004 4.0306 1.42886004 1 P 0 
L 4.0676 1.35248002 4.0676 1.42886004 1 P 0 
L 2.34541634 1.29786663 2.34666683 1.29626644 1 P 0 ;0,1,2=31,3=90.000000
L 2.34666683 1.29626644 2.3475 1.2944002 1 P 0 ;0,1,2=31,3=90.000000
L 2.3475 1.2944002 2.3475 1.29226683 1 P 0 ;0,1,2=31,3=90.000000
L 2.3475 1.29226683 2.34624941 1.28986634 1 P 0 ;0,1,2=31,3=90.000000
L 2.34624941 1.28986634 2.34416654 1.2880001 1 P 0 ;0,1,2=31,3=90.000000
L 2.34416654 1.2880001 2.34166634 1.28666654 1 P 0 ;0,1,2=31,3=90.000000
L 2.34166634 1.28666654 2.3374998 1.28559961 1 P 0 ;0,1,2=31,3=90.000000
L 2.3374998 1.28559961 2.3337498 1.28533297 1 P 0 ;0,1,2=31,3=90.000000
L 2.3337498 1.28533297 2.3299999 1.28586673 1 P 0 ;0,1,2=31,3=90.000000
L 2.3299999 1.28586673 2.32749961 1.28666654 1 P 0 ;0,1,2=31,3=90.000000
L 2.32749961 1.28666654 2.32499941 1.28826663 1 P 0 ;0,1,2=31,3=90.000000
L 2.32499941 1.28826663 2.32333307 1.29013346 1 P 0 ;0,1,2=31,3=90.000000
L 2.32333307 1.29013346 2.3225 1.2919997 1 P 0 ;0,1,2=31,3=90.000000
L 2.3225 1.2919997 2.3225 1.29386644 1 P 0 ;0,1,2=31,3=90.000000
L 2.3225 1.29386644 2.32333307 1.29573327 1 P 0 ;0,1,2=31,3=90.000000
L 2.32333307 1.29573327 2.32458287 1.29733337 1 P 0 ;0,1,2=31,3=90.000000
L 2.32458287 1.29733337 2.32624911 1.29866693 1 P 0 ;0,1,2=31,3=90.000000
L 2.34333337 1.30893317 2.34583287 1.31053327 1 P 0 ;0,1,2=31,3=90.000000
L 2.34583287 1.31053327 2.34708337 1.3124 1 P 0 ;0,1,2=31,3=90.000000
L 2.34708337 1.3124 2.3475 1.31453337 1 P 0 ;0,1,2=31,3=90.000000
L 2.3475 1.31453337 2.34666683 1.3172 1 P 0 ;0,1,2=31,3=90.000000
L 2.34666683 1.3172 2.34458317 1.31906673 1 P 0 ;0,1,2=31,3=90.000000
L 2.34458317 1.31906673 2.34208366 1.3196 1 P 0 ;0,1,2=31,3=90.000000
L 2.34208366 1.3196 2.33958268 1.31933337 1 P 0 ;0,1,2=31,3=90.000000
L 2.33958268 1.31933337 2.3374998 1.31826644 1 P 0 ;0,1,2=31,3=90.000000
L 2.3374998 1.31826644 2.33333327 1.31293327 1 P 0 ;0,1,2=31,3=90.000000
L 2.33333327 1.31293327 2.33041644 1.31053327 1 P 0 ;0,1,2=31,3=90.000000
L 2.33041644 1.31053327 2.32624911 1.30893317 1 P 0 ;0,1,2=31,3=90.000000
L 2.32624911 1.30893317 2.3225 1.3083999 1 P 0 ;0,1,2=31,3=90.000000
L 2.3225 1.3083999 2.3225 1.3196 1 P 0 ;0,1,2=31,3=90.000000
L 2.3225 1.3359997 2.3475 1.3359997 1 P 0 ;0,1,2=31,3=90.000000
L 2.3475 1.3359997 2.3425003 1.3327999 1 P 0 ;0,1,2=31,3=90.000000
L 2.3225 1.3327999 2.3225 1.33919951 1 P 0 ;0,1,2=31,3=90.000000
L 2.32749961 1.35213327 2.32458287 1.35373297 1 P 0 ;0,1,2=31,3=90.000000
L 2.32458287 1.35373297 2.32291654 1.35586634 1 P 0 ;0,1,2=31,3=90.000000
L 2.32291654 1.35586634 2.3225 1.35826683 1 P 0 ;0,1,2=31,3=90.000000
L 2.3225 1.35826683 2.32291654 1.3604002 1 P 0 ;0,1,2=31,3=90.000000
L 2.32291654 1.3604002 2.32499941 1.36253356 1 P 0 ;0,1,2=31,3=90.000000
L 2.32499941 1.36253356 2.32749961 1.36386663 1 P 0 ;0,1,2=31,3=90.000000
L 2.32749961 1.36386663 2.3299999 1.36413317 1 P 0 ;0,1,2=31,3=90.000000
L 2.3299999 1.36413317 2.33291594 1.3636 1 P 0 ;0,1,2=31,3=90.000000
L 2.33291594 1.3636 2.33499961 1.36173327 1 P 0 ;0,1,2=31,3=90.000000
L 2.33499961 1.36173327 2.33583346 1.35986644 1 P 0 ;0,1,2=31,3=90.000000
L 2.33583346 1.35986644 2.33583346 1.35746654 1 P 0 ;0,1,2=31,3=90.000000
L 2.33583346 1.35986644 2.33708327 1.36146663 1 P 0 ;0,1,2=31,3=90.000000
L 2.33708327 1.36146663 2.33916614 1.3628001 1 P 0 ;0,1,2=31,3=90.000000
L 2.33916614 1.3628001 2.34166634 1.36333337 1 P 0 ;0,1,2=31,3=90.000000
L 2.34166634 1.36333337 2.34416654 1.3628001 1 P 0 ;0,1,2=31,3=90.000000
L 2.34416654 1.3628001 2.34624941 1.36146663 1 P 0 ;0,1,2=31,3=90.000000
L 2.34624941 1.36146663 2.3475 1.35906663 1 P 0 ;0,1,2=31,3=90.000000
L 2.3475 1.35906663 2.34708337 1.35666663 1 P 0 ;0,1,2=31,3=90.000000
L 2.34708337 1.35666663 2.34541634 1.35426663 1 P 0 ;0,1,2=31,3=90.000000
L 3.91248002 1.86193002 3.91248002 1.82493002 1 P 0 
L 3.98886004 1.86193002 3.91248002 1.86193002 1 P 0 
L 3.98886004 1.82493002 3.98886004 1.86193002 1 P 0 
L 3.91248002 1.82493002 3.98886004 1.82493002 1 P 0 
L 3.88713337 1.85041634 3.88873356 1.85166683 1 P 0 ;0,1,2=32,3=0.000000
L 3.88873356 1.85166683 3.8905998 1.8525 1 P 0 ;0,1,2=32,3=0.000000
L 3.8905998 1.8525 3.89273317 1.8525 1 P 0 ;0,1,2=32,3=0.000000
L 3.89273317 1.8525 3.89513366 1.85124941 1 P 0 ;0,1,2=32,3=0.000000
L 3.89513366 1.85124941 3.8969999 1.84916654 1 P 0 ;0,1,2=32,3=0.000000
L 3.8969999 1.84916654 3.89833346 1.84666634 1 P 0 ;0,1,2=32,3=0.000000
L 3.89833346 1.84666634 3.89940039 1.8424998 1 P 0 ;0,1,2=32,3=0.000000
L 3.89940039 1.8424998 3.89966703 1.8387498 1 P 0 ;0,1,2=32,3=0.000000
L 3.89966703 1.8387498 3.89913327 1.8349999 1 P 0 ;0,1,2=32,3=0.000000
L 3.89913327 1.8349999 3.89833346 1.83249961 1 P 0 ;0,1,2=32,3=0.000000
L 3.89833346 1.83249961 3.89673337 1.82999941 1 P 0 ;0,1,2=32,3=0.000000
L 3.89673337 1.82999941 3.89486654 1.82833307 1 P 0 ;0,1,2=32,3=0.000000
L 3.89486654 1.82833307 3.8930003 1.8275 1 P 0 ;0,1,2=32,3=0.000000
L 3.8930003 1.8275 3.89113356 1.8275 1 P 0 ;0,1,2=32,3=0.000000
L 3.89113356 1.8275 3.88926673 1.82833307 1 P 0 ;0,1,2=32,3=0.000000
L 3.88926673 1.82833307 3.88766663 1.82958287 1 P 0 ;0,1,2=32,3=0.000000
L 3.88766663 1.82958287 3.88633307 1.83124911 1 P 0 ;0,1,2=32,3=0.000000
L 3.87606683 1.84833337 3.87446673 1.85083287 1 P 0 ;0,1,2=32,3=0.000000
L 3.87446673 1.85083287 3.8726 1.85208337 1 P 0 ;0,1,2=32,3=0.000000
L 3.8726 1.85208337 3.87046663 1.8525 1 P 0 ;0,1,2=32,3=0.000000
L 3.87046663 1.8525 3.8678 1.85166683 1 P 0 ;0,1,2=32,3=0.000000
L 3.8678 1.85166683 3.86593327 1.84958317 1 P 0 ;0,1,2=32,3=0.000000
L 3.86593327 1.84958317 3.8654 1.84708366 1 P 0 ;0,1,2=32,3=0.000000
L 3.8654 1.84708366 3.86566663 1.84458268 1 P 0 ;0,1,2=32,3=0.000000
L 3.86566663 1.84458268 3.86673356 1.8424998 1 P 0 ;0,1,2=32,3=0.000000
L 3.86673356 1.8424998 3.87206673 1.83833327 1 P 0 ;0,1,2=32,3=0.000000
L 3.87206673 1.83833327 3.87446673 1.83541644 1 P 0 ;0,1,2=32,3=0.000000
L 3.87446673 1.83541644 3.87606683 1.83124911 1 P 0 ;0,1,2=32,3=0.000000
L 3.87606683 1.83124911 3.8766001 1.8275 1 P 0 ;0,1,2=32,3=0.000000
L 3.8766001 1.8275 3.8654 1.8275 1 P 0 ;0,1,2=32,3=0.000000
L 3.8490003 1.8525 3.85113366 1.85166683 1 P 0 ;0,1,2=32,3=0.000000
L 3.85113366 1.85166683 3.85273337 1.84958317 1 P 0 ;0,1,2=32,3=0.000000
L 3.85273337 1.84958317 3.8538002 1.84708366 1 P 0 ;0,1,2=32,3=0.000000
L 3.8538002 1.84708366 3.8546001 1.84374951 1 P 0 ;0,1,2=32,3=0.000000
L 3.8546001 1.84374951 3.85486673 1.83999961 1 P 0 ;0,1,2=32,3=0.000000
L 3.85486673 1.83999961 3.8546001 1.83624961 1 P 0 ;0,1,2=32,3=0.000000
L 3.8546001 1.83624961 3.8538002 1.83291624 1 P 0 ;0,1,2=32,3=0.000000
L 3.8538002 1.83291624 3.85273337 1.83041604 1 P 0 ;0,1,2=32,3=0.000000
L 3.85273337 1.83041604 3.85113366 1.82833307 1 P 0 ;0,1,2=32,3=0.000000
L 3.85113366 1.82833307 3.8490003 1.8275 1 P 0 ;0,1,2=32,3=0.000000
L 3.8490003 1.8275 3.84686693 1.82833307 1 P 0 ;0,1,2=32,3=0.000000
L 3.84686693 1.82833307 3.84526673 1.83041604 1 P 0 ;0,1,2=32,3=0.000000
L 3.84526673 1.83041604 3.8441999 1.83291624 1 P 0 ;0,1,2=32,3=0.000000
L 3.8441999 1.83291624 3.8434 1.83624961 1 P 0 ;0,1,2=32,3=0.000000
L 3.8434 1.83624961 3.84313337 1.83999961 1 P 0 ;0,1,2=32,3=0.000000
L 3.84313337 1.83999961 3.8434 1.84374951 1 P 0 ;0,1,2=32,3=0.000000
L 3.8434 1.84374951 3.8441999 1.84708366 1 P 0 ;0,1,2=32,3=0.000000
L 3.8441999 1.84708366 3.84526673 1.84958317 1 P 0 ;0,1,2=32,3=0.000000
L 3.84526673 1.84958317 3.84686693 1.85166683 1 P 0 ;0,1,2=32,3=0.000000
L 3.84686693 1.85166683 3.8490003 1.8525 1 P 0 ;0,1,2=32,3=0.000000
L 3.83286673 1.83249961 3.83126703 1.82958287 1 P 0 ;0,1,2=32,3=0.000000
L 3.83126703 1.82958287 3.82913366 1.82791654 1 P 0 ;0,1,2=32,3=0.000000
L 3.82913366 1.82791654 3.82673317 1.8275 1 P 0 ;0,1,2=32,3=0.000000
L 3.82673317 1.8275 3.8245998 1.82791654 1 P 0 ;0,1,2=32,3=0.000000
L 3.8245998 1.82791654 3.82246644 1.82999941 1 P 0 ;0,1,2=32,3=0.000000
L 3.82246644 1.82999941 3.82113337 1.83249961 1 P 0 ;0,1,2=32,3=0.000000
L 3.82113337 1.83249961 3.82086683 1.8349999 1 P 0 ;0,1,2=32,3=0.000000
L 3.82086683 1.8349999 3.8214 1.83791594 1 P 0 ;0,1,2=32,3=0.000000
L 3.8214 1.83791594 3.82326673 1.83999961 1 P 0 ;0,1,2=32,3=0.000000
L 3.82326673 1.83999961 3.82513356 1.84083346 1 P 0 ;0,1,2=32,3=0.000000
L 3.82513356 1.84083346 3.82753346 1.84083346 1 P 0 ;0,1,2=32,3=0.000000
L 3.82513356 1.84083346 3.82353337 1.84208327 1 P 0 ;0,1,2=32,3=0.000000
L 3.82353337 1.84208327 3.8221999 1.84416614 1 P 0 ;0,1,2=32,3=0.000000
L 3.8221999 1.84416614 3.82166663 1.84666634 1 P 0 ;0,1,2=32,3=0.000000
L 3.82166663 1.84666634 3.8221999 1.84916654 1 P 0 ;0,1,2=32,3=0.000000
L 3.8221999 1.84916654 3.82353337 1.85124941 1 P 0 ;0,1,2=32,3=0.000000
L 3.82353337 1.85124941 3.82593337 1.8525 1 P 0 ;0,1,2=32,3=0.000000
L 3.82593337 1.8525 3.82833337 1.85208337 1 P 0 ;0,1,2=32,3=0.000000
L 3.82833337 1.85208337 3.83073337 1.85041634 1 P 0 ;0,1,2=32,3=0.000000
L 4.14633996 1.70445 4.10933996 1.70445 1 P 0 
L 4.14633996 1.62806998 4.14633996 1.70445 1 P 0 
L 4.10933996 1.62806998 4.14633996 1.62806998 1 P 0 
L 4.10933996 1.70445 4.10933996 1.62806998 1 P 0 
L 2.50521634 1.59416663 2.50646683 1.59256644 1 P 0 ;0,1,2=33,3=90.000000
L 2.50646683 1.59256644 2.5073 1.5907002 1 P 0 ;0,1,2=33,3=90.000000
L 2.5073 1.5907002 2.5073 1.58856683 1 P 0 ;0,1,2=33,3=90.000000
L 2.5073 1.58856683 2.50604941 1.58616634 1 P 0 ;0,1,2=33,3=90.000000
L 2.50604941 1.58616634 2.50396654 1.5843001 1 P 0 ;0,1,2=33,3=90.000000
L 2.50396654 1.5843001 2.50146634 1.58296654 1 P 0 ;0,1,2=33,3=90.000000
L 2.50146634 1.58296654 2.4972998 1.58189961 1 P 0 ;0,1,2=33,3=90.000000
L 2.4972998 1.58189961 2.4935498 1.58163297 1 P 0 ;0,1,2=33,3=90.000000
L 2.4935498 1.58163297 2.4897999 1.58216673 1 P 0 ;0,1,2=33,3=90.000000
L 2.4897999 1.58216673 2.48729961 1.58296654 1 P 0 ;0,1,2=33,3=90.000000
L 2.48729961 1.58296654 2.48479941 1.58456663 1 P 0 ;0,1,2=33,3=90.000000
L 2.48479941 1.58456663 2.48313307 1.58643346 1 P 0 ;0,1,2=33,3=90.000000
L 2.48313307 1.58643346 2.4823 1.5882997 1 P 0 ;0,1,2=33,3=90.000000
L 2.4823 1.5882997 2.4823 1.59016644 1 P 0 ;0,1,2=33,3=90.000000
L 2.4823 1.59016644 2.48313307 1.59203327 1 P 0 ;0,1,2=33,3=90.000000
L 2.48313307 1.59203327 2.48438287 1.59363337 1 P 0 ;0,1,2=33,3=90.000000
L 2.48438287 1.59363337 2.48604911 1.59496693 1 P 0 ;0,1,2=33,3=90.000000
L 2.50313337 1.60523317 2.50563287 1.60683327 1 P 0 ;0,1,2=33,3=90.000000
L 2.50563287 1.60683327 2.50688337 1.6087 1 P 0 ;0,1,2=33,3=90.000000
L 2.50688337 1.6087 2.5073 1.61083337 1 P 0 ;0,1,2=33,3=90.000000
L 2.5073 1.61083337 2.50646683 1.6135 1 P 0 ;0,1,2=33,3=90.000000
L 2.50646683 1.6135 2.50438317 1.61536673 1 P 0 ;0,1,2=33,3=90.000000
L 2.50438317 1.61536673 2.50188366 1.6159 1 P 0 ;0,1,2=33,3=90.000000
L 2.50188366 1.6159 2.49938268 1.61563337 1 P 0 ;0,1,2=33,3=90.000000
L 2.49938268 1.61563337 2.4972998 1.61456644 1 P 0 ;0,1,2=33,3=90.000000
L 2.4972998 1.61456644 2.49313327 1.60923327 1 P 0 ;0,1,2=33,3=90.000000
L 2.49313327 1.60923327 2.49021644 1.60683327 1 P 0 ;0,1,2=33,3=90.000000
L 2.49021644 1.60683327 2.48604911 1.60523317 1 P 0 ;0,1,2=33,3=90.000000
L 2.48604911 1.60523317 2.4823 1.6046999 1 P 0 ;0,1,2=33,3=90.000000
L 2.4823 1.6046999 2.4823 1.6159 1 P 0 ;0,1,2=33,3=90.000000
L 2.50313337 1.62723317 2.50563287 1.62883327 1 P 0 ;0,1,2=33,3=90.000000
L 2.50563287 1.62883327 2.50688337 1.6307 1 P 0 ;0,1,2=33,3=90.000000
L 2.50688337 1.6307 2.5073 1.63283337 1 P 0 ;0,1,2=33,3=90.000000
L 2.5073 1.63283337 2.50646683 1.6355 1 P 0 ;0,1,2=33,3=90.000000
L 2.50646683 1.6355 2.50438317 1.63736673 1 P 0 ;0,1,2=33,3=90.000000
L 2.50438317 1.63736673 2.50188366 1.6379 1 P 0 ;0,1,2=33,3=90.000000
L 2.50188366 1.6379 2.49938268 1.63763337 1 P 0 ;0,1,2=33,3=90.000000
L 2.49938268 1.63763337 2.4972998 1.63656644 1 P 0 ;0,1,2=33,3=90.000000
L 2.4972998 1.63656644 2.49313327 1.63123327 1 P 0 ;0,1,2=33,3=90.000000
L 2.49313327 1.63123327 2.49021644 1.62883327 1 P 0 ;0,1,2=33,3=90.000000
L 2.49021644 1.62883327 2.48604911 1.62723317 1 P 0 ;0,1,2=33,3=90.000000
L 2.48604911 1.62723317 2.4823 1.6266999 1 P 0 ;0,1,2=33,3=90.000000
L 2.4823 1.6266999 2.4823 1.6379 1 P 0 ;0,1,2=33,3=90.000000
L 2.50313337 1.64923317 2.50563287 1.65083327 1 P 0 ;0,1,2=33,3=90.000000
L 2.50563287 1.65083327 2.50688337 1.6527 1 P 0 ;0,1,2=33,3=90.000000
L 2.50688337 1.6527 2.5073 1.65483337 1 P 0 ;0,1,2=33,3=90.000000
L 2.5073 1.65483337 2.50646683 1.6575 1 P 0 ;0,1,2=33,3=90.000000
L 2.50646683 1.6575 2.50438317 1.65936673 1 P 0 ;0,1,2=33,3=90.000000
L 2.50438317 1.65936673 2.50188366 1.6599 1 P 0 ;0,1,2=33,3=90.000000
L 2.50188366 1.6599 2.49938268 1.65963337 1 P 0 ;0,1,2=33,3=90.000000
L 2.49938268 1.65963337 2.4972998 1.65856644 1 P 0 ;0,1,2=33,3=90.000000
L 2.4972998 1.65856644 2.49313327 1.65323327 1 P 0 ;0,1,2=33,3=90.000000
L 2.49313327 1.65323327 2.49021644 1.65083327 1 P 0 ;0,1,2=33,3=90.000000
L 2.49021644 1.65083327 2.48604911 1.64923317 1 P 0 ;0,1,2=33,3=90.000000
L 2.48604911 1.64923317 2.4823 1.6486999 1 P 0 ;0,1,2=33,3=90.000000
L 2.4823 1.6486999 2.4823 1.6599 1 P 0 ;0,1,2=33,3=90.000000
L 3.99121998 1.78556004 4.0676 1.78556004 1 P 0 
L 3.99121998 1.82256004 3.99121998 1.78556004 1 P 0 
L 4.0676 1.82256004 3.99121998 1.82256004 1 P 0 
L 4.0676 1.78556004 4.0676 1.82256004 1 P 0 
L 4.05713337 1.77041634 4.05873356 1.77166683 1 P 0 ;0,1,2=34,3=0.000000
L 4.05873356 1.77166683 4.0605998 1.7725 1 P 0 ;0,1,2=34,3=0.000000
L 4.0605998 1.7725 4.06273317 1.7725 1 P 0 ;0,1,2=34,3=0.000000
L 4.06273317 1.7725 4.06513366 1.77124941 1 P 0 ;0,1,2=34,3=0.000000
L 4.06513366 1.77124941 4.0669999 1.76916654 1 P 0 ;0,1,2=34,3=0.000000
L 4.0669999 1.76916654 4.06833346 1.76666634 1 P 0 ;0,1,2=34,3=0.000000
L 4.06833346 1.76666634 4.06940039 1.7624998 1 P 0 ;0,1,2=34,3=0.000000
L 4.06940039 1.7624998 4.06966703 1.7587498 1 P 0 ;0,1,2=34,3=0.000000
L 4.06966703 1.7587498 4.06913327 1.7549999 1 P 0 ;0,1,2=34,3=0.000000
L 4.06913327 1.7549999 4.06833346 1.75249961 1 P 0 ;0,1,2=34,3=0.000000
L 4.06833346 1.75249961 4.06673337 1.74999941 1 P 0 ;0,1,2=34,3=0.000000
L 4.06673337 1.74999941 4.06486654 1.74833307 1 P 0 ;0,1,2=34,3=0.000000
L 4.06486654 1.74833307 4.0630003 1.7475 1 P 0 ;0,1,2=34,3=0.000000
L 4.0630003 1.7475 4.06113356 1.7475 1 P 0 ;0,1,2=34,3=0.000000
L 4.06113356 1.7475 4.05926673 1.74833307 1 P 0 ;0,1,2=34,3=0.000000
L 4.05926673 1.74833307 4.05766663 1.74958287 1 P 0 ;0,1,2=34,3=0.000000
L 4.05766663 1.74958287 4.05633307 1.75124911 1 P 0 ;0,1,2=34,3=0.000000
L 4.0410003 1.7475 4.0410003 1.7725 1 P 0 ;0,1,2=34,3=0.000000
L 4.0410003 1.7725 4.0442001 1.7675003 1 P 0 ;0,1,2=34,3=0.000000
L 4.0442001 1.7475 4.03780049 1.7475 1 P 0 ;0,1,2=34,3=0.000000
L 4.0190003 1.7725 4.02113366 1.77166683 1 P 0 ;0,1,2=34,3=0.000000
L 4.02113366 1.77166683 4.02273337 1.76958317 1 P 0 ;0,1,2=34,3=0.000000
L 4.02273337 1.76958317 4.0238002 1.76708366 1 P 0 ;0,1,2=34,3=0.000000
L 4.0238002 1.76708366 4.0246001 1.76374951 1 P 0 ;0,1,2=34,3=0.000000
L 4.0246001 1.76374951 4.02486673 1.75999961 1 P 0 ;0,1,2=34,3=0.000000
L 4.02486673 1.75999961 4.0246001 1.75624961 1 P 0 ;0,1,2=34,3=0.000000
L 4.0246001 1.75624961 4.0238002 1.75291624 1 P 0 ;0,1,2=34,3=0.000000
L 4.0238002 1.75291624 4.02273337 1.75041604 1 P 0 ;0,1,2=34,3=0.000000
L 4.02273337 1.75041604 4.02113366 1.74833307 1 P 0 ;0,1,2=34,3=0.000000
L 4.02113366 1.74833307 4.0190003 1.7475 1 P 0 ;0,1,2=34,3=0.000000
L 4.0190003 1.7475 4.01686693 1.74833307 1 P 0 ;0,1,2=34,3=0.000000
L 4.01686693 1.74833307 4.01526673 1.75041604 1 P 0 ;0,1,2=34,3=0.000000
L 4.01526673 1.75041604 4.0141999 1.75291624 1 P 0 ;0,1,2=34,3=0.000000
L 4.0141999 1.75291624 4.0134 1.75624961 1 P 0 ;0,1,2=34,3=0.000000
L 4.0134 1.75624961 4.01313337 1.75999961 1 P 0 ;0,1,2=34,3=0.000000
L 4.01313337 1.75999961 4.0134 1.76374951 1 P 0 ;0,1,2=34,3=0.000000
L 4.0134 1.76374951 4.0141999 1.76708366 1 P 0 ;0,1,2=34,3=0.000000
L 4.0141999 1.76708366 4.01526673 1.76958317 1 P 0 ;0,1,2=34,3=0.000000
L 4.01526673 1.76958317 4.01686693 1.77166683 1 P 0 ;0,1,2=34,3=0.000000
L 4.01686693 1.77166683 4.0190003 1.7725 1 P 0 ;0,1,2=34,3=0.000000
L 4.00206683 1.75791594 4.0002001 1.76083346 1 P 0 ;0,1,2=34,3=0.000000
L 4.0002001 1.76083346 3.9986 1.7624998 1 P 0 ;0,1,2=34,3=0.000000
L 3.9986 1.7624998 3.99646663 1.76333297 1 P 0 ;0,1,2=34,3=0.000000
L 3.99646663 1.76333297 3.9945998 1.7624998 1 P 0 ;0,1,2=34,3=0.000000
L 3.9945998 1.7624998 3.99326673 1.76083346 1 P 0 ;0,1,2=34,3=0.000000
L 3.99326673 1.76083346 3.9921999 1.75833327 1 P 0 ;0,1,2=34,3=0.000000
L 3.9921999 1.75833327 3.99193327 1.75541644 1 P 0 ;0,1,2=34,3=0.000000
L 3.99193327 1.75541644 3.9921999 1.75291624 1 P 0 ;0,1,2=34,3=0.000000
L 3.9921999 1.75291624 3.99326673 1.75041604 1 P 0 ;0,1,2=34,3=0.000000
L 3.99326673 1.75041604 3.99486693 1.74833307 1 P 0 ;0,1,2=34,3=0.000000
L 3.99486693 1.74833307 3.99673317 1.7475 1 P 0 ;0,1,2=34,3=0.000000
L 3.99673317 1.7475 3.99886654 1.74833307 1 P 0 ;0,1,2=34,3=0.000000
L 3.99886654 1.74833307 4.00073337 1.75083258 1 P 0 ;0,1,2=34,3=0.000000
L 4.00073337 1.75083258 4.0018002 1.75458327 1 P 0 ;0,1,2=34,3=0.000000
L 4.0018002 1.75458327 4.00206683 1.7587498 1 P 0 ;0,1,2=34,3=0.000000
L 4.00206683 1.7587498 4.00153366 1.76416614 1 P 0 ;0,1,2=34,3=0.000000
L 4.00153366 1.76416614 4.00073337 1.76708366 1 P 0 ;0,1,2=34,3=0.000000
L 4.00073337 1.76708366 3.9994003 1.7699997 1 P 0 ;0,1,2=34,3=0.000000
L 3.9994003 1.7699997 3.99753346 1.77208337 1 P 0 ;0,1,2=34,3=0.000000
L 3.99753346 1.77208337 3.99566673 1.7725 1 P 0 ;0,1,2=34,3=0.000000
L 3.99566673 1.7725 3.9938 1.77166683 1 P 0 ;0,1,2=34,3=0.000000
L 3.9938 1.77166683 3.99246644 1.76958317 1 P 0 ;0,1,2=34,3=0.000000
L 3.91248002 1.66508002 3.91248002 1.62808002 1 P 0 
L 3.98886004 1.66508002 3.91248002 1.66508002 1 P 0 
L 3.98886004 1.62808002 3.98886004 1.66508002 1 P 0 
L 3.91248002 1.62808002 3.98886004 1.62808002 1 P 0 
L 2.30713337 1.61041634 2.30873356 1.61166683 1 P 0 ;0,1,2=35,3=0.000000
L 2.30873356 1.61166683 2.3105998 1.6125 1 P 0 ;0,1,2=35,3=0.000000
L 2.3105998 1.6125 2.31273317 1.6125 1 P 0 ;0,1,2=35,3=0.000000
L 2.31273317 1.6125 2.31513366 1.61124941 1 P 0 ;0,1,2=35,3=0.000000
L 2.31513366 1.61124941 2.3169999 1.60916654 1 P 0 ;0,1,2=35,3=0.000000
L 2.3169999 1.60916654 2.31833346 1.60666634 1 P 0 ;0,1,2=35,3=0.000000
L 2.31833346 1.60666634 2.31940039 1.6024998 1 P 0 ;0,1,2=35,3=0.000000
L 2.31940039 1.6024998 2.31966703 1.5987498 1 P 0 ;0,1,2=35,3=0.000000
L 2.31966703 1.5987498 2.31913327 1.5949999 1 P 0 ;0,1,2=35,3=0.000000
L 2.31913327 1.5949999 2.31833346 1.59249961 1 P 0 ;0,1,2=35,3=0.000000
L 2.31833346 1.59249961 2.31673337 1.58999941 1 P 0 ;0,1,2=35,3=0.000000
L 2.31673337 1.58999941 2.31486654 1.58833307 1 P 0 ;0,1,2=35,3=0.000000
L 2.31486654 1.58833307 2.3130003 1.5875 1 P 0 ;0,1,2=35,3=0.000000
L 2.3130003 1.5875 2.31113356 1.5875 1 P 0 ;0,1,2=35,3=0.000000
L 2.31113356 1.5875 2.30926673 1.58833307 1 P 0 ;0,1,2=35,3=0.000000
L 2.30926673 1.58833307 2.30766663 1.58958287 1 P 0 ;0,1,2=35,3=0.000000
L 2.30766663 1.58958287 2.30633307 1.59124911 1 P 0 ;0,1,2=35,3=0.000000
L 2.29606683 1.60833337 2.29446673 1.61083287 1 P 0 ;0,1,2=35,3=0.000000
L 2.29446673 1.61083287 2.2926 1.61208337 1 P 0 ;0,1,2=35,3=0.000000
L 2.2926 1.61208337 2.29046663 1.6125 1 P 0 ;0,1,2=35,3=0.000000
L 2.29046663 1.6125 2.2878 1.61166683 1 P 0 ;0,1,2=35,3=0.000000
L 2.2878 1.61166683 2.28593327 1.60958317 1 P 0 ;0,1,2=35,3=0.000000
L 2.28593327 1.60958317 2.2854 1.60708366 1 P 0 ;0,1,2=35,3=0.000000
L 2.2854 1.60708366 2.28566663 1.60458268 1 P 0 ;0,1,2=35,3=0.000000
L 2.28566663 1.60458268 2.28673356 1.6024998 1 P 0 ;0,1,2=35,3=0.000000
L 2.28673356 1.6024998 2.29206673 1.59833327 1 P 0 ;0,1,2=35,3=0.000000
L 2.29206673 1.59833327 2.29446673 1.59541644 1 P 0 ;0,1,2=35,3=0.000000
L 2.29446673 1.59541644 2.29606683 1.59124911 1 P 0 ;0,1,2=35,3=0.000000
L 2.29606683 1.59124911 2.2966001 1.5875 1 P 0 ;0,1,2=35,3=0.000000
L 2.2966001 1.5875 2.2854 1.5875 1 P 0 ;0,1,2=35,3=0.000000
L 2.2690003 1.6125 2.27113366 1.61166683 1 P 0 ;0,1,2=35,3=0.000000
L 2.27113366 1.61166683 2.27273337 1.60958317 1 P 0 ;0,1,2=35,3=0.000000
L 2.27273337 1.60958317 2.2738002 1.60708366 1 P 0 ;0,1,2=35,3=0.000000
L 2.2738002 1.60708366 2.2746001 1.60374951 1 P 0 ;0,1,2=35,3=0.000000
L 2.2746001 1.60374951 2.27486673 1.59999961 1 P 0 ;0,1,2=35,3=0.000000
L 2.27486673 1.59999961 2.2746001 1.59624961 1 P 0 ;0,1,2=35,3=0.000000
L 2.2746001 1.59624961 2.2738002 1.59291624 1 P 0 ;0,1,2=35,3=0.000000
L 2.2738002 1.59291624 2.27273337 1.59041604 1 P 0 ;0,1,2=35,3=0.000000
L 2.27273337 1.59041604 2.27113366 1.58833307 1 P 0 ;0,1,2=35,3=0.000000
L 2.27113366 1.58833307 2.2690003 1.5875 1 P 0 ;0,1,2=35,3=0.000000
L 2.2690003 1.5875 2.26686693 1.58833307 1 P 0 ;0,1,2=35,3=0.000000
L 2.26686693 1.58833307 2.26526673 1.59041604 1 P 0 ;0,1,2=35,3=0.000000
L 2.26526673 1.59041604 2.2641999 1.59291624 1 P 0 ;0,1,2=35,3=0.000000
L 2.2641999 1.59291624 2.2634 1.59624961 1 P 0 ;0,1,2=35,3=0.000000
L 2.2634 1.59624961 2.26313337 1.59999961 1 P 0 ;0,1,2=35,3=0.000000
L 2.26313337 1.59999961 2.2634 1.60374951 1 P 0 ;0,1,2=35,3=0.000000
L 2.2634 1.60374951 2.2641999 1.60708366 1 P 0 ;0,1,2=35,3=0.000000
L 2.2641999 1.60708366 2.26526673 1.60958317 1 P 0 ;0,1,2=35,3=0.000000
L 2.26526673 1.60958317 2.26686693 1.61166683 1 P 0 ;0,1,2=35,3=0.000000
L 2.26686693 1.61166683 2.2690003 1.6125 1 P 0 ;0,1,2=35,3=0.000000
L 2.25153366 1.59041604 2.24966683 1.58833307 1 P 0 ;0,1,2=35,3=0.000000
L 2.24966683 1.58833307 2.24753346 1.5875 1 P 0 ;0,1,2=35,3=0.000000
L 2.24753346 1.5875 2.2454001 1.58833307 1 P 0 ;0,1,2=35,3=0.000000
L 2.2454001 1.58833307 2.24353337 1.59083258 1 P 0 ;0,1,2=35,3=0.000000
L 2.24353337 1.59083258 2.2421999 1.59458327 1 P 0 ;0,1,2=35,3=0.000000
L 2.2421999 1.59458327 2.24166663 1.59833327 1 P 0 ;0,1,2=35,3=0.000000
L 2.24166663 1.59833327 2.24166663 1.60291634 1 P 0 ;0,1,2=35,3=0.000000
L 2.24166663 1.60291634 2.2421999 1.60666634 1 P 0 ;0,1,2=35,3=0.000000
L 2.2421999 1.60666634 2.24353337 1.6099997 1 P 0 ;0,1,2=35,3=0.000000
L 2.24353337 1.6099997 2.24513356 1.61166683 1 P 0 ;0,1,2=35,3=0.000000
L 2.24513356 1.61166683 2.2470003 1.6125 1 P 0 ;0,1,2=35,3=0.000000
L 2.2470003 1.6125 2.24913366 1.61166683 1 P 0 ;0,1,2=35,3=0.000000
L 2.24913366 1.61166683 2.25073337 1.6099997 1 P 0 ;0,1,2=35,3=0.000000
L 2.25073337 1.6099997 2.2518002 1.6075003 1 P 0 ;0,1,2=35,3=0.000000
L 2.2518002 1.6075003 2.25233346 1.60416614 1 P 0 ;0,1,2=35,3=0.000000
L 2.25233346 1.60416614 2.2518002 1.6012501 1 P 0 ;0,1,2=35,3=0.000000
L 2.2518002 1.6012501 2.25046673 1.59833327 1 P 0 ;0,1,2=35,3=0.000000
L 2.25046673 1.59833327 2.24886654 1.59666614 1 P 0 ;0,1,2=35,3=0.000000
L 2.24886654 1.59666614 2.2470003 1.59624961 1 P 0 ;0,1,2=35,3=0.000000
L 2.2470003 1.59624961 2.24486693 1.59708278 1 P 0 ;0,1,2=35,3=0.000000
L 2.24486693 1.59708278 2.24326673 1.59916644 1 P 0 ;0,1,2=35,3=0.000000
L 2.24326673 1.59916644 2.24166663 1.60291634 1 P 0 ;0,1,2=35,3=0.000000
L 3.91248002 1.70681998 3.94948002 1.70681998 1 P 0 
L 3.91248002 1.7832 3.91248002 1.70681998 1 P 0 
L 3.94948002 1.7832 3.91248002 1.7832 1 P 0 
L 3.94948002 1.70681998 3.94948002 1.7832 1 P 0 
L 3.98041634 1.74286663 3.98166683 1.74126644 1 P 0 ;0,1,2=36,3=90.000000
L 3.98166683 1.74126644 3.9825 1.7394002 1 P 0 ;0,1,2=36,3=90.000000
L 3.9825 1.7394002 3.9825 1.73726683 1 P 0 ;0,1,2=36,3=90.000000
L 3.9825 1.73726683 3.98124941 1.73486634 1 P 0 ;0,1,2=36,3=90.000000
L 3.98124941 1.73486634 3.97916654 1.7330001 1 P 0 ;0,1,2=36,3=90.000000
L 3.97916654 1.7330001 3.97666634 1.73166654 1 P 0 ;0,1,2=36,3=90.000000
L 3.97666634 1.73166654 3.9724998 1.73059961 1 P 0 ;0,1,2=36,3=90.000000
L 3.9724998 1.73059961 3.9687498 1.73033297 1 P 0 ;0,1,2=36,3=90.000000
L 3.9687498 1.73033297 3.9649999 1.73086673 1 P 0 ;0,1,2=36,3=90.000000
L 3.9649999 1.73086673 3.96249961 1.73166654 1 P 0 ;0,1,2=36,3=90.000000
L 3.96249961 1.73166654 3.95999941 1.73326663 1 P 0 ;0,1,2=36,3=90.000000
L 3.95999941 1.73326663 3.95833307 1.73513346 1 P 0 ;0,1,2=36,3=90.000000
L 3.95833307 1.73513346 3.9575 1.7369997 1 P 0 ;0,1,2=36,3=90.000000
L 3.9575 1.7369997 3.9575 1.73886644 1 P 0 ;0,1,2=36,3=90.000000
L 3.9575 1.73886644 3.95833307 1.74073327 1 P 0 ;0,1,2=36,3=90.000000
L 3.95833307 1.74073327 3.95958287 1.74233337 1 P 0 ;0,1,2=36,3=90.000000
L 3.95958287 1.74233337 3.96124911 1.74366693 1 P 0 ;0,1,2=36,3=90.000000
L 3.97833337 1.75393317 3.98083287 1.75553327 1 P 0 ;0,1,2=36,3=90.000000
L 3.98083287 1.75553327 3.98208337 1.7574 1 P 0 ;0,1,2=36,3=90.000000
L 3.98208337 1.7574 3.9825 1.75953337 1 P 0 ;0,1,2=36,3=90.000000
L 3.9825 1.75953337 3.98166683 1.7622 1 P 0 ;0,1,2=36,3=90.000000
L 3.98166683 1.7622 3.97958317 1.76406673 1 P 0 ;0,1,2=36,3=90.000000
L 3.97958317 1.76406673 3.97708366 1.7646 1 P 0 ;0,1,2=36,3=90.000000
L 3.97708366 1.7646 3.97458268 1.76433337 1 P 0 ;0,1,2=36,3=90.000000
L 3.97458268 1.76433337 3.9724998 1.76326644 1 P 0 ;0,1,2=36,3=90.000000
L 3.9724998 1.76326644 3.96833327 1.75793327 1 P 0 ;0,1,2=36,3=90.000000
L 3.96833327 1.75793327 3.96541644 1.75553327 1 P 0 ;0,1,2=36,3=90.000000
L 3.96541644 1.75553327 3.96124911 1.75393317 1 P 0 ;0,1,2=36,3=90.000000
L 3.96124911 1.75393317 3.9575 1.7533999 1 P 0 ;0,1,2=36,3=90.000000
L 3.9575 1.7533999 3.9575 1.7646 1 P 0 ;0,1,2=36,3=90.000000
L 3.9825 1.7809997 3.98166683 1.77886634 1 P 0 ;0,1,2=36,3=90.000000
L 3.98166683 1.77886634 3.97958317 1.77726663 1 P 0 ;0,1,2=36,3=90.000000
L 3.97958317 1.77726663 3.97708366 1.7761998 1 P 0 ;0,1,2=36,3=90.000000
L 3.97708366 1.7761998 3.97374951 1.7753999 1 P 0 ;0,1,2=36,3=90.000000
L 3.97374951 1.7753999 3.96999961 1.77513327 1 P 0 ;0,1,2=36,3=90.000000
L 3.96999961 1.77513327 3.96624961 1.7753999 1 P 0 ;0,1,2=36,3=90.000000
L 3.96624961 1.7753999 3.96291624 1.7761998 1 P 0 ;0,1,2=36,3=90.000000
L 3.96291624 1.7761998 3.96041604 1.77726663 1 P 0 ;0,1,2=36,3=90.000000
L 3.96041604 1.77726663 3.95833307 1.77886634 1 P 0 ;0,1,2=36,3=90.000000
L 3.95833307 1.77886634 3.9575 1.7809997 1 P 0 ;0,1,2=36,3=90.000000
L 3.9575 1.7809997 3.95833307 1.78313307 1 P 0 ;0,1,2=36,3=90.000000
L 3.95833307 1.78313307 3.96041604 1.78473327 1 P 0 ;0,1,2=36,3=90.000000
L 3.96041604 1.78473327 3.96291624 1.7858001 1 P 0 ;0,1,2=36,3=90.000000
L 3.96291624 1.7858001 3.96624961 1.7866 1 P 0 ;0,1,2=36,3=90.000000
L 3.96624961 1.7866 3.96999961 1.78686663 1 P 0 ;0,1,2=36,3=90.000000
L 3.96999961 1.78686663 3.97374951 1.7866 1 P 0 ;0,1,2=36,3=90.000000
L 3.97374951 1.7866 3.97708366 1.7858001 1 P 0 ;0,1,2=36,3=90.000000
L 3.97708366 1.7858001 3.97958317 1.78473327 1 P 0 ;0,1,2=36,3=90.000000
L 3.97958317 1.78473327 3.98166683 1.78313307 1 P 0 ;0,1,2=36,3=90.000000
L 3.98166683 1.78313307 3.9825 1.7809997 1 P 0 ;0,1,2=36,3=90.000000
L 3.96124911 1.79713327 3.95916624 1.79873297 1 P 0 ;0,1,2=36,3=90.000000
L 3.95916624 1.79873297 3.95791654 1.8005997 1 P 0 ;0,1,2=36,3=90.000000
L 3.95791654 1.8005997 3.9575 1.8029997 1 P 0 ;0,1,2=36,3=90.000000
L 3.9575 1.8029997 3.95833307 1.8054002 1 P 0 ;0,1,2=36,3=90.000000
L 3.95833307 1.8054002 3.95999941 1.80726644 1 P 0 ;0,1,2=36,3=90.000000
L 3.95999941 1.80726644 3.96291624 1.8086 1 P 0 ;0,1,2=36,3=90.000000
L 3.96291624 1.8086 3.96624961 1.80886663 1 P 0 ;0,1,2=36,3=90.000000
L 3.96624961 1.80886663 3.96958297 1.80833337 1 P 0 ;0,1,2=36,3=90.000000
L 3.96958297 1.80833337 3.97166663 1.8069998 1 P 0 ;0,1,2=36,3=90.000000
L 3.97166663 1.8069998 3.97333297 1.80513307 1 P 0 ;0,1,2=36,3=90.000000
L 3.97333297 1.80513307 3.97374951 1.80326683 1 P 0 ;0,1,2=36,3=90.000000
L 3.97374951 1.80326683 3.97333297 1.8014 1 P 0 ;0,1,2=36,3=90.000000
L 3.97333297 1.8014 3.97166663 1.7990001 1 P 0 ;0,1,2=36,3=90.000000
L 3.97166663 1.7990001 3.9825 1.7997999 1 P 0 ;0,1,2=36,3=90.000000
L 3.9825 1.7997999 3.9825 1.8069998 1 P 0 ;0,1,2=36,3=90.000000
L 3.94948002 1.4706 3.94948002 1.5076 1 P 0 
L 3.8731 1.4706 3.94948002 1.4706 1 P 0 
L 3.8731 1.5076 3.8731 1.4706 1 P 0 
L 3.94948002 1.5076 3.8731 1.5076 1 P 0 
L 2.27713337 1.41541634 2.27873356 1.41666683 1 P 0 ;0,1,2=37,3=0.000000
L 2.27873356 1.41666683 2.2805998 1.4175 1 P 0 ;0,1,2=37,3=0.000000
L 2.2805998 1.4175 2.28273317 1.4175 1 P 0 ;0,1,2=37,3=0.000000
L 2.28273317 1.4175 2.28513366 1.41624941 1 P 0 ;0,1,2=37,3=0.000000
L 2.28513366 1.41624941 2.2869999 1.41416654 1 P 0 ;0,1,2=37,3=0.000000
L 2.2869999 1.41416654 2.28833346 1.41166634 1 P 0 ;0,1,2=37,3=0.000000
L 2.28833346 1.41166634 2.28940039 1.4074998 1 P 0 ;0,1,2=37,3=0.000000
L 2.28940039 1.4074998 2.28966703 1.4037498 1 P 0 ;0,1,2=37,3=0.000000
L 2.28966703 1.4037498 2.28913327 1.3999999 1 P 0 ;0,1,2=37,3=0.000000
L 2.28913327 1.3999999 2.28833346 1.39749961 1 P 0 ;0,1,2=37,3=0.000000
L 2.28833346 1.39749961 2.28673337 1.39499941 1 P 0 ;0,1,2=37,3=0.000000
L 2.28673337 1.39499941 2.28486654 1.39333307 1 P 0 ;0,1,2=37,3=0.000000
L 2.28486654 1.39333307 2.2830003 1.3925 1 P 0 ;0,1,2=37,3=0.000000
L 2.2830003 1.3925 2.28113356 1.3925 1 P 0 ;0,1,2=37,3=0.000000
L 2.28113356 1.3925 2.27926673 1.39333307 1 P 0 ;0,1,2=37,3=0.000000
L 2.27926673 1.39333307 2.27766663 1.39458287 1 P 0 ;0,1,2=37,3=0.000000
L 2.27766663 1.39458287 2.27633307 1.39624911 1 P 0 ;0,1,2=37,3=0.000000
L 2.2610003 1.3925 2.2610003 1.4175 1 P 0 ;0,1,2=37,3=0.000000
L 2.2610003 1.4175 2.2642001 1.4125003 1 P 0 ;0,1,2=37,3=0.000000
L 2.2642001 1.3925 2.25780049 1.3925 1 P 0 ;0,1,2=37,3=0.000000
L 2.2390003 1.3925 2.2390003 1.4175 1 P 0 ;0,1,2=37,3=0.000000
L 2.2390003 1.4175 2.2422001 1.4125003 1 P 0 ;0,1,2=37,3=0.000000
L 2.2422001 1.3925 2.23580049 1.3925 1 P 0 ;0,1,2=37,3=0.000000
L 2.2170003 1.4175 2.21913366 1.41666683 1 P 0 ;0,1,2=37,3=0.000000
L 2.21913366 1.41666683 2.22073337 1.41458317 1 P 0 ;0,1,2=37,3=0.000000
L 2.22073337 1.41458317 2.2218002 1.41208366 1 P 0 ;0,1,2=37,3=0.000000
L 2.2218002 1.41208366 2.2226001 1.40874951 1 P 0 ;0,1,2=37,3=0.000000
L 2.2226001 1.40874951 2.22286673 1.40499961 1 P 0 ;0,1,2=37,3=0.000000
L 2.22286673 1.40499961 2.2226001 1.40124961 1 P 0 ;0,1,2=37,3=0.000000
L 2.2226001 1.40124961 2.2218002 1.39791624 1 P 0 ;0,1,2=37,3=0.000000
L 2.2218002 1.39791624 2.22073337 1.39541604 1 P 0 ;0,1,2=37,3=0.000000
L 2.22073337 1.39541604 2.21913366 1.39333307 1 P 0 ;0,1,2=37,3=0.000000
L 2.21913366 1.39333307 2.2170003 1.3925 1 P 0 ;0,1,2=37,3=0.000000
L 2.2170003 1.3925 2.21486693 1.39333307 1 P 0 ;0,1,2=37,3=0.000000
L 2.21486693 1.39333307 2.21326673 1.39541604 1 P 0 ;0,1,2=37,3=0.000000
L 2.21326673 1.39541604 2.2121999 1.39791624 1 P 0 ;0,1,2=37,3=0.000000
L 2.2121999 1.39791624 2.2114 1.40124961 1 P 0 ;0,1,2=37,3=0.000000
L 2.2114 1.40124961 2.21113337 1.40499961 1 P 0 ;0,1,2=37,3=0.000000
L 2.21113337 1.40499961 2.2114 1.40874951 1 P 0 ;0,1,2=37,3=0.000000
L 2.2114 1.40874951 2.2121999 1.41208366 1 P 0 ;0,1,2=37,3=0.000000
L 2.2121999 1.41208366 2.21326673 1.41458317 1 P 0 ;0,1,2=37,3=0.000000
L 2.21326673 1.41458317 2.21486693 1.41666683 1 P 0 ;0,1,2=37,3=0.000000
L 2.21486693 1.41666683 2.2170003 1.4175 1 P 0 ;0,1,2=37,3=0.000000
L 3.95185 1.43123002 3.98885 1.43123002 1 P 0 
L 3.95185 1.50761004 3.95185 1.43123002 1 P 0 
L 3.98885 1.43123002 3.98885 1.50761004 1 P 0 
L 3.98885 1.50761004 3.95185 1.50761004 1 P 0 
L 2.32771634 1.38226663 2.32896683 1.38066644 1 P 0 ;0,1,2=38,3=90.000000
L 2.32896683 1.38066644 2.3298 1.3788002 1 P 0 ;0,1,2=38,3=90.000000
L 2.3298 1.3788002 2.3298 1.37666683 1 P 0 ;0,1,2=38,3=90.000000
L 2.3298 1.37666683 2.32854941 1.37426634 1 P 0 ;0,1,2=38,3=90.000000
L 2.32854941 1.37426634 2.32646654 1.3724001 1 P 0 ;0,1,2=38,3=90.000000
L 2.32646654 1.3724001 2.32396634 1.37106654 1 P 0 ;0,1,2=38,3=90.000000
L 2.32396634 1.37106654 2.3197998 1.36999961 1 P 0 ;0,1,2=38,3=90.000000
L 2.3197998 1.36999961 2.3160498 1.36973297 1 P 0 ;0,1,2=38,3=90.000000
L 2.3160498 1.36973297 2.3122999 1.37026673 1 P 0 ;0,1,2=38,3=90.000000
L 2.3122999 1.37026673 2.30979961 1.37106654 1 P 0 ;0,1,2=38,3=90.000000
L 2.30979961 1.37106654 2.30729941 1.37266663 1 P 0 ;0,1,2=38,3=90.000000
L 2.30729941 1.37266663 2.30563307 1.37453346 1 P 0 ;0,1,2=38,3=90.000000
L 2.30563307 1.37453346 2.3048 1.3763997 1 P 0 ;0,1,2=38,3=90.000000
L 2.3048 1.3763997 2.3048 1.37826644 1 P 0 ;0,1,2=38,3=90.000000
L 2.3048 1.37826644 2.30563307 1.38013327 1 P 0 ;0,1,2=38,3=90.000000
L 2.30563307 1.38013327 2.30688287 1.38173337 1 P 0 ;0,1,2=38,3=90.000000
L 2.30688287 1.38173337 2.30854911 1.38306693 1 P 0 ;0,1,2=38,3=90.000000
L 2.32563337 1.39333317 2.32813287 1.39493327 1 P 0 ;0,1,2=38,3=90.000000
L 2.32813287 1.39493327 2.32938337 1.3968 1 P 0 ;0,1,2=38,3=90.000000
L 2.32938337 1.3968 2.3298 1.39893337 1 P 0 ;0,1,2=38,3=90.000000
L 2.3298 1.39893337 2.32896683 1.4016 1 P 0 ;0,1,2=38,3=90.000000
L 2.32896683 1.4016 2.32688317 1.40346673 1 P 0 ;0,1,2=38,3=90.000000
L 2.32688317 1.40346673 2.32438366 1.404 1 P 0 ;0,1,2=38,3=90.000000
L 2.32438366 1.404 2.32188268 1.40373337 1 P 0 ;0,1,2=38,3=90.000000
L 2.32188268 1.40373337 2.3197998 1.40266644 1 P 0 ;0,1,2=38,3=90.000000
L 2.3197998 1.40266644 2.31563327 1.39733327 1 P 0 ;0,1,2=38,3=90.000000
L 2.31563327 1.39733327 2.31271644 1.39493327 1 P 0 ;0,1,2=38,3=90.000000
L 2.31271644 1.39493327 2.30854911 1.39333317 1 P 0 ;0,1,2=38,3=90.000000
L 2.30854911 1.39333317 2.3048 1.3927999 1 P 0 ;0,1,2=38,3=90.000000
L 2.3048 1.3927999 2.3048 1.404 1 P 0 ;0,1,2=38,3=90.000000
L 2.3048 1.4203997 2.3298 1.4203997 1 P 0 ;0,1,2=38,3=90.000000
L 2.3298 1.4203997 2.3248003 1.4171999 1 P 0 ;0,1,2=38,3=90.000000
L 2.3048 1.4171999 2.3048 1.42359951 1 P 0 ;0,1,2=38,3=90.000000
L 2.3048 1.44186654 2.31021624 1.4423997 1 P 0 ;0,1,2=38,3=90.000000
L 2.31021624 1.4423997 2.31479931 1.4432 1 P 0 ;0,1,2=38,3=90.000000
L 2.31479931 1.4432 2.31896663 1.44426644 1 P 0 ;0,1,2=38,3=90.000000
L 2.31896663 1.44426644 2.3235498 1.4456 1 P 0 ;0,1,2=38,3=90.000000
L 2.3235498 1.4456 2.3298 1.44773337 1 P 0 ;0,1,2=38,3=90.000000
L 2.3298 1.44773337 2.3298 1.43706654 1 P 0 ;0,1,2=38,3=90.000000
L 4.77626998 1.98241004 4.77626998 2.01941004 1 P 0 
L 4.69988996 1.98241004 4.77626998 1.98241004 1 P 0 
L 4.77626998 2.01941004 4.69988996 2.01941004 1 P 0 
L 4.69988996 2.01941004 4.69988996 1.98241004 1 P 0 
L 4.77213337 2.05041634 4.77373356 2.05166683 1 P 0 ;0,1,2=39,3=0.000000
L 4.77373356 2.05166683 4.7755998 2.0525 1 P 0 ;0,1,2=39,3=0.000000
L 4.7755998 2.0525 4.77773317 2.0525 1 P 0 ;0,1,2=39,3=0.000000
L 4.77773317 2.0525 4.78013366 2.05124941 1 P 0 ;0,1,2=39,3=0.000000
L 4.78013366 2.05124941 4.7819999 2.04916654 1 P 0 ;0,1,2=39,3=0.000000
L 4.7819999 2.04916654 4.78333346 2.04666634 1 P 0 ;0,1,2=39,3=0.000000
L 4.78333346 2.04666634 4.78440039 2.0424998 1 P 0 ;0,1,2=39,3=0.000000
L 4.78440039 2.0424998 4.78466703 2.0387498 1 P 0 ;0,1,2=39,3=0.000000
L 4.78466703 2.0387498 4.78413327 2.0349999 1 P 0 ;0,1,2=39,3=0.000000
L 4.78413327 2.0349999 4.78333346 2.03249961 1 P 0 ;0,1,2=39,3=0.000000
L 4.78333346 2.03249961 4.78173337 2.02999941 1 P 0 ;0,1,2=39,3=0.000000
L 4.78173337 2.02999941 4.77986654 2.02833307 1 P 0 ;0,1,2=39,3=0.000000
L 4.77986654 2.02833307 4.7780003 2.0275 1 P 0 ;0,1,2=39,3=0.000000
L 4.7780003 2.0275 4.77613356 2.0275 1 P 0 ;0,1,2=39,3=0.000000
L 4.77613356 2.0275 4.77426673 2.02833307 1 P 0 ;0,1,2=39,3=0.000000
L 4.77426673 2.02833307 4.77266663 2.02958287 1 P 0 ;0,1,2=39,3=0.000000
L 4.77266663 2.02958287 4.77133307 2.03124911 1 P 0 ;0,1,2=39,3=0.000000
L 4.7560003 2.0275 4.7560003 2.0525 1 P 0 ;0,1,2=39,3=0.000000
L 4.7560003 2.0525 4.7592001 2.0475003 1 P 0 ;0,1,2=39,3=0.000000
L 4.7592001 2.0275 4.75280049 2.0275 1 P 0 ;0,1,2=39,3=0.000000
L 4.7340003 2.0525 4.73613366 2.05166683 1 P 0 ;0,1,2=39,3=0.000000
L 4.73613366 2.05166683 4.73773337 2.04958317 1 P 0 ;0,1,2=39,3=0.000000
L 4.73773337 2.04958317 4.7388002 2.04708366 1 P 0 ;0,1,2=39,3=0.000000
L 4.7388002 2.04708366 4.7396001 2.04374951 1 P 0 ;0,1,2=39,3=0.000000
L 4.7396001 2.04374951 4.73986673 2.03999961 1 P 0 ;0,1,2=39,3=0.000000
L 4.73986673 2.03999961 4.7396001 2.03624961 1 P 0 ;0,1,2=39,3=0.000000
L 4.7396001 2.03624961 4.7388002 2.03291624 1 P 0 ;0,1,2=39,3=0.000000
L 4.7388002 2.03291624 4.73773337 2.03041604 1 P 0 ;0,1,2=39,3=0.000000
L 4.73773337 2.03041604 4.73613366 2.02833307 1 P 0 ;0,1,2=39,3=0.000000
L 4.73613366 2.02833307 4.7340003 2.0275 1 P 0 ;0,1,2=39,3=0.000000
L 4.7340003 2.0275 4.73186693 2.02833307 1 P 0 ;0,1,2=39,3=0.000000
L 4.73186693 2.02833307 4.73026673 2.03041604 1 P 0 ;0,1,2=39,3=0.000000
L 4.73026673 2.03041604 4.7291999 2.03291624 1 P 0 ;0,1,2=39,3=0.000000
L 4.7291999 2.03291624 4.7284 2.03624961 1 P 0 ;0,1,2=39,3=0.000000
L 4.7284 2.03624961 4.72813337 2.03999961 1 P 0 ;0,1,2=39,3=0.000000
L 4.72813337 2.03999961 4.7284 2.04374951 1 P 0 ;0,1,2=39,3=0.000000
L 4.7284 2.04374951 4.7291999 2.04708366 1 P 0 ;0,1,2=39,3=0.000000
L 4.7291999 2.04708366 4.73026673 2.04958317 1 P 0 ;0,1,2=39,3=0.000000
L 4.73026673 2.04958317 4.73186693 2.05166683 1 P 0 ;0,1,2=39,3=0.000000
L 4.73186693 2.05166683 4.7340003 2.0525 1 P 0 ;0,1,2=39,3=0.000000
L 4.71786673 2.03249961 4.71626703 2.02958287 1 P 0 ;0,1,2=39,3=0.000000
L 4.71626703 2.02958287 4.71413366 2.02791654 1 P 0 ;0,1,2=39,3=0.000000
L 4.71413366 2.02791654 4.71173317 2.0275 1 P 0 ;0,1,2=39,3=0.000000
L 4.71173317 2.0275 4.7095998 2.02791654 1 P 0 ;0,1,2=39,3=0.000000
L 4.7095998 2.02791654 4.70746644 2.02999941 1 P 0 ;0,1,2=39,3=0.000000
L 4.70746644 2.02999941 4.70613337 2.03249961 1 P 0 ;0,1,2=39,3=0.000000
L 4.70613337 2.03249961 4.70586683 2.0349999 1 P 0 ;0,1,2=39,3=0.000000
L 4.70586683 2.0349999 4.7064 2.03791594 1 P 0 ;0,1,2=39,3=0.000000
L 4.7064 2.03791594 4.70826673 2.03999961 1 P 0 ;0,1,2=39,3=0.000000
L 4.70826673 2.03999961 4.71013356 2.04083346 1 P 0 ;0,1,2=39,3=0.000000
L 4.71013356 2.04083346 4.71253346 2.04083346 1 P 0 ;0,1,2=39,3=0.000000
L 4.71013356 2.04083346 4.70853337 2.04208327 1 P 0 ;0,1,2=39,3=0.000000
L 4.70853337 2.04208327 4.7071999 2.04416614 1 P 0 ;0,1,2=39,3=0.000000
L 4.7071999 2.04416614 4.70666663 2.04666634 1 P 0 ;0,1,2=39,3=0.000000
L 4.70666663 2.04666634 4.7071999 2.04916654 1 P 0 ;0,1,2=39,3=0.000000
L 4.7071999 2.04916654 4.70853337 2.05124941 1 P 0 ;0,1,2=39,3=0.000000
L 4.70853337 2.05124941 4.71093337 2.0525 1 P 0 ;0,1,2=39,3=0.000000
L 4.71093337 2.0525 4.71333337 2.05208337 1 P 0 ;0,1,2=39,3=0.000000
L 4.71333337 2.05208337 4.71573337 2.05041634 1 P 0 ;0,1,2=39,3=0.000000
L 4.18571004 1.54933002 4.18571004 1.62571004 1 P 0 
L 4.18571004 1.62571004 4.14871004 1.62571004 1 P 0 
L 4.14871004 1.62571004 4.14871004 1.54933002 1 P 0 
L 4.14871004 1.54933002 4.18571004 1.54933002 1 P 0 
L 2.54961634 1.51536663 2.55086683 1.51376644 1 P 0 ;0,1,2=40,3=90.000000
L 2.55086683 1.51376644 2.5517 1.5119002 1 P 0 ;0,1,2=40,3=90.000000
L 2.5517 1.5119002 2.5517 1.50976683 1 P 0 ;0,1,2=40,3=90.000000
L 2.5517 1.50976683 2.55044941 1.50736634 1 P 0 ;0,1,2=40,3=90.000000
L 2.55044941 1.50736634 2.54836654 1.5055001 1 P 0 ;0,1,2=40,3=90.000000
L 2.54836654 1.5055001 2.54586634 1.50416654 1 P 0 ;0,1,2=40,3=90.000000
L 2.54586634 1.50416654 2.5416998 1.50309961 1 P 0 ;0,1,2=40,3=90.000000
L 2.5416998 1.50309961 2.5379498 1.50283297 1 P 0 ;0,1,2=40,3=90.000000
L 2.5379498 1.50283297 2.5341999 1.50336673 1 P 0 ;0,1,2=40,3=90.000000
L 2.5341999 1.50336673 2.53169961 1.50416654 1 P 0 ;0,1,2=40,3=90.000000
L 2.53169961 1.50416654 2.52919941 1.50576663 1 P 0 ;0,1,2=40,3=90.000000
L 2.52919941 1.50576663 2.52753307 1.50763346 1 P 0 ;0,1,2=40,3=90.000000
L 2.52753307 1.50763346 2.5267 1.5094997 1 P 0 ;0,1,2=40,3=90.000000
L 2.5267 1.5094997 2.5267 1.51136644 1 P 0 ;0,1,2=40,3=90.000000
L 2.5267 1.51136644 2.52753307 1.51323327 1 P 0 ;0,1,2=40,3=90.000000
L 2.52753307 1.51323327 2.52878287 1.51483337 1 P 0 ;0,1,2=40,3=90.000000
L 2.52878287 1.51483337 2.53044911 1.51616693 1 P 0 ;0,1,2=40,3=90.000000
L 2.5267 1.5314997 2.5517 1.5314997 1 P 0 ;0,1,2=40,3=90.000000
L 2.5517 1.5314997 2.5467003 1.5282999 1 P 0 ;0,1,2=40,3=90.000000
L 2.5267 1.5282999 2.5267 1.53469951 1 P 0 ;0,1,2=40,3=90.000000
L 2.54753337 1.54843317 2.55003287 1.55003327 1 P 0 ;0,1,2=40,3=90.000000
L 2.55003287 1.55003327 2.55128337 1.5519 1 P 0 ;0,1,2=40,3=90.000000
L 2.55128337 1.5519 2.5517 1.55403337 1 P 0 ;0,1,2=40,3=90.000000
L 2.5517 1.55403337 2.55086683 1.5567 1 P 0 ;0,1,2=40,3=90.000000
L 2.55086683 1.5567 2.54878317 1.55856673 1 P 0 ;0,1,2=40,3=90.000000
L 2.54878317 1.55856673 2.54628366 1.5591 1 P 0 ;0,1,2=40,3=90.000000
L 2.54628366 1.5591 2.54378268 1.55883337 1 P 0 ;0,1,2=40,3=90.000000
L 2.54378268 1.55883337 2.5416998 1.55776644 1 P 0 ;0,1,2=40,3=90.000000
L 2.5416998 1.55776644 2.53753327 1.55243327 1 P 0 ;0,1,2=40,3=90.000000
L 2.53753327 1.55243327 2.53461644 1.55003327 1 P 0 ;0,1,2=40,3=90.000000
L 2.53461644 1.55003327 2.53044911 1.54843317 1 P 0 ;0,1,2=40,3=90.000000
L 2.53044911 1.54843317 2.5267 1.5478999 1 P 0 ;0,1,2=40,3=90.000000
L 2.5267 1.5478999 2.5267 1.5591 1 P 0 ;0,1,2=40,3=90.000000
L 2.5267 1.5754997 2.5517 1.5754997 1 P 0 ;0,1,2=40,3=90.000000
L 2.5517 1.5754997 2.5467003 1.5722999 1 P 0 ;0,1,2=40,3=90.000000
L 2.5267 1.5722999 2.5267 1.57869951 1 P 0 ;0,1,2=40,3=90.000000
L 4.18808002 1.54933996 4.26446004 1.54933996 1 P 0 
L 4.26446004 1.54933996 4.26446004 1.58633996 1 P 0 
L 4.26446004 1.58633996 4.18808002 1.58633996 1 P 0 
L 4.18808002 1.58633996 4.18808002 1.54933996 1 P 0 
L 2.62843337 1.53021634 2.63003356 1.53146683 1 P 0 ;0,1,2=41,3=0.000000
L 2.63003356 1.53146683 2.6318998 1.5323 1 P 0 ;0,1,2=41,3=0.000000
L 2.6318998 1.5323 2.63403317 1.5323 1 P 0 ;0,1,2=41,3=0.000000
L 2.63403317 1.5323 2.63643366 1.53104941 1 P 0 ;0,1,2=41,3=0.000000
L 2.63643366 1.53104941 2.6382999 1.52896654 1 P 0 ;0,1,2=41,3=0.000000
L 2.6382999 1.52896654 2.63963346 1.52646634 1 P 0 ;0,1,2=41,3=0.000000
L 2.63963346 1.52646634 2.64070039 1.5222998 1 P 0 ;0,1,2=41,3=0.000000
L 2.64070039 1.5222998 2.64096703 1.5185498 1 P 0 ;0,1,2=41,3=0.000000
L 2.64096703 1.5185498 2.64043327 1.5147999 1 P 0 ;0,1,2=41,3=0.000000
L 2.64043327 1.5147999 2.63963346 1.51229961 1 P 0 ;0,1,2=41,3=0.000000
L 2.63963346 1.51229961 2.63803337 1.50979941 1 P 0 ;0,1,2=41,3=0.000000
L 2.63803337 1.50979941 2.63616654 1.50813307 1 P 0 ;0,1,2=41,3=0.000000
L 2.63616654 1.50813307 2.6343003 1.5073 1 P 0 ;0,1,2=41,3=0.000000
L 2.6343003 1.5073 2.63243356 1.5073 1 P 0 ;0,1,2=41,3=0.000000
L 2.63243356 1.5073 2.63056673 1.50813307 1 P 0 ;0,1,2=41,3=0.000000
L 2.63056673 1.50813307 2.62896663 1.50938287 1 P 0 ;0,1,2=41,3=0.000000
L 2.62896663 1.50938287 2.62763307 1.51104911 1 P 0 ;0,1,2=41,3=0.000000
L 2.6123003 1.5073 2.6123003 1.5323 1 P 0 ;0,1,2=41,3=0.000000
L 2.6123003 1.5323 2.6155001 1.5273003 1 P 0 ;0,1,2=41,3=0.000000
L 2.6155001 1.5073 2.60910049 1.5073 1 P 0 ;0,1,2=41,3=0.000000
L 2.5871 1.5073 2.5871 1.5323 1 P 0 ;0,1,2=41,3=0.000000
L 2.5871 1.5323 2.59696703 1.51438327 1 P 0 ;0,1,2=41,3=0.000000
L 2.59696703 1.51438327 2.58363307 1.51438327 1 P 0 ;0,1,2=41,3=0.000000
L 2.5683003 1.5073 2.5683003 1.5323 1 P 0 ;0,1,2=41,3=0.000000
L 2.5683003 1.5323 2.5715001 1.5273003 1 P 0 ;0,1,2=41,3=0.000000
L 2.5715001 1.5073 2.56510049 1.5073 1 P 0 ;0,1,2=41,3=0.000000
L 4.26445 1.70445 4.18806998 1.70445 1 P 0 
L 4.18806998 1.70445 4.18806998 1.66745 1 P 0 
L 4.18806998 1.66745 4.26445 1.66745 1 P 0 
L 4.26445 1.66745 4.26445 1.70445 1 P 0 
L 2.63213337 1.66041634 2.63373356 1.66166683 1 P 0 ;0,1,2=42,3=0.000000
L 2.63373356 1.66166683 2.6355998 1.6625 1 P 0 ;0,1,2=42,3=0.000000
L 2.6355998 1.6625 2.63773317 1.6625 1 P 0 ;0,1,2=42,3=0.000000
L 2.63773317 1.6625 2.64013366 1.66124941 1 P 0 ;0,1,2=42,3=0.000000
L 2.64013366 1.66124941 2.6419999 1.65916654 1 P 0 ;0,1,2=42,3=0.000000
L 2.6419999 1.65916654 2.64333346 1.65666634 1 P 0 ;0,1,2=42,3=0.000000
L 2.64333346 1.65666634 2.64440039 1.6524998 1 P 0 ;0,1,2=42,3=0.000000
L 2.64440039 1.6524998 2.64466703 1.6487498 1 P 0 ;0,1,2=42,3=0.000000
L 2.64466703 1.6487498 2.64413327 1.6449999 1 P 0 ;0,1,2=42,3=0.000000
L 2.64413327 1.6449999 2.64333346 1.64249961 1 P 0 ;0,1,2=42,3=0.000000
L 2.64333346 1.64249961 2.64173337 1.63999941 1 P 0 ;0,1,2=42,3=0.000000
L 2.64173337 1.63999941 2.63986654 1.63833307 1 P 0 ;0,1,2=42,3=0.000000
L 2.63986654 1.63833307 2.6380003 1.6375 1 P 0 ;0,1,2=42,3=0.000000
L 2.6380003 1.6375 2.63613356 1.6375 1 P 0 ;0,1,2=42,3=0.000000
L 2.63613356 1.6375 2.63426673 1.63833307 1 P 0 ;0,1,2=42,3=0.000000
L 2.63426673 1.63833307 2.63266663 1.63958287 1 P 0 ;0,1,2=42,3=0.000000
L 2.63266663 1.63958287 2.63133307 1.64124911 1 P 0 ;0,1,2=42,3=0.000000
L 2.6160003 1.6375 2.6160003 1.6625 1 P 0 ;0,1,2=42,3=0.000000
L 2.6160003 1.6625 2.6192001 1.6575003 1 P 0 ;0,1,2=42,3=0.000000
L 2.6192001 1.6375 2.61280049 1.6375 1 P 0 ;0,1,2=42,3=0.000000
L 2.5940003 1.6625 2.59613366 1.66166683 1 P 0 ;0,1,2=42,3=0.000000
L 2.59613366 1.66166683 2.59773337 1.65958317 1 P 0 ;0,1,2=42,3=0.000000
L 2.59773337 1.65958317 2.5988002 1.65708366 1 P 0 ;0,1,2=42,3=0.000000
L 2.5988002 1.65708366 2.5996001 1.65374951 1 P 0 ;0,1,2=42,3=0.000000
L 2.5996001 1.65374951 2.59986673 1.64999961 1 P 0 ;0,1,2=42,3=0.000000
L 2.59986673 1.64999961 2.5996001 1.64624961 1 P 0 ;0,1,2=42,3=0.000000
L 2.5996001 1.64624961 2.5988002 1.64291624 1 P 0 ;0,1,2=42,3=0.000000
L 2.5988002 1.64291624 2.59773337 1.64041604 1 P 0 ;0,1,2=42,3=0.000000
L 2.59773337 1.64041604 2.59613366 1.63833307 1 P 0 ;0,1,2=42,3=0.000000
L 2.59613366 1.63833307 2.5940003 1.6375 1 P 0 ;0,1,2=42,3=0.000000
L 2.5940003 1.6375 2.59186693 1.63833307 1 P 0 ;0,1,2=42,3=0.000000
L 2.59186693 1.63833307 2.59026673 1.64041604 1 P 0 ;0,1,2=42,3=0.000000
L 2.59026673 1.64041604 2.5891999 1.64291624 1 P 0 ;0,1,2=42,3=0.000000
L 2.5891999 1.64291624 2.5884 1.64624961 1 P 0 ;0,1,2=42,3=0.000000
L 2.5884 1.64624961 2.58813337 1.64999961 1 P 0 ;0,1,2=42,3=0.000000
L 2.58813337 1.64999961 2.5884 1.65374951 1 P 0 ;0,1,2=42,3=0.000000
L 2.5884 1.65374951 2.5891999 1.65708366 1 P 0 ;0,1,2=42,3=0.000000
L 2.5891999 1.65708366 2.59026673 1.65958317 1 P 0 ;0,1,2=42,3=0.000000
L 2.59026673 1.65958317 2.59186693 1.66166683 1 P 0 ;0,1,2=42,3=0.000000
L 2.59186693 1.66166683 2.5940003 1.6625 1 P 0 ;0,1,2=42,3=0.000000
L 2.57653366 1.64041604 2.57466683 1.63833307 1 P 0 ;0,1,2=42,3=0.000000
L 2.57466683 1.63833307 2.57253346 1.6375 1 P 0 ;0,1,2=42,3=0.000000
L 2.57253346 1.6375 2.5704001 1.63833307 1 P 0 ;0,1,2=42,3=0.000000
L 2.5704001 1.63833307 2.56853337 1.64083258 1 P 0 ;0,1,2=42,3=0.000000
L 2.56853337 1.64083258 2.5671999 1.64458327 1 P 0 ;0,1,2=42,3=0.000000
L 2.5671999 1.64458327 2.56666663 1.64833327 1 P 0 ;0,1,2=42,3=0.000000
L 2.56666663 1.64833327 2.56666663 1.65291634 1 P 0 ;0,1,2=42,3=0.000000
L 2.56666663 1.65291634 2.5671999 1.65666634 1 P 0 ;0,1,2=42,3=0.000000
L 2.5671999 1.65666634 2.56853337 1.6599997 1 P 0 ;0,1,2=42,3=0.000000
L 2.56853337 1.6599997 2.57013356 1.66166683 1 P 0 ;0,1,2=42,3=0.000000
L 2.57013356 1.66166683 2.5720003 1.6625 1 P 0 ;0,1,2=42,3=0.000000
L 2.5720003 1.6625 2.57413366 1.66166683 1 P 0 ;0,1,2=42,3=0.000000
L 2.57413366 1.66166683 2.57573337 1.6599997 1 P 0 ;0,1,2=42,3=0.000000
L 2.57573337 1.6599997 2.5768002 1.6575003 1 P 0 ;0,1,2=42,3=0.000000
L 2.5768002 1.6575003 2.57733346 1.65416614 1 P 0 ;0,1,2=42,3=0.000000
L 2.57733346 1.65416614 2.5768002 1.6512501 1 P 0 ;0,1,2=42,3=0.000000
L 2.5768002 1.6512501 2.57546673 1.64833327 1 P 0 ;0,1,2=42,3=0.000000
L 2.57546673 1.64833327 2.57386654 1.64666614 1 P 0 ;0,1,2=42,3=0.000000
L 2.57386654 1.64666614 2.5720003 1.64624961 1 P 0 ;0,1,2=42,3=0.000000
L 2.5720003 1.64624961 2.56986693 1.64708278 1 P 0 ;0,1,2=42,3=0.000000
L 2.56986693 1.64708278 2.56826673 1.64916644 1 P 0 ;0,1,2=42,3=0.000000
L 2.56826673 1.64916644 2.56666663 1.65291634 1 P 0 ;0,1,2=42,3=0.000000
L 4.18571004 1.62808002 4.18571004 1.70446004 1 P 0 
L 4.18571004 1.70446004 4.14871004 1.70446004 1 P 0 
L 4.14871004 1.70446004 4.14871004 1.62808002 1 P 0 
L 4.14871004 1.62808002 4.18571004 1.62808002 1 P 0 
L 2.54961634 1.59916663 2.55086683 1.59756644 1 P 0 ;0,1,2=43,3=90.000000
L 2.55086683 1.59756644 2.5517 1.5957002 1 P 0 ;0,1,2=43,3=90.000000
L 2.5517 1.5957002 2.5517 1.59356683 1 P 0 ;0,1,2=43,3=90.000000
L 2.5517 1.59356683 2.55044941 1.59116634 1 P 0 ;0,1,2=43,3=90.000000
L 2.55044941 1.59116634 2.54836654 1.5893001 1 P 0 ;0,1,2=43,3=90.000000
L 2.54836654 1.5893001 2.54586634 1.58796654 1 P 0 ;0,1,2=43,3=90.000000
L 2.54586634 1.58796654 2.5416998 1.58689961 1 P 0 ;0,1,2=43,3=90.000000
L 2.5416998 1.58689961 2.5379498 1.58663297 1 P 0 ;0,1,2=43,3=90.000000
L 2.5379498 1.58663297 2.5341999 1.58716673 1 P 0 ;0,1,2=43,3=90.000000
L 2.5341999 1.58716673 2.53169961 1.58796654 1 P 0 ;0,1,2=43,3=90.000000
L 2.53169961 1.58796654 2.52919941 1.58956663 1 P 0 ;0,1,2=43,3=90.000000
L 2.52919941 1.58956663 2.52753307 1.59143346 1 P 0 ;0,1,2=43,3=90.000000
L 2.52753307 1.59143346 2.5267 1.5932997 1 P 0 ;0,1,2=43,3=90.000000
L 2.5267 1.5932997 2.5267 1.59516644 1 P 0 ;0,1,2=43,3=90.000000
L 2.5267 1.59516644 2.52753307 1.59703327 1 P 0 ;0,1,2=43,3=90.000000
L 2.52753307 1.59703327 2.52878287 1.59863337 1 P 0 ;0,1,2=43,3=90.000000
L 2.52878287 1.59863337 2.53044911 1.59996693 1 P 0 ;0,1,2=43,3=90.000000
L 2.5267 1.6152997 2.5517 1.6152997 1 P 0 ;0,1,2=43,3=90.000000
L 2.5517 1.6152997 2.5467003 1.6120999 1 P 0 ;0,1,2=43,3=90.000000
L 2.5267 1.6120999 2.5267 1.61849951 1 P 0 ;0,1,2=43,3=90.000000
L 2.53044911 1.63143327 2.52836624 1.63303297 1 P 0 ;0,1,2=43,3=90.000000
L 2.52836624 1.63303297 2.52711654 1.6348997 1 P 0 ;0,1,2=43,3=90.000000
L 2.52711654 1.6348997 2.5267 1.6372997 1 P 0 ;0,1,2=43,3=90.000000
L 2.5267 1.6372997 2.52753307 1.6397002 1 P 0 ;0,1,2=43,3=90.000000
L 2.52753307 1.6397002 2.52919941 1.64156644 1 P 0 ;0,1,2=43,3=90.000000
L 2.52919941 1.64156644 2.53211624 1.6429 1 P 0 ;0,1,2=43,3=90.000000
L 2.53211624 1.6429 2.53544961 1.64316663 1 P 0 ;0,1,2=43,3=90.000000
L 2.53544961 1.64316663 2.53878297 1.64263337 1 P 0 ;0,1,2=43,3=90.000000
L 2.53878297 1.64263337 2.54086663 1.6412998 1 P 0 ;0,1,2=43,3=90.000000
L 2.54086663 1.6412998 2.54253297 1.63943307 1 P 0 ;0,1,2=43,3=90.000000
L 2.54253297 1.63943307 2.54294951 1.63756683 1 P 0 ;0,1,2=43,3=90.000000
L 2.54294951 1.63756683 2.54253297 1.6357 1 P 0 ;0,1,2=43,3=90.000000
L 2.54253297 1.6357 2.54086663 1.6333001 1 P 0 ;0,1,2=43,3=90.000000
L 2.54086663 1.6333001 2.5517 1.6340999 1 P 0 ;0,1,2=43,3=90.000000
L 2.5517 1.6340999 2.5517 1.6412998 1 P 0 ;0,1,2=43,3=90.000000
L 2.53711594 1.65423317 2.54003346 1.6560999 1 P 0 ;0,1,2=43,3=90.000000
L 2.54003346 1.6560999 2.5416998 1.6577 1 P 0 ;0,1,2=43,3=90.000000
L 2.5416998 1.6577 2.54253297 1.65983337 1 P 0 ;0,1,2=43,3=90.000000
L 2.54253297 1.65983337 2.5416998 1.6617002 1 P 0 ;0,1,2=43,3=90.000000
L 2.5416998 1.6617002 2.54003346 1.66303327 1 P 0 ;0,1,2=43,3=90.000000
L 2.54003346 1.66303327 2.53753327 1.6641001 1 P 0 ;0,1,2=43,3=90.000000
L 2.53753327 1.6641001 2.53461644 1.66436673 1 P 0 ;0,1,2=43,3=90.000000
L 2.53461644 1.66436673 2.53211624 1.6641001 1 P 0 ;0,1,2=43,3=90.000000
L 2.53211624 1.6641001 2.52961604 1.66303327 1 P 0 ;0,1,2=43,3=90.000000
L 2.52961604 1.66303327 2.52753307 1.66143307 1 P 0 ;0,1,2=43,3=90.000000
L 2.52753307 1.66143307 2.5267 1.65956683 1 P 0 ;0,1,2=43,3=90.000000
L 2.5267 1.65956683 2.52753307 1.65743346 1 P 0 ;0,1,2=43,3=90.000000
L 2.52753307 1.65743346 2.53003258 1.65556663 1 P 0 ;0,1,2=43,3=90.000000
L 2.53003258 1.65556663 2.53378327 1.6544998 1 P 0 ;0,1,2=43,3=90.000000
L 2.53378327 1.6544998 2.5379498 1.65423317 1 P 0 ;0,1,2=43,3=90.000000
L 2.5379498 1.65423317 2.54336614 1.65476634 1 P 0 ;0,1,2=43,3=90.000000
L 2.54336614 1.65476634 2.54628366 1.65556663 1 P 0 ;0,1,2=43,3=90.000000
L 2.54628366 1.65556663 2.5491997 1.6568997 1 P 0 ;0,1,2=43,3=90.000000
L 2.5491997 1.6568997 2.55128337 1.65876654 1 P 0 ;0,1,2=43,3=90.000000
L 2.55128337 1.65876654 2.5517 1.66063327 1 P 0 ;0,1,2=43,3=90.000000
L 2.5517 1.66063327 2.55086683 1.6625 1 P 0 ;0,1,2=43,3=90.000000
L 2.55086683 1.6625 2.54878317 1.66383356 1 P 0 ;0,1,2=43,3=90.000000
L 4.26445 1.66508996 4.22745 1.66508996 1 P 0 
L 4.26445 1.58871004 4.26445 1.66508996 1 P 0 
L 4.22745 1.66508996 4.22745 1.58871004 1 P 0 
L 4.22745 1.58871004 4.26445 1.58871004 1 P 0 
L 2.62831634 1.55976663 2.62956683 1.55816644 1 P 0 ;0,1,2=44,3=90.000000
L 2.62956683 1.55816644 2.6304 1.5563002 1 P 0 ;0,1,2=44,3=90.000000
L 2.6304 1.5563002 2.6304 1.55416683 1 P 0 ;0,1,2=44,3=90.000000
L 2.6304 1.55416683 2.62914941 1.55176634 1 P 0 ;0,1,2=44,3=90.000000
L 2.62914941 1.55176634 2.62706654 1.5499001 1 P 0 ;0,1,2=44,3=90.000000
L 2.62706654 1.5499001 2.62456634 1.54856654 1 P 0 ;0,1,2=44,3=90.000000
L 2.62456634 1.54856654 2.6203998 1.54749961 1 P 0 ;0,1,2=44,3=90.000000
L 2.6203998 1.54749961 2.6166498 1.54723297 1 P 0 ;0,1,2=44,3=90.000000
L 2.6166498 1.54723297 2.6128999 1.54776673 1 P 0 ;0,1,2=44,3=90.000000
L 2.6128999 1.54776673 2.61039961 1.54856654 1 P 0 ;0,1,2=44,3=90.000000
L 2.61039961 1.54856654 2.60789941 1.55016663 1 P 0 ;0,1,2=44,3=90.000000
L 2.60789941 1.55016663 2.60623307 1.55203346 1 P 0 ;0,1,2=44,3=90.000000
L 2.60623307 1.55203346 2.6054 1.5538997 1 P 0 ;0,1,2=44,3=90.000000
L 2.6054 1.5538997 2.6054 1.55576644 1 P 0 ;0,1,2=44,3=90.000000
L 2.6054 1.55576644 2.60623307 1.55763327 1 P 0 ;0,1,2=44,3=90.000000
L 2.60623307 1.55763327 2.60748287 1.55923337 1 P 0 ;0,1,2=44,3=90.000000
L 2.60748287 1.55923337 2.60914911 1.56056693 1 P 0 ;0,1,2=44,3=90.000000
L 2.6054 1.5758997 2.6304 1.5758997 1 P 0 ;0,1,2=44,3=90.000000
L 2.6304 1.5758997 2.6254003 1.5726999 1 P 0 ;0,1,2=44,3=90.000000
L 2.6054 1.5726999 2.6054 1.57909951 1 P 0 ;0,1,2=44,3=90.000000
L 2.61581594 1.59283317 2.61873346 1.5946999 1 P 0 ;0,1,2=44,3=90.000000
L 2.61873346 1.5946999 2.6203998 1.5963 1 P 0 ;0,1,2=44,3=90.000000
L 2.6203998 1.5963 2.62123297 1.59843337 1 P 0 ;0,1,2=44,3=90.000000
L 2.62123297 1.59843337 2.6203998 1.6003002 1 P 0 ;0,1,2=44,3=90.000000
L 2.6203998 1.6003002 2.61873346 1.60163327 1 P 0 ;0,1,2=44,3=90.000000
L 2.61873346 1.60163327 2.61623327 1.6027001 1 P 0 ;0,1,2=44,3=90.000000
L 2.61623327 1.6027001 2.61331644 1.60296673 1 P 0 ;0,1,2=44,3=90.000000
L 2.61331644 1.60296673 2.61081624 1.6027001 1 P 0 ;0,1,2=44,3=90.000000
L 2.61081624 1.6027001 2.60831604 1.60163327 1 P 0 ;0,1,2=44,3=90.000000
L 2.60831604 1.60163327 2.60623307 1.60003307 1 P 0 ;0,1,2=44,3=90.000000
L 2.60623307 1.60003307 2.6054 1.59816683 1 P 0 ;0,1,2=44,3=90.000000
L 2.6054 1.59816683 2.60623307 1.59603346 1 P 0 ;0,1,2=44,3=90.000000
L 2.60623307 1.59603346 2.60873258 1.59416663 1 P 0 ;0,1,2=44,3=90.000000
L 2.60873258 1.59416663 2.61248327 1.5930998 1 P 0 ;0,1,2=44,3=90.000000
L 2.61248327 1.5930998 2.6166498 1.59283317 1 P 0 ;0,1,2=44,3=90.000000
L 2.6166498 1.59283317 2.62206614 1.59336634 1 P 0 ;0,1,2=44,3=90.000000
L 2.62206614 1.59336634 2.62498366 1.59416663 1 P 0 ;0,1,2=44,3=90.000000
L 2.62498366 1.59416663 2.6278997 1.5954997 1 P 0 ;0,1,2=44,3=90.000000
L 2.6278997 1.5954997 2.62998337 1.59736654 1 P 0 ;0,1,2=44,3=90.000000
L 2.62998337 1.59736654 2.6304 1.59923327 1 P 0 ;0,1,2=44,3=90.000000
L 2.6304 1.59923327 2.62956683 1.6011 1 P 0 ;0,1,2=44,3=90.000000
L 2.62956683 1.6011 2.62748317 1.60243356 1 P 0 ;0,1,2=44,3=90.000000
L 2.61581594 1.61483317 2.61873346 1.6166999 1 P 0 ;0,1,2=44,3=90.000000
L 2.61873346 1.6166999 2.6203998 1.6183 1 P 0 ;0,1,2=44,3=90.000000
L 2.6203998 1.6183 2.62123297 1.62043337 1 P 0 ;0,1,2=44,3=90.000000
L 2.62123297 1.62043337 2.6203998 1.6223002 1 P 0 ;0,1,2=44,3=90.000000
L 2.6203998 1.6223002 2.61873346 1.62363327 1 P 0 ;0,1,2=44,3=90.000000
L 2.61873346 1.62363327 2.61623327 1.6247001 1 P 0 ;0,1,2=44,3=90.000000
L 2.61623327 1.6247001 2.61331644 1.62496673 1 P 0 ;0,1,2=44,3=90.000000
L 2.61331644 1.62496673 2.61081624 1.6247001 1 P 0 ;0,1,2=44,3=90.000000
L 2.61081624 1.6247001 2.60831604 1.62363327 1 P 0 ;0,1,2=44,3=90.000000
L 2.60831604 1.62363327 2.60623307 1.62203307 1 P 0 ;0,1,2=44,3=90.000000
L 2.60623307 1.62203307 2.6054 1.62016683 1 P 0 ;0,1,2=44,3=90.000000
L 2.6054 1.62016683 2.60623307 1.61803346 1 P 0 ;0,1,2=44,3=90.000000
L 2.60623307 1.61803346 2.60873258 1.61616663 1 P 0 ;0,1,2=44,3=90.000000
L 2.60873258 1.61616663 2.61248327 1.6150998 1 P 0 ;0,1,2=44,3=90.000000
L 2.61248327 1.6150998 2.6166498 1.61483317 1 P 0 ;0,1,2=44,3=90.000000
L 2.6166498 1.61483317 2.62206614 1.61536634 1 P 0 ;0,1,2=44,3=90.000000
L 2.62206614 1.61536634 2.62498366 1.61616663 1 P 0 ;0,1,2=44,3=90.000000
L 2.62498366 1.61616663 2.6278997 1.6174997 1 P 0 ;0,1,2=44,3=90.000000
L 2.6278997 1.6174997 2.62998337 1.61936654 1 P 0 ;0,1,2=44,3=90.000000
L 2.62998337 1.61936654 2.6304 1.62123327 1 P 0 ;0,1,2=44,3=90.000000
L 2.6304 1.62123327 2.62956683 1.6231 1 P 0 ;0,1,2=44,3=90.000000
L 2.62956683 1.6231 2.62748317 1.62443356 1 P 0 ;0,1,2=44,3=90.000000
L 4.18808002 1.54696998 4.18808002 1.47058996 1 P 0 
L 4.18808002 1.47058996 4.22508002 1.47058996 1 P 0 
L 4.22508002 1.47058996 4.22508002 1.54696998 1 P 0 
L 4.22508002 1.54696998 4.18808002 1.54696998 1 P 0 
L 2.58401634 1.43166663 2.58526683 1.43006644 1 P 0 ;0,1,2=45,3=90.000000
L 2.58526683 1.43006644 2.5861 1.4282002 1 P 0 ;0,1,2=45,3=90.000000
L 2.5861 1.4282002 2.5861 1.42606683 1 P 0 ;0,1,2=45,3=90.000000
L 2.5861 1.42606683 2.58484941 1.42366634 1 P 0 ;0,1,2=45,3=90.000000
L 2.58484941 1.42366634 2.58276654 1.4218001 1 P 0 ;0,1,2=45,3=90.000000
L 2.58276654 1.4218001 2.58026634 1.42046654 1 P 0 ;0,1,2=45,3=90.000000
L 2.58026634 1.42046654 2.5760998 1.41939961 1 P 0 ;0,1,2=45,3=90.000000
L 2.5760998 1.41939961 2.5723498 1.41913297 1 P 0 ;0,1,2=45,3=90.000000
L 2.5723498 1.41913297 2.5685999 1.41966673 1 P 0 ;0,1,2=45,3=90.000000
L 2.5685999 1.41966673 2.56609961 1.42046654 1 P 0 ;0,1,2=45,3=90.000000
L 2.56609961 1.42046654 2.56359941 1.42206663 1 P 0 ;0,1,2=45,3=90.000000
L 2.56359941 1.42206663 2.56193307 1.42393346 1 P 0 ;0,1,2=45,3=90.000000
L 2.56193307 1.42393346 2.5611 1.4257997 1 P 0 ;0,1,2=45,3=90.000000
L 2.5611 1.4257997 2.5611 1.42766644 1 P 0 ;0,1,2=45,3=90.000000
L 2.5611 1.42766644 2.56193307 1.42953327 1 P 0 ;0,1,2=45,3=90.000000
L 2.56193307 1.42953327 2.56318287 1.43113337 1 P 0 ;0,1,2=45,3=90.000000
L 2.56318287 1.43113337 2.56484911 1.43246693 1 P 0 ;0,1,2=45,3=90.000000
L 2.5611 1.4477997 2.5861 1.4477997 1 P 0 ;0,1,2=45,3=90.000000
L 2.5861 1.4477997 2.5811003 1.4445999 1 P 0 ;0,1,2=45,3=90.000000
L 2.5611 1.4445999 2.5611 1.45099951 1 P 0 ;0,1,2=45,3=90.000000
L 2.57151594 1.46473317 2.57443346 1.4665999 1 P 0 ;0,1,2=45,3=90.000000
L 2.57443346 1.4665999 2.5760998 1.4682 1 P 0 ;0,1,2=45,3=90.000000
L 2.5760998 1.4682 2.57693297 1.47033337 1 P 0 ;0,1,2=45,3=90.000000
L 2.57693297 1.47033337 2.5760998 1.4722002 1 P 0 ;0,1,2=45,3=90.000000
L 2.5760998 1.4722002 2.57443346 1.47353327 1 P 0 ;0,1,2=45,3=90.000000
L 2.57443346 1.47353327 2.57193327 1.4746001 1 P 0 ;0,1,2=45,3=90.000000
L 2.57193327 1.4746001 2.56901644 1.47486673 1 P 0 ;0,1,2=45,3=90.000000
L 2.56901644 1.47486673 2.56651624 1.4746001 1 P 0 ;0,1,2=45,3=90.000000
L 2.56651624 1.4746001 2.56401604 1.47353327 1 P 0 ;0,1,2=45,3=90.000000
L 2.56401604 1.47353327 2.56193307 1.47193307 1 P 0 ;0,1,2=45,3=90.000000
L 2.56193307 1.47193307 2.5611 1.47006683 1 P 0 ;0,1,2=45,3=90.000000
L 2.5611 1.47006683 2.56193307 1.46793346 1 P 0 ;0,1,2=45,3=90.000000
L 2.56193307 1.46793346 2.56443258 1.46606663 1 P 0 ;0,1,2=45,3=90.000000
L 2.56443258 1.46606663 2.56818327 1.4649998 1 P 0 ;0,1,2=45,3=90.000000
L 2.56818327 1.4649998 2.5723498 1.46473317 1 P 0 ;0,1,2=45,3=90.000000
L 2.5723498 1.46473317 2.57776614 1.46526634 1 P 0 ;0,1,2=45,3=90.000000
L 2.57776614 1.46526634 2.58068366 1.46606663 1 P 0 ;0,1,2=45,3=90.000000
L 2.58068366 1.46606663 2.5835997 1.4673997 1 P 0 ;0,1,2=45,3=90.000000
L 2.5835997 1.4673997 2.58568337 1.46926654 1 P 0 ;0,1,2=45,3=90.000000
L 2.58568337 1.46926654 2.5861 1.47113327 1 P 0 ;0,1,2=45,3=90.000000
L 2.5861 1.47113327 2.58526683 1.473 1 P 0 ;0,1,2=45,3=90.000000
L 2.58526683 1.473 2.58318317 1.47433356 1 P 0 ;0,1,2=45,3=90.000000
L 2.56401604 1.48726634 2.56193307 1.48913317 1 P 0 ;0,1,2=45,3=90.000000
L 2.56193307 1.48913317 2.5611 1.49126654 1 P 0 ;0,1,2=45,3=90.000000
L 2.5611 1.49126654 2.56193307 1.4933999 1 P 0 ;0,1,2=45,3=90.000000
L 2.56193307 1.4933999 2.56443258 1.49526663 1 P 0 ;0,1,2=45,3=90.000000
L 2.56443258 1.49526663 2.56818327 1.4966001 1 P 0 ;0,1,2=45,3=90.000000
L 2.56818327 1.4966001 2.57193327 1.49713337 1 P 0 ;0,1,2=45,3=90.000000
L 2.57193327 1.49713337 2.57651634 1.49713337 1 P 0 ;0,1,2=45,3=90.000000
L 2.57651634 1.49713337 2.58026634 1.4966001 1 P 0 ;0,1,2=45,3=90.000000
L 2.58026634 1.4966001 2.5835997 1.49526663 1 P 0 ;0,1,2=45,3=90.000000
L 2.5835997 1.49526663 2.58526683 1.49366644 1 P 0 ;0,1,2=45,3=90.000000
L 2.58526683 1.49366644 2.5861 1.4917997 1 P 0 ;0,1,2=45,3=90.000000
L 2.5861 1.4917997 2.58526683 1.48966634 1 P 0 ;0,1,2=45,3=90.000000
L 2.58526683 1.48966634 2.5835997 1.48806663 1 P 0 ;0,1,2=45,3=90.000000
L 2.5835997 1.48806663 2.5811003 1.4869998 1 P 0 ;0,1,2=45,3=90.000000
L 2.5811003 1.4869998 2.57776614 1.48646654 1 P 0 ;0,1,2=45,3=90.000000
L 2.57776614 1.48646654 2.5748501 1.4869998 1 P 0 ;0,1,2=45,3=90.000000
L 2.5748501 1.4869998 2.57193327 1.48833327 1 P 0 ;0,1,2=45,3=90.000000
L 2.57193327 1.48833327 2.57026614 1.48993346 1 P 0 ;0,1,2=45,3=90.000000
L 2.57026614 1.48993346 2.56984961 1.4917997 1 P 0 ;0,1,2=45,3=90.000000
L 2.56984961 1.4917997 2.57068278 1.49393307 1 P 0 ;0,1,2=45,3=90.000000
L 2.57068278 1.49393307 2.57276644 1.49553327 1 P 0 ;0,1,2=45,3=90.000000
L 2.57276644 1.49553327 2.57651634 1.49713337 1 P 0 ;0,1,2=45,3=90.000000
L 4.22508002 1.46823002 4.18808002 1.46823002 1 P 0 
L 4.22508002 1.39185 4.22508002 1.46823002 1 P 0 
L 4.18808002 1.46823002 4.18808002 1.39185 1 P 0 
L 4.18808002 1.39185 4.22508002 1.39185 1 P 0 
L 2.58041634 1.34286663 2.58166683 1.34126644 1 P 0 ;0,1,2=46,3=90.000000
L 2.58166683 1.34126644 2.5825 1.3394002 1 P 0 ;0,1,2=46,3=90.000000
L 2.5825 1.3394002 2.5825 1.33726683 1 P 0 ;0,1,2=46,3=90.000000
L 2.5825 1.33726683 2.58124941 1.33486634 1 P 0 ;0,1,2=46,3=90.000000
L 2.58124941 1.33486634 2.57916654 1.3330001 1 P 0 ;0,1,2=46,3=90.000000
L 2.57916654 1.3330001 2.57666634 1.33166654 1 P 0 ;0,1,2=46,3=90.000000
L 2.57666634 1.33166654 2.5724998 1.33059961 1 P 0 ;0,1,2=46,3=90.000000
L 2.5724998 1.33059961 2.5687498 1.33033297 1 P 0 ;0,1,2=46,3=90.000000
L 2.5687498 1.33033297 2.5649999 1.33086673 1 P 0 ;0,1,2=46,3=90.000000
L 2.5649999 1.33086673 2.56249961 1.33166654 1 P 0 ;0,1,2=46,3=90.000000
L 2.56249961 1.33166654 2.55999941 1.33326663 1 P 0 ;0,1,2=46,3=90.000000
L 2.55999941 1.33326663 2.55833307 1.33513346 1 P 0 ;0,1,2=46,3=90.000000
L 2.55833307 1.33513346 2.5575 1.3369997 1 P 0 ;0,1,2=46,3=90.000000
L 2.5575 1.3369997 2.5575 1.33886644 1 P 0 ;0,1,2=46,3=90.000000
L 2.5575 1.33886644 2.55833307 1.34073327 1 P 0 ;0,1,2=46,3=90.000000
L 2.55833307 1.34073327 2.55958287 1.34233337 1 P 0 ;0,1,2=46,3=90.000000
L 2.55958287 1.34233337 2.56124911 1.34366693 1 P 0 ;0,1,2=46,3=90.000000
L 2.57833337 1.35393317 2.58083287 1.35553327 1 P 0 ;0,1,2=46,3=90.000000
L 2.58083287 1.35553327 2.58208337 1.3574 1 P 0 ;0,1,2=46,3=90.000000
L 2.58208337 1.3574 2.5825 1.35953337 1 P 0 ;0,1,2=46,3=90.000000
L 2.5825 1.35953337 2.58166683 1.3622 1 P 0 ;0,1,2=46,3=90.000000
L 2.58166683 1.3622 2.57958317 1.36406673 1 P 0 ;0,1,2=46,3=90.000000
L 2.57958317 1.36406673 2.57708366 1.3646 1 P 0 ;0,1,2=46,3=90.000000
L 2.57708366 1.3646 2.57458268 1.36433337 1 P 0 ;0,1,2=46,3=90.000000
L 2.57458268 1.36433337 2.5724998 1.36326644 1 P 0 ;0,1,2=46,3=90.000000
L 2.5724998 1.36326644 2.56833327 1.35793327 1 P 0 ;0,1,2=46,3=90.000000
L 2.56833327 1.35793327 2.56541644 1.35553327 1 P 0 ;0,1,2=46,3=90.000000
L 2.56541644 1.35553327 2.56124911 1.35393317 1 P 0 ;0,1,2=46,3=90.000000
L 2.56124911 1.35393317 2.5575 1.3533999 1 P 0 ;0,1,2=46,3=90.000000
L 2.5575 1.3533999 2.5575 1.3646 1 P 0 ;0,1,2=46,3=90.000000
L 2.5825 1.3809997 2.58166683 1.37886634 1 P 0 ;0,1,2=46,3=90.000000
L 2.58166683 1.37886634 2.57958317 1.37726663 1 P 0 ;0,1,2=46,3=90.000000
L 2.57958317 1.37726663 2.57708366 1.3761998 1 P 0 ;0,1,2=46,3=90.000000
L 2.57708366 1.3761998 2.57374951 1.3753999 1 P 0 ;0,1,2=46,3=90.000000
L 2.57374951 1.3753999 2.56999961 1.37513327 1 P 0 ;0,1,2=46,3=90.000000
L 2.56999961 1.37513327 2.56624961 1.3753999 1 P 0 ;0,1,2=46,3=90.000000
L 2.56624961 1.3753999 2.56291624 1.3761998 1 P 0 ;0,1,2=46,3=90.000000
L 2.56291624 1.3761998 2.56041604 1.37726663 1 P 0 ;0,1,2=46,3=90.000000
L 2.56041604 1.37726663 2.55833307 1.37886634 1 P 0 ;0,1,2=46,3=90.000000
L 2.55833307 1.37886634 2.5575 1.3809997 1 P 0 ;0,1,2=46,3=90.000000
L 2.5575 1.3809997 2.55833307 1.38313307 1 P 0 ;0,1,2=46,3=90.000000
L 2.55833307 1.38313307 2.56041604 1.38473327 1 P 0 ;0,1,2=46,3=90.000000
L 2.56041604 1.38473327 2.56291624 1.3858001 1 P 0 ;0,1,2=46,3=90.000000
L 2.56291624 1.3858001 2.56624961 1.3866 1 P 0 ;0,1,2=46,3=90.000000
L 2.56624961 1.3866 2.56999961 1.38686663 1 P 0 ;0,1,2=46,3=90.000000
L 2.56999961 1.38686663 2.57374951 1.3866 1 P 0 ;0,1,2=46,3=90.000000
L 2.57374951 1.3866 2.57708366 1.3858001 1 P 0 ;0,1,2=46,3=90.000000
L 2.57708366 1.3858001 2.57958317 1.38473327 1 P 0 ;0,1,2=46,3=90.000000
L 2.57958317 1.38473327 2.58166683 1.38313307 1 P 0 ;0,1,2=46,3=90.000000
L 2.58166683 1.38313307 2.5825 1.3809997 1 P 0 ;0,1,2=46,3=90.000000
L 2.5575 1.4029997 2.55791654 1.40486644 1 P 0 ;0,1,2=46,3=90.000000
L 2.55791654 1.40486644 2.55916624 1.4069998 1 P 0 ;0,1,2=46,3=90.000000
L 2.55916624 1.4069998 2.56124911 1.40833337 1 P 0 ;0,1,2=46,3=90.000000
L 2.56124911 1.40833337 2.56416673 1.40886663 1 P 0 ;0,1,2=46,3=90.000000
L 2.56416673 1.40886663 2.56708278 1.40833337 1 P 0 ;0,1,2=46,3=90.000000
L 2.56708278 1.40833337 2.56958297 1.40673327 1 P 0 ;0,1,2=46,3=90.000000
L 2.56958297 1.40673327 2.57083346 1.40433327 1 P 0 ;0,1,2=46,3=90.000000
L 2.57083346 1.40433327 2.57083346 1.40166663 1 P 0 ;0,1,2=46,3=90.000000
L 2.57083346 1.40166663 2.57166663 1.40006654 1 P 0 ;0,1,2=46,3=90.000000
L 2.57166663 1.40006654 2.57374951 1.39873297 1 P 0 ;0,1,2=46,3=90.000000
L 2.57374951 1.39873297 2.57666634 1.3981998 1 P 0 ;0,1,2=46,3=90.000000
L 2.57666634 1.3981998 2.57958317 1.3990001 1 P 0 ;0,1,2=46,3=90.000000
L 2.57958317 1.3990001 2.58166683 1.40086634 1 P 0 ;0,1,2=46,3=90.000000
L 2.58166683 1.40086634 2.5825 1.4029997 1 P 0 ;0,1,2=46,3=90.000000
L 2.5825 1.4029997 2.58166683 1.40513307 1 P 0 ;0,1,2=46,3=90.000000
L 2.58166683 1.40513307 2.57958317 1.4069998 1 P 0 ;0,1,2=46,3=90.000000
L 2.57958317 1.4069998 2.57666634 1.4078001 1 P 0 ;0,1,2=46,3=90.000000
L 2.57666634 1.4078001 2.57374951 1.40726644 1 P 0 ;0,1,2=46,3=90.000000
L 2.57374951 1.40726644 2.57166663 1.40593337 1 P 0 ;0,1,2=46,3=90.000000
L 2.57166663 1.40593337 2.57083346 1.40433327 1 P 0 ;0,1,2=46,3=90.000000
L 2.57083346 1.40433327 2.57083346 1.40166663 1 P 0 ;0,1,2=46,3=90.000000
L 2.57083346 1.40166663 2.56958297 1.39926663 1 P 0 ;0,1,2=46,3=90.000000
L 2.56958297 1.39926663 2.56708278 1.39766654 1 P 0 ;0,1,2=46,3=90.000000
L 2.56708278 1.39766654 2.56416673 1.39713327 1 P 0 ;0,1,2=46,3=90.000000
L 2.56416673 1.39713327 2.56124911 1.39766654 1 P 0 ;0,1,2=46,3=90.000000
L 2.56124911 1.39766654 2.55916624 1.3990001 1 P 0 ;0,1,2=46,3=90.000000
L 2.55916624 1.3990001 2.55791654 1.40113346 1 P 0 ;0,1,2=46,3=90.000000
L 2.55791654 1.40113346 2.5575 1.4029997 1 P 0 ;0,1,2=46,3=90.000000
L 4.18571004 1.50996998 4.18571004 1.54696998 1 P 0 
L 4.18571004 1.54696998 4.10933002 1.54696998 1 P 0 
L 4.10933002 1.54696998 4.10933002 1.50996998 1 P 0 
L 4.10933002 1.50996998 4.18571004 1.50996998 1 P 0 
L 2.53463337 1.48591634 2.53623356 1.48716683 1 P 0 ;0,1,2=47,3=0.000000
L 2.53623356 1.48716683 2.5380998 1.488 1 P 0 ;0,1,2=47,3=0.000000
L 2.5380998 1.488 2.54023317 1.488 1 P 0 ;0,1,2=47,3=0.000000
L 2.54023317 1.488 2.54263366 1.48674941 1 P 0 ;0,1,2=47,3=0.000000
L 2.54263366 1.48674941 2.5444999 1.48466654 1 P 0 ;0,1,2=47,3=0.000000
L 2.5444999 1.48466654 2.54583346 1.48216634 1 P 0 ;0,1,2=47,3=0.000000
L 2.54583346 1.48216634 2.54690039 1.4779998 1 P 0 ;0,1,2=47,3=0.000000
L 2.54690039 1.4779998 2.54716703 1.4742498 1 P 0 ;0,1,2=47,3=0.000000
L 2.54716703 1.4742498 2.54663327 1.4704999 1 P 0 ;0,1,2=47,3=0.000000
L 2.54663327 1.4704999 2.54583346 1.46799961 1 P 0 ;0,1,2=47,3=0.000000
L 2.54583346 1.46799961 2.54423337 1.46549941 1 P 0 ;0,1,2=47,3=0.000000
L 2.54423337 1.46549941 2.54236654 1.46383307 1 P 0 ;0,1,2=47,3=0.000000
L 2.54236654 1.46383307 2.5405003 1.463 1 P 0 ;0,1,2=47,3=0.000000
L 2.5405003 1.463 2.53863356 1.463 1 P 0 ;0,1,2=47,3=0.000000
L 2.53863356 1.463 2.53676673 1.46383307 1 P 0 ;0,1,2=47,3=0.000000
L 2.53676673 1.46383307 2.53516663 1.46508287 1 P 0 ;0,1,2=47,3=0.000000
L 2.53516663 1.46508287 2.53383307 1.46674911 1 P 0 ;0,1,2=47,3=0.000000
L 2.52356683 1.48383337 2.52196673 1.48633287 1 P 0 ;0,1,2=47,3=0.000000
L 2.52196673 1.48633287 2.5201 1.48758337 1 P 0 ;0,1,2=47,3=0.000000
L 2.5201 1.48758337 2.51796663 1.488 1 P 0 ;0,1,2=47,3=0.000000
L 2.51796663 1.488 2.5153 1.48716683 1 P 0 ;0,1,2=47,3=0.000000
L 2.5153 1.48716683 2.51343327 1.48508317 1 P 0 ;0,1,2=47,3=0.000000
L 2.51343327 1.48508317 2.5129 1.48258366 1 P 0 ;0,1,2=47,3=0.000000
L 2.5129 1.48258366 2.51316663 1.48008268 1 P 0 ;0,1,2=47,3=0.000000
L 2.51316663 1.48008268 2.51423356 1.4779998 1 P 0 ;0,1,2=47,3=0.000000
L 2.51423356 1.4779998 2.51956673 1.47383327 1 P 0 ;0,1,2=47,3=0.000000
L 2.51956673 1.47383327 2.52196673 1.47091644 1 P 0 ;0,1,2=47,3=0.000000
L 2.52196673 1.47091644 2.52356683 1.46674911 1 P 0 ;0,1,2=47,3=0.000000
L 2.52356683 1.46674911 2.5241001 1.463 1 P 0 ;0,1,2=47,3=0.000000
L 2.5241001 1.463 2.5129 1.463 1 P 0 ;0,1,2=47,3=0.000000
L 2.4965003 1.488 2.49863366 1.48716683 1 P 0 ;0,1,2=47,3=0.000000
L 2.49863366 1.48716683 2.50023337 1.48508317 1 P 0 ;0,1,2=47,3=0.000000
L 2.50023337 1.48508317 2.5013002 1.48258366 1 P 0 ;0,1,2=47,3=0.000000
L 2.5013002 1.48258366 2.5021001 1.47924951 1 P 0 ;0,1,2=47,3=0.000000
L 2.5021001 1.47924951 2.50236673 1.47549961 1 P 0 ;0,1,2=47,3=0.000000
L 2.50236673 1.47549961 2.5021001 1.47174961 1 P 0 ;0,1,2=47,3=0.000000
L 2.5021001 1.47174961 2.5013002 1.46841624 1 P 0 ;0,1,2=47,3=0.000000
L 2.5013002 1.46841624 2.50023337 1.46591604 1 P 0 ;0,1,2=47,3=0.000000
L 2.50023337 1.46591604 2.49863366 1.46383307 1 P 0 ;0,1,2=47,3=0.000000
L 2.49863366 1.46383307 2.4965003 1.463 1 P 0 ;0,1,2=47,3=0.000000
L 2.4965003 1.463 2.49436693 1.46383307 1 P 0 ;0,1,2=47,3=0.000000
L 2.49436693 1.46383307 2.49276673 1.46591604 1 P 0 ;0,1,2=47,3=0.000000
L 2.49276673 1.46591604 2.4916999 1.46841624 1 P 0 ;0,1,2=47,3=0.000000
L 2.4916999 1.46841624 2.4909 1.47174961 1 P 0 ;0,1,2=47,3=0.000000
L 2.4909 1.47174961 2.49063337 1.47549961 1 P 0 ;0,1,2=47,3=0.000000
L 2.49063337 1.47549961 2.4909 1.47924951 1 P 0 ;0,1,2=47,3=0.000000
L 2.4909 1.47924951 2.4916999 1.48258366 1 P 0 ;0,1,2=47,3=0.000000
L 2.4916999 1.48258366 2.49276673 1.48508317 1 P 0 ;0,1,2=47,3=0.000000
L 2.49276673 1.48508317 2.49436693 1.48716683 1 P 0 ;0,1,2=47,3=0.000000
L 2.49436693 1.48716683 2.4965003 1.488 1 P 0 ;0,1,2=47,3=0.000000
L 2.4713 1.463 2.4713 1.488 1 P 0 ;0,1,2=47,3=0.000000
L 2.4713 1.488 2.48116703 1.47008327 1 P 0 ;0,1,2=47,3=0.000000
L 2.48116703 1.47008327 2.46783307 1.47008327 1 P 0 ;0,1,2=47,3=0.000000
L 4.18571004 1.4706 4.18571004 1.5076 1 P 0 
L 4.18571004 1.5076 4.10933002 1.5076 1 P 0 
L 4.10933002 1.5076 4.10933002 1.4706 1 P 0 
L 4.10933002 1.4706 4.18571004 1.4706 1 P 0 
L 2.53463337 1.44651634 2.53623356 1.44776683 1 P 0 ;0,1,2=48,3=0.000000
L 2.53623356 1.44776683 2.5380998 1.4486 1 P 0 ;0,1,2=48,3=0.000000
L 2.5380998 1.4486 2.54023317 1.4486 1 P 0 ;0,1,2=48,3=0.000000
L 2.54023317 1.4486 2.54263366 1.44734941 1 P 0 ;0,1,2=48,3=0.000000
L 2.54263366 1.44734941 2.5444999 1.44526654 1 P 0 ;0,1,2=48,3=0.000000
L 2.5444999 1.44526654 2.54583346 1.44276634 1 P 0 ;0,1,2=48,3=0.000000
L 2.54583346 1.44276634 2.54690039 1.4385998 1 P 0 ;0,1,2=48,3=0.000000
L 2.54690039 1.4385998 2.54716703 1.4348498 1 P 0 ;0,1,2=48,3=0.000000
L 2.54716703 1.4348498 2.54663327 1.4310999 1 P 0 ;0,1,2=48,3=0.000000
L 2.54663327 1.4310999 2.54583346 1.42859961 1 P 0 ;0,1,2=48,3=0.000000
L 2.54583346 1.42859961 2.54423337 1.42609941 1 P 0 ;0,1,2=48,3=0.000000
L 2.54423337 1.42609941 2.54236654 1.42443307 1 P 0 ;0,1,2=48,3=0.000000
L 2.54236654 1.42443307 2.5405003 1.4236 1 P 0 ;0,1,2=48,3=0.000000
L 2.5405003 1.4236 2.53863356 1.4236 1 P 0 ;0,1,2=48,3=0.000000
L 2.53863356 1.4236 2.53676673 1.42443307 1 P 0 ;0,1,2=48,3=0.000000
L 2.53676673 1.42443307 2.53516663 1.42568287 1 P 0 ;0,1,2=48,3=0.000000
L 2.53516663 1.42568287 2.53383307 1.42734911 1 P 0 ;0,1,2=48,3=0.000000
L 2.5185003 1.4236 2.5185003 1.4486 1 P 0 ;0,1,2=48,3=0.000000
L 2.5185003 1.4486 2.5217001 1.4436003 1 P 0 ;0,1,2=48,3=0.000000
L 2.5217001 1.4236 2.51530049 1.4236 1 P 0 ;0,1,2=48,3=0.000000
L 2.4933 1.4236 2.4933 1.4486 1 P 0 ;0,1,2=48,3=0.000000
L 2.4933 1.4486 2.50316703 1.43068327 1 P 0 ;0,1,2=48,3=0.000000
L 2.50316703 1.43068327 2.48983307 1.43068327 1 P 0 ;0,1,2=48,3=0.000000
L 2.47956683 1.43401594 2.4777001 1.43693346 1 P 0 ;0,1,2=48,3=0.000000
L 2.4777001 1.43693346 2.4761 1.4385998 1 P 0 ;0,1,2=48,3=0.000000
L 2.4761 1.4385998 2.47396663 1.43943297 1 P 0 ;0,1,2=48,3=0.000000
L 2.47396663 1.43943297 2.4720998 1.4385998 1 P 0 ;0,1,2=48,3=0.000000
L 2.4720998 1.4385998 2.47076673 1.43693346 1 P 0 ;0,1,2=48,3=0.000000
L 2.47076673 1.43693346 2.4696999 1.43443327 1 P 0 ;0,1,2=48,3=0.000000
L 2.4696999 1.43443327 2.46943327 1.43151644 1 P 0 ;0,1,2=48,3=0.000000
L 2.46943327 1.43151644 2.4696999 1.42901624 1 P 0 ;0,1,2=48,3=0.000000
L 2.4696999 1.42901624 2.47076673 1.42651604 1 P 0 ;0,1,2=48,3=0.000000
L 2.47076673 1.42651604 2.47236693 1.42443307 1 P 0 ;0,1,2=48,3=0.000000
L 2.47236693 1.42443307 2.47423317 1.4236 1 P 0 ;0,1,2=48,3=0.000000
L 2.47423317 1.4236 2.47636654 1.42443307 1 P 0 ;0,1,2=48,3=0.000000
L 2.47636654 1.42443307 2.47823337 1.42693258 1 P 0 ;0,1,2=48,3=0.000000
L 2.47823337 1.42693258 2.4793002 1.43068327 1 P 0 ;0,1,2=48,3=0.000000
L 2.4793002 1.43068327 2.47956683 1.4348498 1 P 0 ;0,1,2=48,3=0.000000
L 2.47956683 1.4348498 2.47903366 1.44026614 1 P 0 ;0,1,2=48,3=0.000000
L 2.47903366 1.44026614 2.47823337 1.44318366 1 P 0 ;0,1,2=48,3=0.000000
L 2.47823337 1.44318366 2.4769003 1.4460997 1 P 0 ;0,1,2=48,3=0.000000
L 2.4769003 1.4460997 2.47503346 1.44818337 1 P 0 ;0,1,2=48,3=0.000000
L 2.47503346 1.44818337 2.47316673 1.4486 1 P 0 ;0,1,2=48,3=0.000000
L 2.47316673 1.4486 2.4713 1.44776683 1 P 0 ;0,1,2=48,3=0.000000
L 2.4713 1.44776683 2.46996644 1.44568317 1 P 0 ;0,1,2=48,3=0.000000
L 4.3275 1.50318996 4.2905 1.50318996 1 P 0 
L 4.3275 1.42681004 4.3275 1.50318996 1 P 0 
L 4.2905 1.50318996 4.2905 1.42681004 1 P 0 
L 4.2905 1.42681004 4.3275 1.42681004 1 P 0 
L 2.67641634 1.38786663 2.67766683 1.38626644 1 P 0 ;0,1,2=49,3=90.000000
L 2.67766683 1.38626644 2.6785 1.3844002 1 P 0 ;0,1,2=49,3=90.000000
L 2.6785 1.3844002 2.6785 1.38226683 1 P 0 ;0,1,2=49,3=90.000000
L 2.6785 1.38226683 2.67724941 1.37986634 1 P 0 ;0,1,2=49,3=90.000000
L 2.67724941 1.37986634 2.67516654 1.3780001 1 P 0 ;0,1,2=49,3=90.000000
L 2.67516654 1.3780001 2.67266634 1.37666654 1 P 0 ;0,1,2=49,3=90.000000
L 2.67266634 1.37666654 2.6684998 1.37559961 1 P 0 ;0,1,2=49,3=90.000000
L 2.6684998 1.37559961 2.6647498 1.37533297 1 P 0 ;0,1,2=49,3=90.000000
L 2.6647498 1.37533297 2.6609999 1.37586673 1 P 0 ;0,1,2=49,3=90.000000
L 2.6609999 1.37586673 2.65849961 1.37666654 1 P 0 ;0,1,2=49,3=90.000000
L 2.65849961 1.37666654 2.65599941 1.37826663 1 P 0 ;0,1,2=49,3=90.000000
L 2.65599941 1.37826663 2.65433307 1.38013346 1 P 0 ;0,1,2=49,3=90.000000
L 2.65433307 1.38013346 2.6535 1.3819997 1 P 0 ;0,1,2=49,3=90.000000
L 2.6535 1.3819997 2.6535 1.38386644 1 P 0 ;0,1,2=49,3=90.000000
L 2.6535 1.38386644 2.65433307 1.38573327 1 P 0 ;0,1,2=49,3=90.000000
L 2.65433307 1.38573327 2.65558287 1.38733337 1 P 0 ;0,1,2=49,3=90.000000
L 2.65558287 1.38733337 2.65724911 1.38866693 1 P 0 ;0,1,2=49,3=90.000000
L 2.6535 1.4039997 2.6785 1.4039997 1 P 0 ;0,1,2=49,3=90.000000
L 2.6785 1.4039997 2.6735003 1.4007999 1 P 0 ;0,1,2=49,3=90.000000
L 2.6535 1.4007999 2.6535 1.40719951 1 P 0 ;0,1,2=49,3=90.000000
L 2.6535 1.4292 2.6785 1.4292 1 P 0 ;0,1,2=49,3=90.000000
L 2.6785 1.4292 2.66058327 1.41933297 1 P 0 ;0,1,2=49,3=90.000000
L 2.66058327 1.41933297 2.66058327 1.43266693 1 P 0 ;0,1,2=49,3=90.000000
L 2.67433337 1.44293317 2.67683287 1.44453327 1 P 0 ;0,1,2=49,3=90.000000
L 2.67683287 1.44453327 2.67808337 1.4464 1 P 0 ;0,1,2=49,3=90.000000
L 2.67808337 1.4464 2.6785 1.44853337 1 P 0 ;0,1,2=49,3=90.000000
L 2.6785 1.44853337 2.67766683 1.4512 1 P 0 ;0,1,2=49,3=90.000000
L 2.67766683 1.4512 2.67558317 1.45306673 1 P 0 ;0,1,2=49,3=90.000000
L 2.67558317 1.45306673 2.67308366 1.4536 1 P 0 ;0,1,2=49,3=90.000000
L 2.67308366 1.4536 2.67058268 1.45333337 1 P 0 ;0,1,2=49,3=90.000000
L 2.67058268 1.45333337 2.6684998 1.45226644 1 P 0 ;0,1,2=49,3=90.000000
L 2.6684998 1.45226644 2.66433327 1.44693327 1 P 0 ;0,1,2=49,3=90.000000
L 2.66433327 1.44693327 2.66141644 1.44453327 1 P 0 ;0,1,2=49,3=90.000000
L 2.66141644 1.44453327 2.65724911 1.44293317 1 P 0 ;0,1,2=49,3=90.000000
L 2.65724911 1.44293317 2.6535 1.4423999 1 P 0 ;0,1,2=49,3=90.000000
L 2.6535 1.4423999 2.6535 1.4536 1 P 0 ;0,1,2=49,3=90.000000
L 4.38256004 1.50996004 4.38256004 1.58633996 1 P 0 
L 4.34556004 1.58633996 4.34556004 1.50996004 1 P 0 
L 4.34556004 1.50996004 4.38256004 1.50996004 1 P 0 
L 4.38256004 1.58633996 4.34556004 1.58633996 1 P 0 
L 2.72151634 1.47606663 2.72276683 1.47446644 1 P 0 ;0,1,2=50,3=90.000000
L 2.72276683 1.47446644 2.7236 1.4726002 1 P 0 ;0,1,2=50,3=90.000000
L 2.7236 1.4726002 2.7236 1.47046683 1 P 0 ;0,1,2=50,3=90.000000
L 2.7236 1.47046683 2.72234941 1.46806634 1 P 0 ;0,1,2=50,3=90.000000
L 2.72234941 1.46806634 2.72026654 1.4662001 1 P 0 ;0,1,2=50,3=90.000000
L 2.72026654 1.4662001 2.71776634 1.46486654 1 P 0 ;0,1,2=50,3=90.000000
L 2.71776634 1.46486654 2.7135998 1.46379961 1 P 0 ;0,1,2=50,3=90.000000
L 2.7135998 1.46379961 2.7098498 1.46353297 1 P 0 ;0,1,2=50,3=90.000000
L 2.7098498 1.46353297 2.7060999 1.46406673 1 P 0 ;0,1,2=50,3=90.000000
L 2.7060999 1.46406673 2.70359961 1.46486654 1 P 0 ;0,1,2=50,3=90.000000
L 2.70359961 1.46486654 2.70109941 1.46646663 1 P 0 ;0,1,2=50,3=90.000000
L 2.70109941 1.46646663 2.69943307 1.46833346 1 P 0 ;0,1,2=50,3=90.000000
L 2.69943307 1.46833346 2.6986 1.4701997 1 P 0 ;0,1,2=50,3=90.000000
L 2.6986 1.4701997 2.6986 1.47206644 1 P 0 ;0,1,2=50,3=90.000000
L 2.6986 1.47206644 2.69943307 1.47393327 1 P 0 ;0,1,2=50,3=90.000000
L 2.69943307 1.47393327 2.70068287 1.47553337 1 P 0 ;0,1,2=50,3=90.000000
L 2.70068287 1.47553337 2.70234911 1.47686693 1 P 0 ;0,1,2=50,3=90.000000
L 2.71943337 1.48713317 2.72193287 1.48873327 1 P 0 ;0,1,2=50,3=90.000000
L 2.72193287 1.48873327 2.72318337 1.4906 1 P 0 ;0,1,2=50,3=90.000000
L 2.72318337 1.4906 2.7236 1.49273337 1 P 0 ;0,1,2=50,3=90.000000
L 2.7236 1.49273337 2.72276683 1.4954 1 P 0 ;0,1,2=50,3=90.000000
L 2.72276683 1.4954 2.72068317 1.49726673 1 P 0 ;0,1,2=50,3=90.000000
L 2.72068317 1.49726673 2.71818366 1.4978 1 P 0 ;0,1,2=50,3=90.000000
L 2.71818366 1.4978 2.71568268 1.49753337 1 P 0 ;0,1,2=50,3=90.000000
L 2.71568268 1.49753337 2.7135998 1.49646644 1 P 0 ;0,1,2=50,3=90.000000
L 2.7135998 1.49646644 2.70943327 1.49113327 1 P 0 ;0,1,2=50,3=90.000000
L 2.70943327 1.49113327 2.70651644 1.48873327 1 P 0 ;0,1,2=50,3=90.000000
L 2.70651644 1.48873327 2.70234911 1.48713317 1 P 0 ;0,1,2=50,3=90.000000
L 2.70234911 1.48713317 2.6986 1.4865999 1 P 0 ;0,1,2=50,3=90.000000
L 2.6986 1.4865999 2.6986 1.4978 1 P 0 ;0,1,2=50,3=90.000000
L 2.6986 1.5141997 2.7236 1.5141997 1 P 0 ;0,1,2=50,3=90.000000
L 2.7236 1.5141997 2.7186003 1.5109999 1 P 0 ;0,1,2=50,3=90.000000
L 2.6986 1.5109999 2.6986 1.51739951 1 P 0 ;0,1,2=50,3=90.000000
L 2.6986 1.5394 2.7236 1.5394 1 P 0 ;0,1,2=50,3=90.000000
L 2.7236 1.5394 2.70568327 1.52953297 1 P 0 ;0,1,2=50,3=90.000000
L 2.70568327 1.52953297 2.70568327 1.54286693 1 P 0 ;0,1,2=50,3=90.000000
L 4.38256004 1.43123002 4.38256004 1.50761004 1 P 0 
L 4.38256004 1.50761004 4.34556004 1.50761004 1 P 0 
L 4.34556004 1.50761004 4.34556004 1.43123002 1 P 0 
L 4.34556004 1.43123002 4.38256004 1.43123002 1 P 0 
L 2.72041634 1.38786663 2.72166683 1.38626644 1 P 0 ;0,1,2=51,3=90.000000
L 2.72166683 1.38626644 2.7225 1.3844002 1 P 0 ;0,1,2=51,3=90.000000
L 2.7225 1.3844002 2.7225 1.38226683 1 P 0 ;0,1,2=51,3=90.000000
L 2.7225 1.38226683 2.72124941 1.37986634 1 P 0 ;0,1,2=51,3=90.000000
L 2.72124941 1.37986634 2.71916654 1.3780001 1 P 0 ;0,1,2=51,3=90.000000
L 2.71916654 1.3780001 2.71666634 1.37666654 1 P 0 ;0,1,2=51,3=90.000000
L 2.71666634 1.37666654 2.7124998 1.37559961 1 P 0 ;0,1,2=51,3=90.000000
L 2.7124998 1.37559961 2.7087498 1.37533297 1 P 0 ;0,1,2=51,3=90.000000
L 2.7087498 1.37533297 2.7049999 1.37586673 1 P 0 ;0,1,2=51,3=90.000000
L 2.7049999 1.37586673 2.70249961 1.37666654 1 P 0 ;0,1,2=51,3=90.000000
L 2.70249961 1.37666654 2.69999941 1.37826663 1 P 0 ;0,1,2=51,3=90.000000
L 2.69999941 1.37826663 2.69833307 1.38013346 1 P 0 ;0,1,2=51,3=90.000000
L 2.69833307 1.38013346 2.6975 1.3819997 1 P 0 ;0,1,2=51,3=90.000000
L 2.6975 1.3819997 2.6975 1.38386644 1 P 0 ;0,1,2=51,3=90.000000
L 2.6975 1.38386644 2.69833307 1.38573327 1 P 0 ;0,1,2=51,3=90.000000
L 2.69833307 1.38573327 2.69958287 1.38733337 1 P 0 ;0,1,2=51,3=90.000000
L 2.69958287 1.38733337 2.70124911 1.38866693 1 P 0 ;0,1,2=51,3=90.000000
L 2.71833337 1.39893317 2.72083287 1.40053327 1 P 0 ;0,1,2=51,3=90.000000
L 2.72083287 1.40053327 2.72208337 1.4024 1 P 0 ;0,1,2=51,3=90.000000
L 2.72208337 1.4024 2.7225 1.40453337 1 P 0 ;0,1,2=51,3=90.000000
L 2.7225 1.40453337 2.72166683 1.4072 1 P 0 ;0,1,2=51,3=90.000000
L 2.72166683 1.4072 2.71958317 1.40906673 1 P 0 ;0,1,2=51,3=90.000000
L 2.71958317 1.40906673 2.71708366 1.4096 1 P 0 ;0,1,2=51,3=90.000000
L 2.71708366 1.4096 2.71458268 1.40933337 1 P 0 ;0,1,2=51,3=90.000000
L 2.71458268 1.40933337 2.7124998 1.40826644 1 P 0 ;0,1,2=51,3=90.000000
L 2.7124998 1.40826644 2.70833327 1.40293327 1 P 0 ;0,1,2=51,3=90.000000
L 2.70833327 1.40293327 2.70541644 1.40053327 1 P 0 ;0,1,2=51,3=90.000000
L 2.70541644 1.40053327 2.70124911 1.39893317 1 P 0 ;0,1,2=51,3=90.000000
L 2.70124911 1.39893317 2.6975 1.3983999 1 P 0 ;0,1,2=51,3=90.000000
L 2.6975 1.3983999 2.6975 1.4096 1 P 0 ;0,1,2=51,3=90.000000
L 2.71833337 1.42093317 2.72083287 1.42253327 1 P 0 ;0,1,2=51,3=90.000000
L 2.72083287 1.42253327 2.72208337 1.4244 1 P 0 ;0,1,2=51,3=90.000000
L 2.72208337 1.4244 2.7225 1.42653337 1 P 0 ;0,1,2=51,3=90.000000
L 2.7225 1.42653337 2.72166683 1.4292 1 P 0 ;0,1,2=51,3=90.000000
L 2.72166683 1.4292 2.71958317 1.43106673 1 P 0 ;0,1,2=51,3=90.000000
L 2.71958317 1.43106673 2.71708366 1.4316 1 P 0 ;0,1,2=51,3=90.000000
L 2.71708366 1.4316 2.71458268 1.43133337 1 P 0 ;0,1,2=51,3=90.000000
L 2.71458268 1.43133337 2.7124998 1.43026644 1 P 0 ;0,1,2=51,3=90.000000
L 2.7124998 1.43026644 2.70833327 1.42493327 1 P 0 ;0,1,2=51,3=90.000000
L 2.70833327 1.42493327 2.70541644 1.42253327 1 P 0 ;0,1,2=51,3=90.000000
L 2.70541644 1.42253327 2.70124911 1.42093317 1 P 0 ;0,1,2=51,3=90.000000
L 2.70124911 1.42093317 2.6975 1.4203999 1 P 0 ;0,1,2=51,3=90.000000
L 2.6975 1.4203999 2.6975 1.4316 1 P 0 ;0,1,2=51,3=90.000000
L 2.7225 1.4479997 2.72166683 1.44586634 1 P 0 ;0,1,2=51,3=90.000000
L 2.72166683 1.44586634 2.71958317 1.44426663 1 P 0 ;0,1,2=51,3=90.000000
L 2.71958317 1.44426663 2.71708366 1.4431998 1 P 0 ;0,1,2=51,3=90.000000
L 2.71708366 1.4431998 2.71374951 1.4423999 1 P 0 ;0,1,2=51,3=90.000000
L 2.71374951 1.4423999 2.70999961 1.44213327 1 P 0 ;0,1,2=51,3=90.000000
L 2.70999961 1.44213327 2.70624961 1.4423999 1 P 0 ;0,1,2=51,3=90.000000
L 2.70624961 1.4423999 2.70291624 1.4431998 1 P 0 ;0,1,2=51,3=90.000000
L 2.70291624 1.4431998 2.70041604 1.44426663 1 P 0 ;0,1,2=51,3=90.000000
L 2.70041604 1.44426663 2.69833307 1.44586634 1 P 0 ;0,1,2=51,3=90.000000
L 2.69833307 1.44586634 2.6975 1.4479997 1 P 0 ;0,1,2=51,3=90.000000
L 2.6975 1.4479997 2.69833307 1.45013307 1 P 0 ;0,1,2=51,3=90.000000
L 2.69833307 1.45013307 2.70041604 1.45173327 1 P 0 ;0,1,2=51,3=90.000000
L 2.70041604 1.45173327 2.70291624 1.4528001 1 P 0 ;0,1,2=51,3=90.000000
L 2.70291624 1.4528001 2.70624961 1.4536 1 P 0 ;0,1,2=51,3=90.000000
L 2.70624961 1.4536 2.70999961 1.45386663 1 P 0 ;0,1,2=51,3=90.000000
L 2.70999961 1.45386663 2.71374951 1.4536 1 P 0 ;0,1,2=51,3=90.000000
L 2.71374951 1.4536 2.71708366 1.4528001 1 P 0 ;0,1,2=51,3=90.000000
L 2.71708366 1.4528001 2.71958317 1.45173327 1 P 0 ;0,1,2=51,3=90.000000
L 2.71958317 1.45173327 2.72166683 1.45013307 1 P 0 ;0,1,2=51,3=90.000000
L 2.72166683 1.45013307 2.7225 1.4479997 1 P 0 ;0,1,2=51,3=90.000000
L 3.94948002 2.17688996 3.8731 2.17688996 1 P 0 
L 3.8731 2.17688996 3.8731 2.13988996 1 P 0 
L 3.8731 2.13988996 3.94948002 2.13988996 1 P 0 
L 3.94948002 2.13988996 3.94948002 2.17688996 1 P 0 
L 3.88806673 2.22291624 3.89036693 2.22446683 1 P 0 ;0,1,2=52,3=0.000000
L 3.89036693 2.22446683 3.8930497 2.2255 1 P 0 ;0,1,2=52,3=0.000000
L 3.8930497 2.2255 3.89611644 2.2255 1 P 0 ;0,1,2=52,3=0.000000
L 3.89611644 2.2255 3.89956713 2.22394931 1 P 0 ;0,1,2=52,3=0.000000
L 3.89956713 2.22394931 3.9022499 2.22136654 1 P 0 ;0,1,2=52,3=0.000000
L 3.9022499 2.22136654 3.90416683 2.21826624 1 P 0 ;0,1,2=52,3=0.000000
L 3.90416683 2.21826624 3.90570049 2.2130998 1 P 0 ;0,1,2=52,3=0.000000
L 3.90570049 2.2130998 3.90608376 2.2084498 1 P 0 ;0,1,2=52,3=0.000000
L 3.90608376 2.2084498 3.90531663 2.2037999 1 P 0 ;0,1,2=52,3=0.000000
L 3.90531663 2.2037999 3.90416683 2.20069961 1 P 0 ;0,1,2=52,3=0.000000
L 3.90416683 2.20069961 3.90186663 2.19759931 1 P 0 ;0,1,2=52,3=0.000000
L 3.90186663 2.19759931 3.89918317 2.19553307 1 P 0 ;0,1,2=52,3=0.000000
L 3.89918317 2.19553307 3.89650039 2.1945 1 P 0 ;0,1,2=52,3=0.000000
L 3.89650039 2.1945 3.89381693 2.1945 1 P 0 ;0,1,2=52,3=0.000000
L 3.89381693 2.1945 3.89113346 2.19553307 1 P 0 ;0,1,2=52,3=0.000000
L 3.89113346 2.19553307 3.88883327 2.19708278 1 P 0 ;0,1,2=52,3=0.000000
L 3.88883327 2.19708278 3.88691634 2.19914892 1 P 0 ;0,1,2=52,3=0.000000
L 3.87278356 2.22033346 3.87048337 2.22343278 1 P 0 ;0,1,2=52,3=0.000000
L 3.87048337 2.22343278 3.8677999 2.22498337 1 P 0 ;0,1,2=52,3=0.000000
L 3.8677999 2.22498337 3.86473317 2.2255 1 P 0 ;0,1,2=52,3=0.000000
L 3.86473317 2.2255 3.8609 2.22446683 1 P 0 ;0,1,2=52,3=0.000000
L 3.8609 2.22446683 3.85821654 2.22188307 1 P 0 ;0,1,2=52,3=0.000000
L 3.85821654 2.22188307 3.85745 2.21878376 1 P 0 ;0,1,2=52,3=0.000000
L 3.85745 2.21878376 3.85783327 2.21568258 1 P 0 ;0,1,2=52,3=0.000000
L 3.85783327 2.21568258 3.85936693 2.2130998 1 P 0 ;0,1,2=52,3=0.000000
L 3.85936693 2.2130998 3.86703337 2.20793327 1 P 0 ;0,1,2=52,3=0.000000
L 3.86703337 2.20793327 3.87048337 2.20431644 1 P 0 ;0,1,2=52,3=0.000000
L 3.87048337 2.20431644 3.87278356 2.19914892 1 P 0 ;0,1,2=52,3=0.000000
L 3.87278356 2.19914892 3.8735501 2.1945 1 P 0 ;0,1,2=52,3=0.000000
L 3.8735501 2.1945 3.85745 2.1945 1 P 0 ;0,1,2=52,3=0.000000
L 3.83450039 2.1945 3.83450039 2.2255 1 P 0 ;0,1,2=52,3=0.000000
L 3.83450039 2.2255 3.8391001 2.2193003 1 P 0 ;0,1,2=52,3=0.000000
L 3.8391001 2.1945 3.82990069 2.1945 1 P 0 ;0,1,2=52,3=0.000000
L 3.81078356 2.20741575 3.8081001 2.21103356 1 P 0 ;0,1,2=52,3=0.000000
L 3.8081001 2.21103356 3.8057999 2.2130998 1 P 0 ;0,1,2=52,3=0.000000
L 3.8057999 2.2130998 3.80273317 2.21413287 1 P 0 ;0,1,2=52,3=0.000000
L 3.80273317 2.21413287 3.8000497 2.2130998 1 P 0 ;0,1,2=52,3=0.000000
L 3.8000497 2.2130998 3.79813346 2.21103356 1 P 0 ;0,1,2=52,3=0.000000
L 3.79813346 2.21103356 3.7965998 2.20793327 1 P 0 ;0,1,2=52,3=0.000000
L 3.7965998 2.20793327 3.79621654 2.20431644 1 P 0 ;0,1,2=52,3=0.000000
L 3.79621654 2.20431644 3.7965998 2.20121614 1 P 0 ;0,1,2=52,3=0.000000
L 3.7965998 2.20121614 3.79813346 2.19811585 1 P 0 ;0,1,2=52,3=0.000000
L 3.79813346 2.19811585 3.80043366 2.19553307 1 P 0 ;0,1,2=52,3=0.000000
L 3.80043366 2.19553307 3.80311644 2.1945 1 P 0 ;0,1,2=52,3=0.000000
L 3.80311644 2.1945 3.80618317 2.19553307 1 P 0 ;0,1,2=52,3=0.000000
L 3.80618317 2.19553307 3.80886663 2.19863238 1 P 0 ;0,1,2=52,3=0.000000
L 3.80886663 2.19863238 3.8104003 2.20328327 1 P 0 ;0,1,2=52,3=0.000000
L 3.8104003 2.20328327 3.81078356 2.2084498 1 P 0 ;0,1,2=52,3=0.000000
L 3.81078356 2.2084498 3.81001713 2.21516594 1 P 0 ;0,1,2=52,3=0.000000
L 3.81001713 2.21516594 3.80886663 2.21878376 1 P 0 ;0,1,2=52,3=0.000000
L 3.80886663 2.21878376 3.80695039 2.2223997 1 P 0 ;0,1,2=52,3=0.000000
L 3.80695039 2.2223997 3.80426693 2.22498337 1 P 0 ;0,1,2=52,3=0.000000
L 3.80426693 2.22498337 3.80158346 2.2255 1 P 0 ;0,1,2=52,3=0.000000
L 3.80158346 2.2255 3.7989 2.22446683 1 P 0 ;0,1,2=52,3=0.000000
L 3.7989 2.22446683 3.79698297 2.22188307 1 P 0 ;0,1,2=52,3=0.000000
L 3.91248002 2.13751998 3.91248002 2.06113996 1 P 0 
L 3.91248002 2.06113996 3.94948002 2.06113996 1 P 0 
L 3.94948002 2.06113996 3.94948002 2.13751998 1 P 0 
L 3.94948002 2.13751998 3.91248002 2.13751998 1 P 0 
L 3.98541634 2.12786663 3.98666683 2.12626644 1 P 0 ;0,1,2=53,3=90.000000
L 3.98666683 2.12626644 3.9875 2.1244002 1 P 0 ;0,1,2=53,3=90.000000
L 3.9875 2.1244002 3.9875 2.12226683 1 P 0 ;0,1,2=53,3=90.000000
L 3.9875 2.12226683 3.98624941 2.11986634 1 P 0 ;0,1,2=53,3=90.000000
L 3.98624941 2.11986634 3.98416654 2.1180001 1 P 0 ;0,1,2=53,3=90.000000
L 3.98416654 2.1180001 3.98166634 2.11666654 1 P 0 ;0,1,2=53,3=90.000000
L 3.98166634 2.11666654 3.9774998 2.11559961 1 P 0 ;0,1,2=53,3=90.000000
L 3.9774998 2.11559961 3.9737498 2.11533297 1 P 0 ;0,1,2=53,3=90.000000
L 3.9737498 2.11533297 3.9699999 2.11586673 1 P 0 ;0,1,2=53,3=90.000000
L 3.9699999 2.11586673 3.96749961 2.11666654 1 P 0 ;0,1,2=53,3=90.000000
L 3.96749961 2.11666654 3.96499941 2.11826663 1 P 0 ;0,1,2=53,3=90.000000
L 3.96499941 2.11826663 3.96333307 2.12013346 1 P 0 ;0,1,2=53,3=90.000000
L 3.96333307 2.12013346 3.9625 2.1219997 1 P 0 ;0,1,2=53,3=90.000000
L 3.9625 2.1219997 3.9625 2.12386644 1 P 0 ;0,1,2=53,3=90.000000
L 3.9625 2.12386644 3.96333307 2.12573327 1 P 0 ;0,1,2=53,3=90.000000
L 3.96333307 2.12573327 3.96458287 2.12733337 1 P 0 ;0,1,2=53,3=90.000000
L 3.96458287 2.12733337 3.96624911 2.12866693 1 P 0 ;0,1,2=53,3=90.000000
L 3.9625 2.1439997 3.9875 2.1439997 1 P 0 ;0,1,2=53,3=90.000000
L 3.9875 2.1439997 3.9825003 2.1407999 1 P 0 ;0,1,2=53,3=90.000000
L 3.9625 2.1407999 3.9625 2.14719951 1 P 0 ;0,1,2=53,3=90.000000
L 3.9625 2.1692 3.9875 2.1692 1 P 0 ;0,1,2=53,3=90.000000
L 3.9875 2.1692 3.96958327 2.15933297 1 P 0 ;0,1,2=53,3=90.000000
L 3.96958327 2.15933297 3.96958327 2.17266693 1 P 0 ;0,1,2=53,3=90.000000
L 3.9875 2.1879997 3.98666683 2.18586634 1 P 0 ;0,1,2=53,3=90.000000
L 3.98666683 2.18586634 3.98458317 2.18426663 1 P 0 ;0,1,2=53,3=90.000000
L 3.98458317 2.18426663 3.98208366 2.1831998 1 P 0 ;0,1,2=53,3=90.000000
L 3.98208366 2.1831998 3.97874951 2.1823999 1 P 0 ;0,1,2=53,3=90.000000
L 3.97874951 2.1823999 3.97499961 2.18213327 1 P 0 ;0,1,2=53,3=90.000000
L 3.97499961 2.18213327 3.97124961 2.1823999 1 P 0 ;0,1,2=53,3=90.000000
L 3.97124961 2.1823999 3.96791624 2.1831998 1 P 0 ;0,1,2=53,3=90.000000
L 3.96791624 2.1831998 3.96541604 2.18426663 1 P 0 ;0,1,2=53,3=90.000000
L 3.96541604 2.18426663 3.96333307 2.18586634 1 P 0 ;0,1,2=53,3=90.000000
L 3.96333307 2.18586634 3.9625 2.1879997 1 P 0 ;0,1,2=53,3=90.000000
L 3.9625 2.1879997 3.96333307 2.19013307 1 P 0 ;0,1,2=53,3=90.000000
L 3.96333307 2.19013307 3.96541604 2.19173327 1 P 0 ;0,1,2=53,3=90.000000
L 3.96541604 2.19173327 3.96791624 2.1928001 1 P 0 ;0,1,2=53,3=90.000000
L 3.96791624 2.1928001 3.97124961 2.1936 1 P 0 ;0,1,2=53,3=90.000000
L 3.97124961 2.1936 3.97499961 2.19386663 1 P 0 ;0,1,2=53,3=90.000000
L 3.97499961 2.19386663 3.97874951 2.1936 1 P 0 ;0,1,2=53,3=90.000000
L 3.97874951 2.1936 3.98208366 2.1928001 1 P 0 ;0,1,2=53,3=90.000000
L 3.98208366 2.1928001 3.98458317 2.19173327 1 P 0 ;0,1,2=53,3=90.000000
L 3.98458317 2.19173327 3.98666683 2.19013307 1 P 0 ;0,1,2=53,3=90.000000
L 3.98666683 2.19013307 3.9875 2.1879997 1 P 0 ;0,1,2=53,3=90.000000
L 3.98885 2.05878002 3.91246998 2.05878002 1 P 0 
L 3.91246998 2.05878002 3.91246998 2.02178002 1 P 0 
L 3.91246998 2.02178002 3.98885 2.02178002 1 P 0 
L 3.98885 2.02178002 3.98885 2.05878002 1 P 0 
L 3.89213337 2.05041634 3.89373356 2.05166683 1 P 0 ;0,1,2=54,3=0.000000
L 3.89373356 2.05166683 3.8955998 2.0525 1 P 0 ;0,1,2=54,3=0.000000
L 3.8955998 2.0525 3.89773317 2.0525 1 P 0 ;0,1,2=54,3=0.000000
L 3.89773317 2.0525 3.90013366 2.05124941 1 P 0 ;0,1,2=54,3=0.000000
L 3.90013366 2.05124941 3.9019999 2.04916654 1 P 0 ;0,1,2=54,3=0.000000
L 3.9019999 2.04916654 3.90333346 2.04666634 1 P 0 ;0,1,2=54,3=0.000000
L 3.90333346 2.04666634 3.90440039 2.0424998 1 P 0 ;0,1,2=54,3=0.000000
L 3.90440039 2.0424998 3.90466703 2.0387498 1 P 0 ;0,1,2=54,3=0.000000
L 3.90466703 2.0387498 3.90413327 2.0349999 1 P 0 ;0,1,2=54,3=0.000000
L 3.90413327 2.0349999 3.90333346 2.03249961 1 P 0 ;0,1,2=54,3=0.000000
L 3.90333346 2.03249961 3.90173337 2.02999941 1 P 0 ;0,1,2=54,3=0.000000
L 3.90173337 2.02999941 3.89986654 2.02833307 1 P 0 ;0,1,2=54,3=0.000000
L 3.89986654 2.02833307 3.8980003 2.0275 1 P 0 ;0,1,2=54,3=0.000000
L 3.8980003 2.0275 3.89613356 2.0275 1 P 0 ;0,1,2=54,3=0.000000
L 3.89613356 2.0275 3.89426673 2.02833307 1 P 0 ;0,1,2=54,3=0.000000
L 3.89426673 2.02833307 3.89266663 2.02958287 1 P 0 ;0,1,2=54,3=0.000000
L 3.89266663 2.02958287 3.89133307 2.03124911 1 P 0 ;0,1,2=54,3=0.000000
L 3.8760003 2.0275 3.8760003 2.0525 1 P 0 ;0,1,2=54,3=0.000000
L 3.8760003 2.0525 3.8792001 2.0475003 1 P 0 ;0,1,2=54,3=0.000000
L 3.8792001 2.0275 3.87280049 2.0275 1 P 0 ;0,1,2=54,3=0.000000
L 3.85986673 2.03124911 3.85826703 2.02916624 1 P 0 ;0,1,2=54,3=0.000000
L 3.85826703 2.02916624 3.8564003 2.02791654 1 P 0 ;0,1,2=54,3=0.000000
L 3.8564003 2.02791654 3.8540003 2.0275 1 P 0 ;0,1,2=54,3=0.000000
L 3.8540003 2.0275 3.8515998 2.02833307 1 P 0 ;0,1,2=54,3=0.000000
L 3.8515998 2.02833307 3.84973356 2.02999941 1 P 0 ;0,1,2=54,3=0.000000
L 3.84973356 2.02999941 3.8484 2.03291624 1 P 0 ;0,1,2=54,3=0.000000
L 3.8484 2.03291624 3.84813337 2.03624961 1 P 0 ;0,1,2=54,3=0.000000
L 3.84813337 2.03624961 3.84866663 2.03958297 1 P 0 ;0,1,2=54,3=0.000000
L 3.84866663 2.03958297 3.8500002 2.04166663 1 P 0 ;0,1,2=54,3=0.000000
L 3.8500002 2.04166663 3.85186693 2.04333297 1 P 0 ;0,1,2=54,3=0.000000
L 3.85186693 2.04333297 3.85373317 2.04374951 1 P 0 ;0,1,2=54,3=0.000000
L 3.85373317 2.04374951 3.8556 2.04333297 1 P 0 ;0,1,2=54,3=0.000000
L 3.8556 2.04333297 3.8579999 2.04166663 1 P 0 ;0,1,2=54,3=0.000000
L 3.8579999 2.04166663 3.8572001 2.0525 1 P 0 ;0,1,2=54,3=0.000000
L 3.8572001 2.0525 3.8500002 2.0525 1 P 0 ;0,1,2=54,3=0.000000
L 3.83253346 2.0275 3.8320003 2.03291624 1 P 0 ;0,1,2=54,3=0.000000
L 3.8320003 2.03291624 3.8312 2.03749931 1 P 0 ;0,1,2=54,3=0.000000
L 3.8312 2.03749931 3.83013356 2.04166663 1 P 0 ;0,1,2=54,3=0.000000
L 3.83013356 2.04166663 3.8288 2.0462498 1 P 0 ;0,1,2=54,3=0.000000
L 3.8288 2.0462498 3.82666663 2.0525 1 P 0 ;0,1,2=54,3=0.000000
L 3.82666663 2.0525 3.83733346 2.0525 1 P 0 ;0,1,2=54,3=0.000000
L 3.98886004 2.01941004 3.91248002 2.01941004 1 P 0 
L 3.91248002 2.01941004 3.91248002 1.98241004 1 P 0 
L 3.91248002 1.98241004 3.98886004 1.98241004 1 P 0 
L 3.98886004 1.98241004 3.98886004 2.01941004 1 P 0 
L 3.92713337 1.97041634 3.92873356 1.97166683 1 P 0 ;0,1,2=55,3=0.000000
L 3.92873356 1.97166683 3.9305998 1.9725 1 P 0 ;0,1,2=55,3=0.000000
L 3.9305998 1.9725 3.93273317 1.9725 1 P 0 ;0,1,2=55,3=0.000000
L 3.93273317 1.9725 3.93513366 1.97124941 1 P 0 ;0,1,2=55,3=0.000000
L 3.93513366 1.97124941 3.9369999 1.96916654 1 P 0 ;0,1,2=55,3=0.000000
L 3.9369999 1.96916654 3.93833346 1.96666634 1 P 0 ;0,1,2=55,3=0.000000
L 3.93833346 1.96666634 3.93940039 1.9624998 1 P 0 ;0,1,2=55,3=0.000000
L 3.93940039 1.9624998 3.93966703 1.9587498 1 P 0 ;0,1,2=55,3=0.000000
L 3.93966703 1.9587498 3.93913327 1.9549999 1 P 0 ;0,1,2=55,3=0.000000
L 3.93913327 1.9549999 3.93833346 1.95249961 1 P 0 ;0,1,2=55,3=0.000000
L 3.93833346 1.95249961 3.93673337 1.94999941 1 P 0 ;0,1,2=55,3=0.000000
L 3.93673337 1.94999941 3.93486654 1.94833307 1 P 0 ;0,1,2=55,3=0.000000
L 3.93486654 1.94833307 3.9330003 1.9475 1 P 0 ;0,1,2=55,3=0.000000
L 3.9330003 1.9475 3.93113356 1.9475 1 P 0 ;0,1,2=55,3=0.000000
L 3.93113356 1.9475 3.92926673 1.94833307 1 P 0 ;0,1,2=55,3=0.000000
L 3.92926673 1.94833307 3.92766663 1.94958287 1 P 0 ;0,1,2=55,3=0.000000
L 3.92766663 1.94958287 3.92633307 1.95124911 1 P 0 ;0,1,2=55,3=0.000000
L 3.91606683 1.96833337 3.91446673 1.97083287 1 P 0 ;0,1,2=55,3=0.000000
L 3.91446673 1.97083287 3.9126 1.97208337 1 P 0 ;0,1,2=55,3=0.000000
L 3.9126 1.97208337 3.91046663 1.9725 1 P 0 ;0,1,2=55,3=0.000000
L 3.91046663 1.9725 3.9078 1.97166683 1 P 0 ;0,1,2=55,3=0.000000
L 3.9078 1.97166683 3.90593327 1.96958317 1 P 0 ;0,1,2=55,3=0.000000
L 3.90593327 1.96958317 3.9054 1.96708366 1 P 0 ;0,1,2=55,3=0.000000
L 3.9054 1.96708366 3.90566663 1.96458268 1 P 0 ;0,1,2=55,3=0.000000
L 3.90566663 1.96458268 3.90673356 1.9624998 1 P 0 ;0,1,2=55,3=0.000000
L 3.90673356 1.9624998 3.91206673 1.95833327 1 P 0 ;0,1,2=55,3=0.000000
L 3.91206673 1.95833327 3.91446673 1.95541644 1 P 0 ;0,1,2=55,3=0.000000
L 3.91446673 1.95541644 3.91606683 1.95124911 1 P 0 ;0,1,2=55,3=0.000000
L 3.91606683 1.95124911 3.9166001 1.9475 1 P 0 ;0,1,2=55,3=0.000000
L 3.9166001 1.9475 3.9054 1.9475 1 P 0 ;0,1,2=55,3=0.000000
L 3.8890003 1.9475 3.8890003 1.9725 1 P 0 ;0,1,2=55,3=0.000000
L 3.8890003 1.9725 3.8922001 1.9675003 1 P 0 ;0,1,2=55,3=0.000000
L 3.8922001 1.9475 3.88580049 1.9475 1 P 0 ;0,1,2=55,3=0.000000
L 3.8670003 1.9475 3.8670003 1.9725 1 P 0 ;0,1,2=55,3=0.000000
L 3.8670003 1.9725 3.8702001 1.9675003 1 P 0 ;0,1,2=55,3=0.000000
L 3.8702001 1.9475 3.86380049 1.9475 1 P 0 ;0,1,2=55,3=0.000000
L 4.4613 1.46823002 4.4243 1.46823002 1 P 0 
L 4.4243 1.46823002 4.4243 1.39185 1 P 0 
L 4.4243 1.39185 4.4613 1.39185 1 P 0 
L 4.4613 1.39185 4.4613 1.46823002 1 P 0 
L 4.45041634 1.31286663 4.45166683 1.31126644 1 P 0 ;0,1,2=56,3=90.000000
L 4.45166683 1.31126644 4.4525 1.3094002 1 P 0 ;0,1,2=56,3=90.000000
L 4.4525 1.3094002 4.4525 1.30726683 1 P 0 ;0,1,2=56,3=90.000000
L 4.4525 1.30726683 4.45124941 1.30486634 1 P 0 ;0,1,2=56,3=90.000000
L 4.45124941 1.30486634 4.44916654 1.3030001 1 P 0 ;0,1,2=56,3=90.000000
L 4.44916654 1.3030001 4.44666634 1.30166654 1 P 0 ;0,1,2=56,3=90.000000
L 4.44666634 1.30166654 4.4424998 1.30059961 1 P 0 ;0,1,2=56,3=90.000000
L 4.4424998 1.30059961 4.4387498 1.30033297 1 P 0 ;0,1,2=56,3=90.000000
L 4.4387498 1.30033297 4.4349999 1.30086673 1 P 0 ;0,1,2=56,3=90.000000
L 4.4349999 1.30086673 4.43249961 1.30166654 1 P 0 ;0,1,2=56,3=90.000000
L 4.43249961 1.30166654 4.42999941 1.30326663 1 P 0 ;0,1,2=56,3=90.000000
L 4.42999941 1.30326663 4.42833307 1.30513346 1 P 0 ;0,1,2=56,3=90.000000
L 4.42833307 1.30513346 4.4275 1.3069997 1 P 0 ;0,1,2=56,3=90.000000
L 4.4275 1.3069997 4.4275 1.30886644 1 P 0 ;0,1,2=56,3=90.000000
L 4.4275 1.30886644 4.42833307 1.31073327 1 P 0 ;0,1,2=56,3=90.000000
L 4.42833307 1.31073327 4.42958287 1.31233337 1 P 0 ;0,1,2=56,3=90.000000
L 4.42958287 1.31233337 4.43124911 1.31366693 1 P 0 ;0,1,2=56,3=90.000000
L 4.4275 1.3289997 4.4525 1.3289997 1 P 0 ;0,1,2=56,3=90.000000
L 4.4525 1.3289997 4.4475003 1.3257999 1 P 0 ;0,1,2=56,3=90.000000
L 4.4275 1.3257999 4.4275 1.33219951 1 P 0 ;0,1,2=56,3=90.000000
L 4.43249961 1.34513327 4.42958287 1.34673297 1 P 0 ;0,1,2=56,3=90.000000
L 4.42958287 1.34673297 4.42791654 1.34886634 1 P 0 ;0,1,2=56,3=90.000000
L 4.42791654 1.34886634 4.4275 1.35126683 1 P 0 ;0,1,2=56,3=90.000000
L 4.4275 1.35126683 4.42791654 1.3534002 1 P 0 ;0,1,2=56,3=90.000000
L 4.42791654 1.3534002 4.42999941 1.35553356 1 P 0 ;0,1,2=56,3=90.000000
L 4.42999941 1.35553356 4.43249961 1.35686663 1 P 0 ;0,1,2=56,3=90.000000
L 4.43249961 1.35686663 4.4349999 1.35713317 1 P 0 ;0,1,2=56,3=90.000000
L 4.4349999 1.35713317 4.43791594 1.3566 1 P 0 ;0,1,2=56,3=90.000000
L 4.43791594 1.3566 4.43999961 1.35473327 1 P 0 ;0,1,2=56,3=90.000000
L 4.43999961 1.35473327 4.44083346 1.35286644 1 P 0 ;0,1,2=56,3=90.000000
L 4.44083346 1.35286644 4.44083346 1.35046654 1 P 0 ;0,1,2=56,3=90.000000
L 4.44083346 1.35286644 4.44208327 1.35446663 1 P 0 ;0,1,2=56,3=90.000000
L 4.44208327 1.35446663 4.44416614 1.3558001 1 P 0 ;0,1,2=56,3=90.000000
L 4.44416614 1.3558001 4.44666634 1.35633337 1 P 0 ;0,1,2=56,3=90.000000
L 4.44666634 1.35633337 4.44916654 1.3558001 1 P 0 ;0,1,2=56,3=90.000000
L 4.44916654 1.3558001 4.45124941 1.35446663 1 P 0 ;0,1,2=56,3=90.000000
L 4.45124941 1.35446663 4.4525 1.35206663 1 P 0 ;0,1,2=56,3=90.000000
L 4.4525 1.35206663 4.45208337 1.34966663 1 P 0 ;0,1,2=56,3=90.000000
L 4.45208337 1.34966663 4.45041634 1.34726663 1 P 0 ;0,1,2=56,3=90.000000
L 4.43124911 1.36713327 4.42916624 1.36873297 1 P 0 ;0,1,2=56,3=90.000000
L 4.42916624 1.36873297 4.42791654 1.3705997 1 P 0 ;0,1,2=56,3=90.000000
L 4.42791654 1.3705997 4.4275 1.3729997 1 P 0 ;0,1,2=56,3=90.000000
L 4.4275 1.3729997 4.42833307 1.3754002 1 P 0 ;0,1,2=56,3=90.000000
L 4.42833307 1.3754002 4.42999941 1.37726644 1 P 0 ;0,1,2=56,3=90.000000
L 4.42999941 1.37726644 4.43291624 1.3786 1 P 0 ;0,1,2=56,3=90.000000
L 4.43291624 1.3786 4.43624961 1.37886663 1 P 0 ;0,1,2=56,3=90.000000
L 4.43624961 1.37886663 4.43958297 1.37833337 1 P 0 ;0,1,2=56,3=90.000000
L 4.43958297 1.37833337 4.44166663 1.3769998 1 P 0 ;0,1,2=56,3=90.000000
L 4.44166663 1.3769998 4.44333297 1.37513307 1 P 0 ;0,1,2=56,3=90.000000
L 4.44333297 1.37513307 4.44374951 1.37326683 1 P 0 ;0,1,2=56,3=90.000000
L 4.44374951 1.37326683 4.44333297 1.3714 1 P 0 ;0,1,2=56,3=90.000000
L 4.44333297 1.3714 4.44166663 1.3690001 1 P 0 ;0,1,2=56,3=90.000000
L 4.44166663 1.3690001 4.4525 1.3697999 1 P 0 ;0,1,2=56,3=90.000000
L 4.4525 1.3697999 4.4525 1.3769998 1 P 0 ;0,1,2=56,3=90.000000
L 4.42193002 1.31311004 4.42193002 1.38948996 1 P 0 
L 4.42193002 1.38948996 4.38493002 1.38948996 1 P 0 
L 4.38493002 1.38948996 4.38493002 1.31311004 1 P 0 
L 4.38493002 1.31311004 4.42193002 1.31311004 1 P 0 
L 4.41541634 1.24286663 4.41666683 1.24126644 1 P 0 ;0,1,2=57,3=90.000000
L 4.41666683 1.24126644 4.4175 1.2394002 1 P 0 ;0,1,2=57,3=90.000000
L 4.4175 1.2394002 4.4175 1.23726683 1 P 0 ;0,1,2=57,3=90.000000
L 4.4175 1.23726683 4.41624941 1.23486634 1 P 0 ;0,1,2=57,3=90.000000
L 4.41624941 1.23486634 4.41416654 1.2330001 1 P 0 ;0,1,2=57,3=90.000000
L 4.41416654 1.2330001 4.41166634 1.23166654 1 P 0 ;0,1,2=57,3=90.000000
L 4.41166634 1.23166654 4.4074998 1.23059961 1 P 0 ;0,1,2=57,3=90.000000
L 4.4074998 1.23059961 4.4037498 1.23033297 1 P 0 ;0,1,2=57,3=90.000000
L 4.4037498 1.23033297 4.3999999 1.23086673 1 P 0 ;0,1,2=57,3=90.000000
L 4.3999999 1.23086673 4.39749961 1.23166654 1 P 0 ;0,1,2=57,3=90.000000
L 4.39749961 1.23166654 4.39499941 1.23326663 1 P 0 ;0,1,2=57,3=90.000000
L 4.39499941 1.23326663 4.39333307 1.23513346 1 P 0 ;0,1,2=57,3=90.000000
L 4.39333307 1.23513346 4.3925 1.2369997 1 P 0 ;0,1,2=57,3=90.000000
L 4.3925 1.2369997 4.3925 1.23886644 1 P 0 ;0,1,2=57,3=90.000000
L 4.3925 1.23886644 4.39333307 1.24073327 1 P 0 ;0,1,2=57,3=90.000000
L 4.39333307 1.24073327 4.39458287 1.24233337 1 P 0 ;0,1,2=57,3=90.000000
L 4.39458287 1.24233337 4.39624911 1.24366693 1 P 0 ;0,1,2=57,3=90.000000
L 4.3925 1.2589997 4.4175 1.2589997 1 P 0 ;0,1,2=57,3=90.000000
L 4.4175 1.2589997 4.4125003 1.2557999 1 P 0 ;0,1,2=57,3=90.000000
L 4.3925 1.2557999 4.3925 1.26219951 1 P 0 ;0,1,2=57,3=90.000000
L 4.4175 1.2809997 4.41666683 1.27886634 1 P 0 ;0,1,2=57,3=90.000000
L 4.41666683 1.27886634 4.41458317 1.27726663 1 P 0 ;0,1,2=57,3=90.000000
L 4.41458317 1.27726663 4.41208366 1.2761998 1 P 0 ;0,1,2=57,3=90.000000
L 4.41208366 1.2761998 4.40874951 1.2753999 1 P 0 ;0,1,2=57,3=90.000000
L 4.40874951 1.2753999 4.40499961 1.27513327 1 P 0 ;0,1,2=57,3=90.000000
L 4.40499961 1.27513327 4.40124961 1.2753999 1 P 0 ;0,1,2=57,3=90.000000
L 4.40124961 1.2753999 4.39791624 1.2761998 1 P 0 ;0,1,2=57,3=90.000000
L 4.39791624 1.2761998 4.39541604 1.27726663 1 P 0 ;0,1,2=57,3=90.000000
L 4.39541604 1.27726663 4.39333307 1.27886634 1 P 0 ;0,1,2=57,3=90.000000
L 4.39333307 1.27886634 4.3925 1.2809997 1 P 0 ;0,1,2=57,3=90.000000
L 4.3925 1.2809997 4.39333307 1.28313307 1 P 0 ;0,1,2=57,3=90.000000
L 4.39333307 1.28313307 4.39541604 1.28473327 1 P 0 ;0,1,2=57,3=90.000000
L 4.39541604 1.28473327 4.39791624 1.2858001 1 P 0 ;0,1,2=57,3=90.000000
L 4.39791624 1.2858001 4.40124961 1.2866 1 P 0 ;0,1,2=57,3=90.000000
L 4.40124961 1.2866 4.40499961 1.28686663 1 P 0 ;0,1,2=57,3=90.000000
L 4.40499961 1.28686663 4.40874951 1.2866 1 P 0 ;0,1,2=57,3=90.000000
L 4.40874951 1.2866 4.41208366 1.2858001 1 P 0 ;0,1,2=57,3=90.000000
L 4.41208366 1.2858001 4.41458317 1.28473327 1 P 0 ;0,1,2=57,3=90.000000
L 4.41458317 1.28473327 4.41666683 1.28313307 1 P 0 ;0,1,2=57,3=90.000000
L 4.41666683 1.28313307 4.4175 1.2809997 1 P 0 ;0,1,2=57,3=90.000000
L 4.3925 1.3029997 4.39291654 1.30486644 1 P 0 ;0,1,2=57,3=90.000000
L 4.39291654 1.30486644 4.39416624 1.3069998 1 P 0 ;0,1,2=57,3=90.000000
L 4.39416624 1.3069998 4.39624911 1.30833337 1 P 0 ;0,1,2=57,3=90.000000
L 4.39624911 1.30833337 4.39916673 1.30886663 1 P 0 ;0,1,2=57,3=90.000000
L 4.39916673 1.30886663 4.40208278 1.30833337 1 P 0 ;0,1,2=57,3=90.000000
L 4.40208278 1.30833337 4.40458297 1.30673327 1 P 0 ;0,1,2=57,3=90.000000
L 4.40458297 1.30673327 4.40583346 1.30433327 1 P 0 ;0,1,2=57,3=90.000000
L 4.40583346 1.30433327 4.40583346 1.30166663 1 P 0 ;0,1,2=57,3=90.000000
L 4.40583346 1.30166663 4.40666663 1.30006654 1 P 0 ;0,1,2=57,3=90.000000
L 4.40666663 1.30006654 4.40874951 1.29873297 1 P 0 ;0,1,2=57,3=90.000000
L 4.40874951 1.29873297 4.41166634 1.2981998 1 P 0 ;0,1,2=57,3=90.000000
L 4.41166634 1.2981998 4.41458317 1.2990001 1 P 0 ;0,1,2=57,3=90.000000
L 4.41458317 1.2990001 4.41666683 1.30086634 1 P 0 ;0,1,2=57,3=90.000000
L 4.41666683 1.30086634 4.4175 1.3029997 1 P 0 ;0,1,2=57,3=90.000000
L 4.4175 1.3029997 4.41666683 1.30513307 1 P 0 ;0,1,2=57,3=90.000000
L 4.41666683 1.30513307 4.41458317 1.3069998 1 P 0 ;0,1,2=57,3=90.000000
L 4.41458317 1.3069998 4.41166634 1.3078001 1 P 0 ;0,1,2=57,3=90.000000
L 4.41166634 1.3078001 4.40874951 1.30726644 1 P 0 ;0,1,2=57,3=90.000000
L 4.40874951 1.30726644 4.40666663 1.30593337 1 P 0 ;0,1,2=57,3=90.000000
L 4.40666663 1.30593337 4.40583346 1.30433327 1 P 0 ;0,1,2=57,3=90.000000
L 4.40583346 1.30433327 4.40583346 1.30166663 1 P 0 ;0,1,2=57,3=90.000000
L 4.40583346 1.30166663 4.40458297 1.29926663 1 P 0 ;0,1,2=57,3=90.000000
L 4.40458297 1.29926663 4.40208278 1.29766654 1 P 0 ;0,1,2=57,3=90.000000
L 4.40208278 1.29766654 4.39916673 1.29713327 1 P 0 ;0,1,2=57,3=90.000000
L 4.39916673 1.29713327 4.39624911 1.29766654 1 P 0 ;0,1,2=57,3=90.000000
L 4.39624911 1.29766654 4.39416624 1.2990001 1 P 0 ;0,1,2=57,3=90.000000
L 4.39416624 1.2990001 4.39291654 1.30113346 1 P 0 ;0,1,2=57,3=90.000000
L 4.39291654 1.30113346 4.3925 1.3029997 1 P 0 ;0,1,2=57,3=90.000000
L 4.18571998 2.02178002 4.18571998 2.05878002 1 P 0 
L 4.10933996 2.02178002 4.18571998 2.02178002 1 P 0 
L 4.18571998 2.05878002 4.10933996 2.05878002 1 P 0 
L 4.10933996 2.05878002 4.10933996 2.02178002 1 P 0 
L 4.20713337 2.09041634 4.20873356 2.09166683 1 P 0 ;0,1,2=58,3=0.000000
L 4.20873356 2.09166683 4.2105998 2.0925 1 P 0 ;0,1,2=58,3=0.000000
L 4.2105998 2.0925 4.21273317 2.0925 1 P 0 ;0,1,2=58,3=0.000000
L 4.21273317 2.0925 4.21513366 2.09124941 1 P 0 ;0,1,2=58,3=0.000000
L 4.21513366 2.09124941 4.2169999 2.08916654 1 P 0 ;0,1,2=58,3=0.000000
L 4.2169999 2.08916654 4.21833346 2.08666634 1 P 0 ;0,1,2=58,3=0.000000
L 4.21833346 2.08666634 4.21940039 2.0824998 1 P 0 ;0,1,2=58,3=0.000000
L 4.21940039 2.0824998 4.21966703 2.0787498 1 P 0 ;0,1,2=58,3=0.000000
L 4.21966703 2.0787498 4.21913327 2.0749999 1 P 0 ;0,1,2=58,3=0.000000
L 4.21913327 2.0749999 4.21833346 2.07249961 1 P 0 ;0,1,2=58,3=0.000000
L 4.21833346 2.07249961 4.21673337 2.06999941 1 P 0 ;0,1,2=58,3=0.000000
L 4.21673337 2.06999941 4.21486654 2.06833307 1 P 0 ;0,1,2=58,3=0.000000
L 4.21486654 2.06833307 4.2130003 2.0675 1 P 0 ;0,1,2=58,3=0.000000
L 4.2130003 2.0675 4.21113356 2.0675 1 P 0 ;0,1,2=58,3=0.000000
L 4.21113356 2.0675 4.20926673 2.06833307 1 P 0 ;0,1,2=58,3=0.000000
L 4.20926673 2.06833307 4.20766663 2.06958287 1 P 0 ;0,1,2=58,3=0.000000
L 4.20766663 2.06958287 4.20633307 2.07124911 1 P 0 ;0,1,2=58,3=0.000000
L 4.1910003 2.0675 4.1910003 2.0925 1 P 0 ;0,1,2=58,3=0.000000
L 4.1910003 2.0925 4.1942001 2.0875003 1 P 0 ;0,1,2=58,3=0.000000
L 4.1942001 2.0675 4.18780049 2.0675 1 P 0 ;0,1,2=58,3=0.000000
L 4.1690003 2.0675 4.1690003 2.0925 1 P 0 ;0,1,2=58,3=0.000000
L 4.1690003 2.0925 4.1722001 2.0875003 1 P 0 ;0,1,2=58,3=0.000000
L 4.1722001 2.0675 4.16580049 2.0675 1 P 0 ;0,1,2=58,3=0.000000
L 4.15206683 2.08833337 4.15046673 2.09083287 1 P 0 ;0,1,2=58,3=0.000000
L 4.15046673 2.09083287 4.1486 2.09208337 1 P 0 ;0,1,2=58,3=0.000000
L 4.1486 2.09208337 4.14646663 2.0925 1 P 0 ;0,1,2=58,3=0.000000
L 4.14646663 2.0925 4.1438 2.09166683 1 P 0 ;0,1,2=58,3=0.000000
L 4.1438 2.09166683 4.14193327 2.08958317 1 P 0 ;0,1,2=58,3=0.000000
L 4.14193327 2.08958317 4.1414 2.08708366 1 P 0 ;0,1,2=58,3=0.000000
L 4.1414 2.08708366 4.14166663 2.08458268 1 P 0 ;0,1,2=58,3=0.000000
L 4.14166663 2.08458268 4.14273356 2.0824998 1 P 0 ;0,1,2=58,3=0.000000
L 4.14273356 2.0824998 4.14806673 2.07833327 1 P 0 ;0,1,2=58,3=0.000000
L 4.14806673 2.07833327 4.15046673 2.07541644 1 P 0 ;0,1,2=58,3=0.000000
L 4.15046673 2.07541644 4.15206683 2.07124911 1 P 0 ;0,1,2=58,3=0.000000
L 4.15206683 2.07124911 4.1526001 2.0675 1 P 0 ;0,1,2=58,3=0.000000
L 4.1526001 2.0675 4.1414 2.0675 1 P 0 ;0,1,2=58,3=0.000000
L 4.14633996 1.98003996 4.06996004 1.98003996 1 P 0 
L 4.06996004 1.98003996 4.06996004 1.94303996 1 P 0 
L 4.06996004 1.94303996 4.14633996 1.94303996 1 P 0 
L 4.14633996 1.94303996 4.14633996 1.98003996 1 P 0 
L 4.12713337 2.01041634 4.12873356 2.01166683 1 P 0 ;0,1,2=59,3=0.000000
L 4.12873356 2.01166683 4.1305998 2.0125 1 P 0 ;0,1,2=59,3=0.000000
L 4.1305998 2.0125 4.13273317 2.0125 1 P 0 ;0,1,2=59,3=0.000000
L 4.13273317 2.0125 4.13513366 2.01124941 1 P 0 ;0,1,2=59,3=0.000000
L 4.13513366 2.01124941 4.1369999 2.00916654 1 P 0 ;0,1,2=59,3=0.000000
L 4.1369999 2.00916654 4.13833346 2.00666634 1 P 0 ;0,1,2=59,3=0.000000
L 4.13833346 2.00666634 4.13940039 2.0024998 1 P 0 ;0,1,2=59,3=0.000000
L 4.13940039 2.0024998 4.13966703 1.9987498 1 P 0 ;0,1,2=59,3=0.000000
L 4.13966703 1.9987498 4.13913327 1.9949999 1 P 0 ;0,1,2=59,3=0.000000
L 4.13913327 1.9949999 4.13833346 1.99249961 1 P 0 ;0,1,2=59,3=0.000000
L 4.13833346 1.99249961 4.13673337 1.98999941 1 P 0 ;0,1,2=59,3=0.000000
L 4.13673337 1.98999941 4.13486654 1.98833307 1 P 0 ;0,1,2=59,3=0.000000
L 4.13486654 1.98833307 4.1330003 1.9875 1 P 0 ;0,1,2=59,3=0.000000
L 4.1330003 1.9875 4.13113356 1.9875 1 P 0 ;0,1,2=59,3=0.000000
L 4.13113356 1.9875 4.12926673 1.98833307 1 P 0 ;0,1,2=59,3=0.000000
L 4.12926673 1.98833307 4.12766663 1.98958287 1 P 0 ;0,1,2=59,3=0.000000
L 4.12766663 1.98958287 4.12633307 1.99124911 1 P 0 ;0,1,2=59,3=0.000000
L 4.1110003 1.9875 4.1110003 2.0125 1 P 0 ;0,1,2=59,3=0.000000
L 4.1110003 2.0125 4.1142001 2.0075003 1 P 0 ;0,1,2=59,3=0.000000
L 4.1142001 1.9875 4.10780049 1.9875 1 P 0 ;0,1,2=59,3=0.000000
L 4.09486673 1.99124911 4.09326703 1.98916624 1 P 0 ;0,1,2=59,3=0.000000
L 4.09326703 1.98916624 4.0914003 1.98791654 1 P 0 ;0,1,2=59,3=0.000000
L 4.0914003 1.98791654 4.0890003 1.9875 1 P 0 ;0,1,2=59,3=0.000000
L 4.0890003 1.9875 4.0865998 1.98833307 1 P 0 ;0,1,2=59,3=0.000000
L 4.0865998 1.98833307 4.08473356 1.98999941 1 P 0 ;0,1,2=59,3=0.000000
L 4.08473356 1.98999941 4.0834 1.99291624 1 P 0 ;0,1,2=59,3=0.000000
L 4.0834 1.99291624 4.08313337 1.99624961 1 P 0 ;0,1,2=59,3=0.000000
L 4.08313337 1.99624961 4.08366663 1.99958297 1 P 0 ;0,1,2=59,3=0.000000
L 4.08366663 1.99958297 4.0850002 2.00166663 1 P 0 ;0,1,2=59,3=0.000000
L 4.0850002 2.00166663 4.08686693 2.00333297 1 P 0 ;0,1,2=59,3=0.000000
L 4.08686693 2.00333297 4.08873317 2.00374951 1 P 0 ;0,1,2=59,3=0.000000
L 4.08873317 2.00374951 4.0906 2.00333297 1 P 0 ;0,1,2=59,3=0.000000
L 4.0906 2.00333297 4.0929999 2.00166663 1 P 0 ;0,1,2=59,3=0.000000
L 4.0929999 2.00166663 4.0922001 2.0125 1 P 0 ;0,1,2=59,3=0.000000
L 4.0922001 2.0125 4.0850002 2.0125 1 P 0 ;0,1,2=59,3=0.000000
L 4.07286673 1.99249961 4.07126703 1.98958287 1 P 0 ;0,1,2=59,3=0.000000
L 4.07126703 1.98958287 4.06913366 1.98791654 1 P 0 ;0,1,2=59,3=0.000000
L 4.06913366 1.98791654 4.06673317 1.9875 1 P 0 ;0,1,2=59,3=0.000000
L 4.06673317 1.9875 4.0645998 1.98791654 1 P 0 ;0,1,2=59,3=0.000000
L 4.0645998 1.98791654 4.06246644 1.98999941 1 P 0 ;0,1,2=59,3=0.000000
L 4.06246644 1.98999941 4.06113337 1.99249961 1 P 0 ;0,1,2=59,3=0.000000
L 4.06113337 1.99249961 4.06086683 1.9949999 1 P 0 ;0,1,2=59,3=0.000000
L 4.06086683 1.9949999 4.0614 1.99791594 1 P 0 ;0,1,2=59,3=0.000000
L 4.0614 1.99791594 4.06326673 1.99999961 1 P 0 ;0,1,2=59,3=0.000000
L 4.06326673 1.99999961 4.06513356 2.00083346 1 P 0 ;0,1,2=59,3=0.000000
L 4.06513356 2.00083346 4.06753346 2.00083346 1 P 0 ;0,1,2=59,3=0.000000
L 4.06513356 2.00083346 4.06353337 2.00208327 1 P 0 ;0,1,2=59,3=0.000000
L 4.06353337 2.00208327 4.0621999 2.00416614 1 P 0 ;0,1,2=59,3=0.000000
L 4.0621999 2.00416614 4.06166663 2.00666634 1 P 0 ;0,1,2=59,3=0.000000
L 4.06166663 2.00666634 4.0621999 2.00916654 1 P 0 ;0,1,2=59,3=0.000000
L 4.0621999 2.00916654 4.06353337 2.01124941 1 P 0 ;0,1,2=59,3=0.000000
L 4.06353337 2.01124941 4.06593337 2.0125 1 P 0 ;0,1,2=59,3=0.000000
L 4.06593337 2.0125 4.06833337 2.01208337 1 P 0 ;0,1,2=59,3=0.000000
L 4.06833337 2.01208337 4.07073337 2.01041634 1 P 0 ;0,1,2=59,3=0.000000
L 4.18571004 1.94303996 4.18571004 2.01941998 1 P 0 
L 4.18571004 2.01941998 4.14871004 2.01941998 1 P 0 
L 4.14871004 2.01941998 4.14871004 1.94303996 1 P 0 
L 4.14871004 1.94303996 4.18571004 1.94303996 1 P 0 
L 4.21541634 1.93786663 4.21666683 1.93626644 1 P 0 ;0,1,2=60,3=90.000000
L 4.21666683 1.93626644 4.2175 1.9344002 1 P 0 ;0,1,2=60,3=90.000000
L 4.2175 1.9344002 4.2175 1.93226683 1 P 0 ;0,1,2=60,3=90.000000
L 4.2175 1.93226683 4.21624941 1.92986634 1 P 0 ;0,1,2=60,3=90.000000
L 4.21624941 1.92986634 4.21416654 1.9280001 1 P 0 ;0,1,2=60,3=90.000000
L 4.21416654 1.9280001 4.21166634 1.92666654 1 P 0 ;0,1,2=60,3=90.000000
L 4.21166634 1.92666654 4.2074998 1.92559961 1 P 0 ;0,1,2=60,3=90.000000
L 4.2074998 1.92559961 4.2037498 1.92533297 1 P 0 ;0,1,2=60,3=90.000000
L 4.2037498 1.92533297 4.1999999 1.92586673 1 P 0 ;0,1,2=60,3=90.000000
L 4.1999999 1.92586673 4.19749961 1.92666654 1 P 0 ;0,1,2=60,3=90.000000
L 4.19749961 1.92666654 4.19499941 1.92826663 1 P 0 ;0,1,2=60,3=90.000000
L 4.19499941 1.92826663 4.19333307 1.93013346 1 P 0 ;0,1,2=60,3=90.000000
L 4.19333307 1.93013346 4.1925 1.9319997 1 P 0 ;0,1,2=60,3=90.000000
L 4.1925 1.9319997 4.1925 1.93386644 1 P 0 ;0,1,2=60,3=90.000000
L 4.1925 1.93386644 4.19333307 1.93573327 1 P 0 ;0,1,2=60,3=90.000000
L 4.19333307 1.93573327 4.19458287 1.93733337 1 P 0 ;0,1,2=60,3=90.000000
L 4.19458287 1.93733337 4.19624911 1.93866693 1 P 0 ;0,1,2=60,3=90.000000
L 4.1925 1.9539997 4.2175 1.9539997 1 P 0 ;0,1,2=60,3=90.000000
L 4.2175 1.9539997 4.2125003 1.9507999 1 P 0 ;0,1,2=60,3=90.000000
L 4.1925 1.9507999 4.1925 1.95719951 1 P 0 ;0,1,2=60,3=90.000000
L 4.1925 1.9759997 4.2175 1.9759997 1 P 0 ;0,1,2=60,3=90.000000
L 4.2175 1.9759997 4.2125003 1.9727999 1 P 0 ;0,1,2=60,3=90.000000
L 4.1925 1.9727999 4.1925 1.97919951 1 P 0 ;0,1,2=60,3=90.000000
L 4.19541604 1.99346634 4.19333307 1.99533317 1 P 0 ;0,1,2=60,3=90.000000
L 4.19333307 1.99533317 4.1925 1.99746654 1 P 0 ;0,1,2=60,3=90.000000
L 4.1925 1.99746654 4.19333307 1.9995999 1 P 0 ;0,1,2=60,3=90.000000
L 4.19333307 1.9995999 4.19583258 2.00146663 1 P 0 ;0,1,2=60,3=90.000000
L 4.19583258 2.00146663 4.19958327 2.0028001 1 P 0 ;0,1,2=60,3=90.000000
L 4.19958327 2.0028001 4.20333327 2.00333337 1 P 0 ;0,1,2=60,3=90.000000
L 4.20333327 2.00333337 4.20791634 2.00333337 1 P 0 ;0,1,2=60,3=90.000000
L 4.20791634 2.00333337 4.21166634 2.0028001 1 P 0 ;0,1,2=60,3=90.000000
L 4.21166634 2.0028001 4.2149997 2.00146663 1 P 0 ;0,1,2=60,3=90.000000
L 4.2149997 2.00146663 4.21666683 1.99986644 1 P 0 ;0,1,2=60,3=90.000000
L 4.21666683 1.99986644 4.2175 1.9979997 1 P 0 ;0,1,2=60,3=90.000000
L 4.2175 1.9979997 4.21666683 1.99586634 1 P 0 ;0,1,2=60,3=90.000000
L 4.21666683 1.99586634 4.2149997 1.99426663 1 P 0 ;0,1,2=60,3=90.000000
L 4.2149997 1.99426663 4.2125003 1.9931998 1 P 0 ;0,1,2=60,3=90.000000
L 4.2125003 1.9931998 4.20916614 1.99266654 1 P 0 ;0,1,2=60,3=90.000000
L 4.20916614 1.99266654 4.2062501 1.9931998 1 P 0 ;0,1,2=60,3=90.000000
L 4.2062501 1.9931998 4.20333327 1.99453327 1 P 0 ;0,1,2=60,3=90.000000
L 4.20333327 1.99453327 4.20166614 1.99613346 1 P 0 ;0,1,2=60,3=90.000000
L 4.20166614 1.99613346 4.20124961 1.9979997 1 P 0 ;0,1,2=60,3=90.000000
L 4.20124961 1.9979997 4.20208278 2.00013307 1 P 0 ;0,1,2=60,3=90.000000
L 4.20208278 2.00013307 4.20416644 2.00173327 1 P 0 ;0,1,2=60,3=90.000000
L 4.20416644 2.00173327 4.20791634 2.00333337 1 P 0 ;0,1,2=60,3=90.000000
L 4.26445 2.1769 4.22745 2.1769 1 P 0 
L 4.26445 2.10051998 4.26445 2.1769 1 P 0 
L 4.22745 2.1769 4.22745 2.10051998 1 P 0 
L 4.22745 2.10051998 4.26445 2.10051998 1 P 0 
L 4.31041634 2.12286663 4.31166683 2.12126644 1 P 0 ;0,1,2=61,3=90.000000
L 4.31166683 2.12126644 4.3125 2.1194002 1 P 0 ;0,1,2=61,3=90.000000
L 4.3125 2.1194002 4.3125 2.11726683 1 P 0 ;0,1,2=61,3=90.000000
L 4.3125 2.11726683 4.31124941 2.11486634 1 P 0 ;0,1,2=61,3=90.000000
L 4.31124941 2.11486634 4.30916654 2.1130001 1 P 0 ;0,1,2=61,3=90.000000
L 4.30916654 2.1130001 4.30666634 2.11166654 1 P 0 ;0,1,2=61,3=90.000000
L 4.30666634 2.11166654 4.3024998 2.11059961 1 P 0 ;0,1,2=61,3=90.000000
L 4.3024998 2.11059961 4.2987498 2.11033297 1 P 0 ;0,1,2=61,3=90.000000
L 4.2987498 2.11033297 4.2949999 2.11086673 1 P 0 ;0,1,2=61,3=90.000000
L 4.2949999 2.11086673 4.29249961 2.11166654 1 P 0 ;0,1,2=61,3=90.000000
L 4.29249961 2.11166654 4.28999941 2.11326663 1 P 0 ;0,1,2=61,3=90.000000
L 4.28999941 2.11326663 4.28833307 2.11513346 1 P 0 ;0,1,2=61,3=90.000000
L 4.28833307 2.11513346 4.2875 2.1169997 1 P 0 ;0,1,2=61,3=90.000000
L 4.2875 2.1169997 4.2875 2.11886644 1 P 0 ;0,1,2=61,3=90.000000
L 4.2875 2.11886644 4.28833307 2.12073327 1 P 0 ;0,1,2=61,3=90.000000
L 4.28833307 2.12073327 4.28958287 2.12233337 1 P 0 ;0,1,2=61,3=90.000000
L 4.28958287 2.12233337 4.29124911 2.12366693 1 P 0 ;0,1,2=61,3=90.000000
L 4.2875 2.1389997 4.3125 2.1389997 1 P 0 ;0,1,2=61,3=90.000000
L 4.3125 2.1389997 4.3075003 2.1357999 1 P 0 ;0,1,2=61,3=90.000000
L 4.2875 2.1357999 4.2875 2.14219951 1 P 0 ;0,1,2=61,3=90.000000
L 4.29791594 2.15593317 4.30083346 2.1577999 1 P 0 ;0,1,2=61,3=90.000000
L 4.30083346 2.1577999 4.3024998 2.1594 1 P 0 ;0,1,2=61,3=90.000000
L 4.3024998 2.1594 4.30333297 2.16153337 1 P 0 ;0,1,2=61,3=90.000000
L 4.30333297 2.16153337 4.3024998 2.1634002 1 P 0 ;0,1,2=61,3=90.000000
L 4.3024998 2.1634002 4.30083346 2.16473327 1 P 0 ;0,1,2=61,3=90.000000
L 4.30083346 2.16473327 4.29833327 2.1658001 1 P 0 ;0,1,2=61,3=90.000000
L 4.29833327 2.1658001 4.29541644 2.16606673 1 P 0 ;0,1,2=61,3=90.000000
L 4.29541644 2.16606673 4.29291624 2.1658001 1 P 0 ;0,1,2=61,3=90.000000
L 4.29291624 2.1658001 4.29041604 2.16473327 1 P 0 ;0,1,2=61,3=90.000000
L 4.29041604 2.16473327 4.28833307 2.16313307 1 P 0 ;0,1,2=61,3=90.000000
L 4.28833307 2.16313307 4.2875 2.16126683 1 P 0 ;0,1,2=61,3=90.000000
L 4.2875 2.16126683 4.28833307 2.15913346 1 P 0 ;0,1,2=61,3=90.000000
L 4.28833307 2.15913346 4.29083258 2.15726663 1 P 0 ;0,1,2=61,3=90.000000
L 4.29083258 2.15726663 4.29458327 2.1561998 1 P 0 ;0,1,2=61,3=90.000000
L 4.29458327 2.1561998 4.2987498 2.15593317 1 P 0 ;0,1,2=61,3=90.000000
L 4.2987498 2.15593317 4.30416614 2.15646634 1 P 0 ;0,1,2=61,3=90.000000
L 4.30416614 2.15646634 4.30708366 2.15726663 1 P 0 ;0,1,2=61,3=90.000000
L 4.30708366 2.15726663 4.3099997 2.1585997 1 P 0 ;0,1,2=61,3=90.000000
L 4.3099997 2.1585997 4.31208337 2.16046654 1 P 0 ;0,1,2=61,3=90.000000
L 4.31208337 2.16046654 4.3125 2.16233327 1 P 0 ;0,1,2=61,3=90.000000
L 4.3125 2.16233327 4.31166683 2.1642 1 P 0 ;0,1,2=61,3=90.000000
L 4.31166683 2.1642 4.30958317 2.16553356 1 P 0 ;0,1,2=61,3=90.000000
L 4.30833337 2.17793317 4.31083287 2.17953327 1 P 0 ;0,1,2=61,3=90.000000
L 4.31083287 2.17953327 4.31208337 2.1814 1 P 0 ;0,1,2=61,3=90.000000
L 4.31208337 2.1814 4.3125 2.18353337 1 P 0 ;0,1,2=61,3=90.000000
L 4.3125 2.18353337 4.31166683 2.1862 1 P 0 ;0,1,2=61,3=90.000000
L 4.31166683 2.1862 4.30958317 2.18806673 1 P 0 ;0,1,2=61,3=90.000000
L 4.30958317 2.18806673 4.30708366 2.1886 1 P 0 ;0,1,2=61,3=90.000000
L 4.30708366 2.1886 4.30458268 2.18833337 1 P 0 ;0,1,2=61,3=90.000000
L 4.30458268 2.18833337 4.3024998 2.18726644 1 P 0 ;0,1,2=61,3=90.000000
L 4.3024998 2.18726644 4.29833327 2.18193327 1 P 0 ;0,1,2=61,3=90.000000
L 4.29833327 2.18193327 4.29541644 2.17953327 1 P 0 ;0,1,2=61,3=90.000000
L 4.29541644 2.17953327 4.29124911 2.17793317 1 P 0 ;0,1,2=61,3=90.000000
L 4.29124911 2.17793317 4.2875 2.1773999 1 P 0 ;0,1,2=61,3=90.000000
L 4.2875 2.1773999 4.2875 2.1886 1 P 0 ;0,1,2=61,3=90.000000
L 4.32856004 1.8793 4.32856004 1.95568002 1 P 0 
L 4.32856004 1.95568002 4.29156004 1.95568002 1 P 0 
L 4.29156004 1.95568002 4.29156004 1.8793 1 P 0 
L 4.29156004 1.8793 4.32856004 1.8793 1 P 0 
L 4.36041634 1.89286663 4.36166683 1.89126644 1 P 0 ;0,1,2=62,3=90.000000
L 4.36166683 1.89126644 4.3625 1.8894002 1 P 0 ;0,1,2=62,3=90.000000
L 4.3625 1.8894002 4.3625 1.88726683 1 P 0 ;0,1,2=62,3=90.000000
L 4.3625 1.88726683 4.36124941 1.88486634 1 P 0 ;0,1,2=62,3=90.000000
L 4.36124941 1.88486634 4.35916654 1.8830001 1 P 0 ;0,1,2=62,3=90.000000
L 4.35916654 1.8830001 4.35666634 1.88166654 1 P 0 ;0,1,2=62,3=90.000000
L 4.35666634 1.88166654 4.3524998 1.88059961 1 P 0 ;0,1,2=62,3=90.000000
L 4.3524998 1.88059961 4.3487498 1.88033297 1 P 0 ;0,1,2=62,3=90.000000
L 4.3487498 1.88033297 4.3449999 1.88086673 1 P 0 ;0,1,2=62,3=90.000000
L 4.3449999 1.88086673 4.34249961 1.88166654 1 P 0 ;0,1,2=62,3=90.000000
L 4.34249961 1.88166654 4.33999941 1.88326663 1 P 0 ;0,1,2=62,3=90.000000
L 4.33999941 1.88326663 4.33833307 1.88513346 1 P 0 ;0,1,2=62,3=90.000000
L 4.33833307 1.88513346 4.3375 1.8869997 1 P 0 ;0,1,2=62,3=90.000000
L 4.3375 1.8869997 4.3375 1.88886644 1 P 0 ;0,1,2=62,3=90.000000
L 4.3375 1.88886644 4.33833307 1.89073327 1 P 0 ;0,1,2=62,3=90.000000
L 4.33833307 1.89073327 4.33958287 1.89233337 1 P 0 ;0,1,2=62,3=90.000000
L 4.33958287 1.89233337 4.34124911 1.89366693 1 P 0 ;0,1,2=62,3=90.000000
L 4.3375 1.9089997 4.3625 1.9089997 1 P 0 ;0,1,2=62,3=90.000000
L 4.3625 1.9089997 4.3575003 1.9057999 1 P 0 ;0,1,2=62,3=90.000000
L 4.3375 1.9057999 4.3375 1.91219951 1 P 0 ;0,1,2=62,3=90.000000
L 4.3375 1.9342 4.3625 1.9342 1 P 0 ;0,1,2=62,3=90.000000
L 4.3625 1.9342 4.34458327 1.92433297 1 P 0 ;0,1,2=62,3=90.000000
L 4.34458327 1.92433297 4.34458327 1.93766693 1 P 0 ;0,1,2=62,3=90.000000
L 4.3375 1.9562 4.3625 1.9562 1 P 0 ;0,1,2=62,3=90.000000
L 4.3625 1.9562 4.34458327 1.94633297 1 P 0 ;0,1,2=62,3=90.000000
L 4.34458327 1.94633297 4.34458327 1.95966693 1 P 0 ;0,1,2=62,3=90.000000
L 4.22508002 1.82493002 4.22508002 1.90131004 1 P 0 
L 4.22508002 1.90131004 4.18808002 1.90131004 1 P 0 
L 4.18808002 1.90131004 4.18808002 1.82493002 1 P 0 
L 4.18808002 1.82493002 4.22508002 1.82493002 1 P 0 
L 4.25541634 1.89286663 4.25666683 1.89126644 1 P 0 ;0,1,2=63,3=90.000000
L 4.25666683 1.89126644 4.2575 1.8894002 1 P 0 ;0,1,2=63,3=90.000000
L 4.2575 1.8894002 4.2575 1.88726683 1 P 0 ;0,1,2=63,3=90.000000
L 4.2575 1.88726683 4.25624941 1.88486634 1 P 0 ;0,1,2=63,3=90.000000
L 4.25624941 1.88486634 4.25416654 1.8830001 1 P 0 ;0,1,2=63,3=90.000000
L 4.25416654 1.8830001 4.25166634 1.88166654 1 P 0 ;0,1,2=63,3=90.000000
L 4.25166634 1.88166654 4.2474998 1.88059961 1 P 0 ;0,1,2=63,3=90.000000
L 4.2474998 1.88059961 4.2437498 1.88033297 1 P 0 ;0,1,2=63,3=90.000000
L 4.2437498 1.88033297 4.2399999 1.88086673 1 P 0 ;0,1,2=63,3=90.000000
L 4.2399999 1.88086673 4.23749961 1.88166654 1 P 0 ;0,1,2=63,3=90.000000
L 4.23749961 1.88166654 4.23499941 1.88326663 1 P 0 ;0,1,2=63,3=90.000000
L 4.23499941 1.88326663 4.23333307 1.88513346 1 P 0 ;0,1,2=63,3=90.000000
L 4.23333307 1.88513346 4.2325 1.8869997 1 P 0 ;0,1,2=63,3=90.000000
L 4.2325 1.8869997 4.2325 1.88886644 1 P 0 ;0,1,2=63,3=90.000000
L 4.2325 1.88886644 4.23333307 1.89073327 1 P 0 ;0,1,2=63,3=90.000000
L 4.23333307 1.89073327 4.23458287 1.89233337 1 P 0 ;0,1,2=63,3=90.000000
L 4.23458287 1.89233337 4.23624911 1.89366693 1 P 0 ;0,1,2=63,3=90.000000
L 4.25333337 1.90393317 4.25583287 1.90553327 1 P 0 ;0,1,2=63,3=90.000000
L 4.25583287 1.90553327 4.25708337 1.9074 1 P 0 ;0,1,2=63,3=90.000000
L 4.25708337 1.9074 4.2575 1.90953337 1 P 0 ;0,1,2=63,3=90.000000
L 4.2575 1.90953337 4.25666683 1.9122 1 P 0 ;0,1,2=63,3=90.000000
L 4.25666683 1.9122 4.25458317 1.91406673 1 P 0 ;0,1,2=63,3=90.000000
L 4.25458317 1.91406673 4.25208366 1.9146 1 P 0 ;0,1,2=63,3=90.000000
L 4.25208366 1.9146 4.24958268 1.91433337 1 P 0 ;0,1,2=63,3=90.000000
L 4.24958268 1.91433337 4.2474998 1.91326644 1 P 0 ;0,1,2=63,3=90.000000
L 4.2474998 1.91326644 4.24333327 1.90793327 1 P 0 ;0,1,2=63,3=90.000000
L 4.24333327 1.90793327 4.24041644 1.90553327 1 P 0 ;0,1,2=63,3=90.000000
L 4.24041644 1.90553327 4.23624911 1.90393317 1 P 0 ;0,1,2=63,3=90.000000
L 4.23624911 1.90393317 4.2325 1.9033999 1 P 0 ;0,1,2=63,3=90.000000
L 4.2325 1.9033999 4.2325 1.9146 1 P 0 ;0,1,2=63,3=90.000000
L 4.25333337 1.92593317 4.25583287 1.92753327 1 P 0 ;0,1,2=63,3=90.000000
L 4.25583287 1.92753327 4.25708337 1.9294 1 P 0 ;0,1,2=63,3=90.000000
L 4.25708337 1.9294 4.2575 1.93153337 1 P 0 ;0,1,2=63,3=90.000000
L 4.2575 1.93153337 4.25666683 1.9342 1 P 0 ;0,1,2=63,3=90.000000
L 4.25666683 1.9342 4.25458317 1.93606673 1 P 0 ;0,1,2=63,3=90.000000
L 4.25458317 1.93606673 4.25208366 1.9366 1 P 0 ;0,1,2=63,3=90.000000
L 4.25208366 1.9366 4.24958268 1.93633337 1 P 0 ;0,1,2=63,3=90.000000
L 4.24958268 1.93633337 4.2474998 1.93526644 1 P 0 ;0,1,2=63,3=90.000000
L 4.2474998 1.93526644 4.24333327 1.92993327 1 P 0 ;0,1,2=63,3=90.000000
L 4.24333327 1.92993327 4.24041644 1.92753327 1 P 0 ;0,1,2=63,3=90.000000
L 4.24041644 1.92753327 4.23624911 1.92593317 1 P 0 ;0,1,2=63,3=90.000000
L 4.23624911 1.92593317 4.2325 1.9253999 1 P 0 ;0,1,2=63,3=90.000000
L 4.2325 1.9253999 4.2325 1.9366 1 P 0 ;0,1,2=63,3=90.000000
L 4.2325 1.9529997 4.2575 1.9529997 1 P 0 ;0,1,2=63,3=90.000000
L 4.2575 1.9529997 4.2525003 1.9497999 1 P 0 ;0,1,2=63,3=90.000000
L 4.2325 1.9497999 4.2325 1.95619951 1 P 0 ;0,1,2=63,3=90.000000
L 4.26445 1.82256004 4.18806998 1.82256004 1 P 0 
L 4.18806998 1.82256004 4.18806998 1.78556004 1 P 0 
L 4.18806998 1.78556004 4.26445 1.78556004 1 P 0 
L 4.26445 1.78556004 4.26445 1.82256004 1 P 0 
L 4.16213337 1.80541634 4.16373356 1.80666683 1 P 0 ;0,1,2=64,3=0.000000
L 4.16373356 1.80666683 4.1655998 1.8075 1 P 0 ;0,1,2=64,3=0.000000
L 4.1655998 1.8075 4.16773317 1.8075 1 P 0 ;0,1,2=64,3=0.000000
L 4.16773317 1.8075 4.17013366 1.80624941 1 P 0 ;0,1,2=64,3=0.000000
L 4.17013366 1.80624941 4.1719999 1.80416654 1 P 0 ;0,1,2=64,3=0.000000
L 4.1719999 1.80416654 4.17333346 1.80166634 1 P 0 ;0,1,2=64,3=0.000000
L 4.17333346 1.80166634 4.17440039 1.7974998 1 P 0 ;0,1,2=64,3=0.000000
L 4.17440039 1.7974998 4.17466703 1.7937498 1 P 0 ;0,1,2=64,3=0.000000
L 4.17466703 1.7937498 4.17413327 1.7899999 1 P 0 ;0,1,2=64,3=0.000000
L 4.17413327 1.7899999 4.17333346 1.78749961 1 P 0 ;0,1,2=64,3=0.000000
L 4.17333346 1.78749961 4.17173337 1.78499941 1 P 0 ;0,1,2=64,3=0.000000
L 4.17173337 1.78499941 4.16986654 1.78333307 1 P 0 ;0,1,2=64,3=0.000000
L 4.16986654 1.78333307 4.1680003 1.7825 1 P 0 ;0,1,2=64,3=0.000000
L 4.1680003 1.7825 4.16613356 1.7825 1 P 0 ;0,1,2=64,3=0.000000
L 4.16613356 1.7825 4.16426673 1.78333307 1 P 0 ;0,1,2=64,3=0.000000
L 4.16426673 1.78333307 4.16266663 1.78458287 1 P 0 ;0,1,2=64,3=0.000000
L 4.16266663 1.78458287 4.16133307 1.78624911 1 P 0 ;0,1,2=64,3=0.000000
L 4.15106683 1.80333337 4.14946673 1.80583287 1 P 0 ;0,1,2=64,3=0.000000
L 4.14946673 1.80583287 4.1476 1.80708337 1 P 0 ;0,1,2=64,3=0.000000
L 4.1476 1.80708337 4.14546663 1.8075 1 P 0 ;0,1,2=64,3=0.000000
L 4.14546663 1.8075 4.1428 1.80666683 1 P 0 ;0,1,2=64,3=0.000000
L 4.1428 1.80666683 4.14093327 1.80458317 1 P 0 ;0,1,2=64,3=0.000000
L 4.14093327 1.80458317 4.1404 1.80208366 1 P 0 ;0,1,2=64,3=0.000000
L 4.1404 1.80208366 4.14066663 1.79958268 1 P 0 ;0,1,2=64,3=0.000000
L 4.14066663 1.79958268 4.14173356 1.7974998 1 P 0 ;0,1,2=64,3=0.000000
L 4.14173356 1.7974998 4.14706673 1.79333327 1 P 0 ;0,1,2=64,3=0.000000
L 4.14706673 1.79333327 4.14946673 1.79041644 1 P 0 ;0,1,2=64,3=0.000000
L 4.14946673 1.79041644 4.15106683 1.78624911 1 P 0 ;0,1,2=64,3=0.000000
L 4.15106683 1.78624911 4.1516001 1.7825 1 P 0 ;0,1,2=64,3=0.000000
L 4.1516001 1.7825 4.1404 1.7825 1 P 0 ;0,1,2=64,3=0.000000
L 4.1240003 1.8075 4.12613366 1.80666683 1 P 0 ;0,1,2=64,3=0.000000
L 4.12613366 1.80666683 4.12773337 1.80458317 1 P 0 ;0,1,2=64,3=0.000000
L 4.12773337 1.80458317 4.1288002 1.80208366 1 P 0 ;0,1,2=64,3=0.000000
L 4.1288002 1.80208366 4.1296001 1.79874951 1 P 0 ;0,1,2=64,3=0.000000
L 4.1296001 1.79874951 4.12986673 1.79499961 1 P 0 ;0,1,2=64,3=0.000000
L 4.12986673 1.79499961 4.1296001 1.79124961 1 P 0 ;0,1,2=64,3=0.000000
L 4.1296001 1.79124961 4.1288002 1.78791624 1 P 0 ;0,1,2=64,3=0.000000
L 4.1288002 1.78791624 4.12773337 1.78541604 1 P 0 ;0,1,2=64,3=0.000000
L 4.12773337 1.78541604 4.12613366 1.78333307 1 P 0 ;0,1,2=64,3=0.000000
L 4.12613366 1.78333307 4.1240003 1.7825 1 P 0 ;0,1,2=64,3=0.000000
L 4.1240003 1.7825 4.12186693 1.78333307 1 P 0 ;0,1,2=64,3=0.000000
L 4.12186693 1.78333307 4.12026673 1.78541604 1 P 0 ;0,1,2=64,3=0.000000
L 4.12026673 1.78541604 4.1191999 1.78791624 1 P 0 ;0,1,2=64,3=0.000000
L 4.1191999 1.78791624 4.1184 1.79124961 1 P 0 ;0,1,2=64,3=0.000000
L 4.1184 1.79124961 4.11813337 1.79499961 1 P 0 ;0,1,2=64,3=0.000000
L 4.11813337 1.79499961 4.1184 1.79874951 1 P 0 ;0,1,2=64,3=0.000000
L 4.1184 1.79874951 4.1191999 1.80208366 1 P 0 ;0,1,2=64,3=0.000000
L 4.1191999 1.80208366 4.12026673 1.80458317 1 P 0 ;0,1,2=64,3=0.000000
L 4.12026673 1.80458317 4.12186693 1.80666683 1 P 0 ;0,1,2=64,3=0.000000
L 4.12186693 1.80666683 4.1240003 1.8075 1 P 0 ;0,1,2=64,3=0.000000
L 4.1020003 1.8075 4.10413366 1.80666683 1 P 0 ;0,1,2=64,3=0.000000
L 4.10413366 1.80666683 4.10573337 1.80458317 1 P 0 ;0,1,2=64,3=0.000000
L 4.10573337 1.80458317 4.1068002 1.80208366 1 P 0 ;0,1,2=64,3=0.000000
L 4.1068002 1.80208366 4.1076001 1.79874951 1 P 0 ;0,1,2=64,3=0.000000
L 4.1076001 1.79874951 4.10786673 1.79499961 1 P 0 ;0,1,2=64,3=0.000000
L 4.10786673 1.79499961 4.1076001 1.79124961 1 P 0 ;0,1,2=64,3=0.000000
L 4.1076001 1.79124961 4.1068002 1.78791624 1 P 0 ;0,1,2=64,3=0.000000
L 4.1068002 1.78791624 4.10573337 1.78541604 1 P 0 ;0,1,2=64,3=0.000000
L 4.10573337 1.78541604 4.10413366 1.78333307 1 P 0 ;0,1,2=64,3=0.000000
L 4.10413366 1.78333307 4.1020003 1.7825 1 P 0 ;0,1,2=64,3=0.000000
L 4.1020003 1.7825 4.09986693 1.78333307 1 P 0 ;0,1,2=64,3=0.000000
L 4.09986693 1.78333307 4.09826673 1.78541604 1 P 0 ;0,1,2=64,3=0.000000
L 4.09826673 1.78541604 4.0971999 1.78791624 1 P 0 ;0,1,2=64,3=0.000000
L 4.0971999 1.78791624 4.0964 1.79124961 1 P 0 ;0,1,2=64,3=0.000000
L 4.0964 1.79124961 4.09613337 1.79499961 1 P 0 ;0,1,2=64,3=0.000000
L 4.09613337 1.79499961 4.0964 1.79874951 1 P 0 ;0,1,2=64,3=0.000000
L 4.0964 1.79874951 4.0971999 1.80208366 1 P 0 ;0,1,2=64,3=0.000000
L 4.0971999 1.80208366 4.09826673 1.80458317 1 P 0 ;0,1,2=64,3=0.000000
L 4.09826673 1.80458317 4.09986693 1.80666683 1 P 0 ;0,1,2=64,3=0.000000
L 4.09986693 1.80666683 4.1020003 1.8075 1 P 0 ;0,1,2=64,3=0.000000
L 4.38256004 1.58871004 4.38256004 1.66508996 1 P 0 
L 4.38256004 1.66508996 4.34556004 1.66508996 1 P 0 
L 4.34556004 1.66508996 4.34556004 1.58871004 1 P 0 
L 4.34556004 1.58871004 4.38256004 1.58871004 1 P 0 
L 2.72041634 1.56786663 2.72166683 1.56626644 1 P 0 ;0,1,2=65,3=90.000000
L 2.72166683 1.56626644 2.7225 1.5644002 1 P 0 ;0,1,2=65,3=90.000000
L 2.7225 1.5644002 2.7225 1.56226683 1 P 0 ;0,1,2=65,3=90.000000
L 2.7225 1.56226683 2.72124941 1.55986634 1 P 0 ;0,1,2=65,3=90.000000
L 2.72124941 1.55986634 2.71916654 1.5580001 1 P 0 ;0,1,2=65,3=90.000000
L 2.71916654 1.5580001 2.71666634 1.55666654 1 P 0 ;0,1,2=65,3=90.000000
L 2.71666634 1.55666654 2.7124998 1.55559961 1 P 0 ;0,1,2=65,3=90.000000
L 2.7124998 1.55559961 2.7087498 1.55533297 1 P 0 ;0,1,2=65,3=90.000000
L 2.7087498 1.55533297 2.7049999 1.55586673 1 P 0 ;0,1,2=65,3=90.000000
L 2.7049999 1.55586673 2.70249961 1.55666654 1 P 0 ;0,1,2=65,3=90.000000
L 2.70249961 1.55666654 2.69999941 1.55826663 1 P 0 ;0,1,2=65,3=90.000000
L 2.69999941 1.55826663 2.69833307 1.56013346 1 P 0 ;0,1,2=65,3=90.000000
L 2.69833307 1.56013346 2.6975 1.5619997 1 P 0 ;0,1,2=65,3=90.000000
L 2.6975 1.5619997 2.6975 1.56386644 1 P 0 ;0,1,2=65,3=90.000000
L 2.6975 1.56386644 2.69833307 1.56573327 1 P 0 ;0,1,2=65,3=90.000000
L 2.69833307 1.56573327 2.69958287 1.56733337 1 P 0 ;0,1,2=65,3=90.000000
L 2.69958287 1.56733337 2.70124911 1.56866693 1 P 0 ;0,1,2=65,3=90.000000
L 2.6975 1.5839997 2.7225 1.5839997 1 P 0 ;0,1,2=65,3=90.000000
L 2.7225 1.5839997 2.7175003 1.5807999 1 P 0 ;0,1,2=65,3=90.000000
L 2.6975 1.5807999 2.6975 1.58719951 1 P 0 ;0,1,2=65,3=90.000000
L 2.71833337 1.60093317 2.72083287 1.60253327 1 P 0 ;0,1,2=65,3=90.000000
L 2.72083287 1.60253327 2.72208337 1.6044 1 P 0 ;0,1,2=65,3=90.000000
L 2.72208337 1.6044 2.7225 1.60653337 1 P 0 ;0,1,2=65,3=90.000000
L 2.7225 1.60653337 2.72166683 1.6092 1 P 0 ;0,1,2=65,3=90.000000
L 2.72166683 1.6092 2.71958317 1.61106673 1 P 0 ;0,1,2=65,3=90.000000
L 2.71958317 1.61106673 2.71708366 1.6116 1 P 0 ;0,1,2=65,3=90.000000
L 2.71708366 1.6116 2.71458268 1.61133337 1 P 0 ;0,1,2=65,3=90.000000
L 2.71458268 1.61133337 2.7124998 1.61026644 1 P 0 ;0,1,2=65,3=90.000000
L 2.7124998 1.61026644 2.70833327 1.60493327 1 P 0 ;0,1,2=65,3=90.000000
L 2.70833327 1.60493327 2.70541644 1.60253327 1 P 0 ;0,1,2=65,3=90.000000
L 2.70541644 1.60253327 2.70124911 1.60093317 1 P 0 ;0,1,2=65,3=90.000000
L 2.70124911 1.60093317 2.6975 1.6003999 1 P 0 ;0,1,2=65,3=90.000000
L 2.6975 1.6003999 2.6975 1.6116 1 P 0 ;0,1,2=65,3=90.000000
L 2.70041604 1.62346634 2.69833307 1.62533317 1 P 0 ;0,1,2=65,3=90.000000
L 2.69833307 1.62533317 2.6975 1.62746654 1 P 0 ;0,1,2=65,3=90.000000
L 2.6975 1.62746654 2.69833307 1.6295999 1 P 0 ;0,1,2=65,3=90.000000
L 2.69833307 1.6295999 2.70083258 1.63146663 1 P 0 ;0,1,2=65,3=90.000000
L 2.70083258 1.63146663 2.70458327 1.6328001 1 P 0 ;0,1,2=65,3=90.000000
L 2.70458327 1.6328001 2.70833327 1.63333337 1 P 0 ;0,1,2=65,3=90.000000
L 2.70833327 1.63333337 2.71291634 1.63333337 1 P 0 ;0,1,2=65,3=90.000000
L 2.71291634 1.63333337 2.71666634 1.6328001 1 P 0 ;0,1,2=65,3=90.000000
L 2.71666634 1.6328001 2.7199997 1.63146663 1 P 0 ;0,1,2=65,3=90.000000
L 2.7199997 1.63146663 2.72166683 1.62986644 1 P 0 ;0,1,2=65,3=90.000000
L 2.72166683 1.62986644 2.7225 1.6279997 1 P 0 ;0,1,2=65,3=90.000000
L 2.7225 1.6279997 2.72166683 1.62586634 1 P 0 ;0,1,2=65,3=90.000000
L 2.72166683 1.62586634 2.7199997 1.62426663 1 P 0 ;0,1,2=65,3=90.000000
L 2.7199997 1.62426663 2.7175003 1.6231998 1 P 0 ;0,1,2=65,3=90.000000
L 2.7175003 1.6231998 2.71416614 1.62266654 1 P 0 ;0,1,2=65,3=90.000000
L 2.71416614 1.62266654 2.7112501 1.6231998 1 P 0 ;0,1,2=65,3=90.000000
L 2.7112501 1.6231998 2.70833327 1.62453327 1 P 0 ;0,1,2=65,3=90.000000
L 2.70833327 1.62453327 2.70666614 1.62613346 1 P 0 ;0,1,2=65,3=90.000000
L 2.70666614 1.62613346 2.70624961 1.6279997 1 P 0 ;0,1,2=65,3=90.000000
L 2.70624961 1.6279997 2.70708278 1.63013307 1 P 0 ;0,1,2=65,3=90.000000
L 2.70708278 1.63013307 2.70916644 1.63173327 1 P 0 ;0,1,2=65,3=90.000000
L 2.70916644 1.63173327 2.71291634 1.63333337 1 P 0 ;0,1,2=65,3=90.000000
L 4.42193996 1.78556004 4.42193996 1.82256004 1 P 0 
L 4.42193996 1.82256004 4.34556004 1.82256004 1 P 0 
L 4.34556004 1.78556004 4.42193996 1.78556004 1 P 0 
L 4.34556004 1.82256004 4.34556004 1.78556004 1 P 0 
L 2.71213337 1.77541634 2.71373356 1.77666683 1 P 0 ;0,1,2=66,3=0.000000
L 2.71373356 1.77666683 2.7155998 1.7775 1 P 0 ;0,1,2=66,3=0.000000
L 2.7155998 1.7775 2.71773317 1.7775 1 P 0 ;0,1,2=66,3=0.000000
L 2.71773317 1.7775 2.72013366 1.77624941 1 P 0 ;0,1,2=66,3=0.000000
L 2.72013366 1.77624941 2.7219999 1.77416654 1 P 0 ;0,1,2=66,3=0.000000
L 2.7219999 1.77416654 2.72333346 1.77166634 1 P 0 ;0,1,2=66,3=0.000000
L 2.72333346 1.77166634 2.72440039 1.7674998 1 P 0 ;0,1,2=66,3=0.000000
L 2.72440039 1.7674998 2.72466703 1.7637498 1 P 0 ;0,1,2=66,3=0.000000
L 2.72466703 1.7637498 2.72413327 1.7599999 1 P 0 ;0,1,2=66,3=0.000000
L 2.72413327 1.7599999 2.72333346 1.75749961 1 P 0 ;0,1,2=66,3=0.000000
L 2.72333346 1.75749961 2.72173337 1.75499941 1 P 0 ;0,1,2=66,3=0.000000
L 2.72173337 1.75499941 2.71986654 1.75333307 1 P 0 ;0,1,2=66,3=0.000000
L 2.71986654 1.75333307 2.7180003 1.7525 1 P 0 ;0,1,2=66,3=0.000000
L 2.7180003 1.7525 2.71613356 1.7525 1 P 0 ;0,1,2=66,3=0.000000
L 2.71613356 1.7525 2.71426673 1.75333307 1 P 0 ;0,1,2=66,3=0.000000
L 2.71426673 1.75333307 2.71266663 1.75458287 1 P 0 ;0,1,2=66,3=0.000000
L 2.71266663 1.75458287 2.71133307 1.75624911 1 P 0 ;0,1,2=66,3=0.000000
L 2.70106683 1.77333337 2.69946673 1.77583287 1 P 0 ;0,1,2=66,3=0.000000
L 2.69946673 1.77583287 2.6976 1.77708337 1 P 0 ;0,1,2=66,3=0.000000
L 2.6976 1.77708337 2.69546663 1.7775 1 P 0 ;0,1,2=66,3=0.000000
L 2.69546663 1.7775 2.6928 1.77666683 1 P 0 ;0,1,2=66,3=0.000000
L 2.6928 1.77666683 2.69093327 1.77458317 1 P 0 ;0,1,2=66,3=0.000000
L 2.69093327 1.77458317 2.6904 1.77208366 1 P 0 ;0,1,2=66,3=0.000000
L 2.6904 1.77208366 2.69066663 1.76958268 1 P 0 ;0,1,2=66,3=0.000000
L 2.69066663 1.76958268 2.69173356 1.7674998 1 P 0 ;0,1,2=66,3=0.000000
L 2.69173356 1.7674998 2.69706673 1.76333327 1 P 0 ;0,1,2=66,3=0.000000
L 2.69706673 1.76333327 2.69946673 1.76041644 1 P 0 ;0,1,2=66,3=0.000000
L 2.69946673 1.76041644 2.70106683 1.75624911 1 P 0 ;0,1,2=66,3=0.000000
L 2.70106683 1.75624911 2.7016001 1.7525 1 P 0 ;0,1,2=66,3=0.000000
L 2.7016001 1.7525 2.6904 1.7525 1 P 0 ;0,1,2=66,3=0.000000
L 2.6740003 1.7775 2.67613366 1.77666683 1 P 0 ;0,1,2=66,3=0.000000
L 2.67613366 1.77666683 2.67773337 1.77458317 1 P 0 ;0,1,2=66,3=0.000000
L 2.67773337 1.77458317 2.6788002 1.77208366 1 P 0 ;0,1,2=66,3=0.000000
L 2.6788002 1.77208366 2.6796001 1.76874951 1 P 0 ;0,1,2=66,3=0.000000
L 2.6796001 1.76874951 2.67986673 1.76499961 1 P 0 ;0,1,2=66,3=0.000000
L 2.67986673 1.76499961 2.6796001 1.76124961 1 P 0 ;0,1,2=66,3=0.000000
L 2.6796001 1.76124961 2.6788002 1.75791624 1 P 0 ;0,1,2=66,3=0.000000
L 2.6788002 1.75791624 2.67773337 1.75541604 1 P 0 ;0,1,2=66,3=0.000000
L 2.67773337 1.75541604 2.67613366 1.75333307 1 P 0 ;0,1,2=66,3=0.000000
L 2.67613366 1.75333307 2.6740003 1.7525 1 P 0 ;0,1,2=66,3=0.000000
L 2.6740003 1.7525 2.67186693 1.75333307 1 P 0 ;0,1,2=66,3=0.000000
L 2.67186693 1.75333307 2.67026673 1.75541604 1 P 0 ;0,1,2=66,3=0.000000
L 2.67026673 1.75541604 2.6691999 1.75791624 1 P 0 ;0,1,2=66,3=0.000000
L 2.6691999 1.75791624 2.6684 1.76124961 1 P 0 ;0,1,2=66,3=0.000000
L 2.6684 1.76124961 2.66813337 1.76499961 1 P 0 ;0,1,2=66,3=0.000000
L 2.66813337 1.76499961 2.6684 1.76874951 1 P 0 ;0,1,2=66,3=0.000000
L 2.6684 1.76874951 2.6691999 1.77208366 1 P 0 ;0,1,2=66,3=0.000000
L 2.6691999 1.77208366 2.67026673 1.77458317 1 P 0 ;0,1,2=66,3=0.000000
L 2.67026673 1.77458317 2.67186693 1.77666683 1 P 0 ;0,1,2=66,3=0.000000
L 2.67186693 1.77666683 2.6740003 1.7775 1 P 0 ;0,1,2=66,3=0.000000
L 2.65706683 1.76291594 2.6552001 1.76583346 1 P 0 ;0,1,2=66,3=0.000000
L 2.6552001 1.76583346 2.6536 1.7674998 1 P 0 ;0,1,2=66,3=0.000000
L 2.6536 1.7674998 2.65146663 1.76833297 1 P 0 ;0,1,2=66,3=0.000000
L 2.65146663 1.76833297 2.6495998 1.7674998 1 P 0 ;0,1,2=66,3=0.000000
L 2.6495998 1.7674998 2.64826673 1.76583346 1 P 0 ;0,1,2=66,3=0.000000
L 2.64826673 1.76583346 2.6471999 1.76333327 1 P 0 ;0,1,2=66,3=0.000000
L 2.6471999 1.76333327 2.64693327 1.76041644 1 P 0 ;0,1,2=66,3=0.000000
L 2.64693327 1.76041644 2.6471999 1.75791624 1 P 0 ;0,1,2=66,3=0.000000
L 2.6471999 1.75791624 2.64826673 1.75541604 1 P 0 ;0,1,2=66,3=0.000000
L 2.64826673 1.75541604 2.64986693 1.75333307 1 P 0 ;0,1,2=66,3=0.000000
L 2.64986693 1.75333307 2.65173317 1.7525 1 P 0 ;0,1,2=66,3=0.000000
L 2.65173317 1.7525 2.65386654 1.75333307 1 P 0 ;0,1,2=66,3=0.000000
L 2.65386654 1.75333307 2.65573337 1.75583258 1 P 0 ;0,1,2=66,3=0.000000
L 2.65573337 1.75583258 2.6568002 1.75958327 1 P 0 ;0,1,2=66,3=0.000000
L 2.6568002 1.75958327 2.65706683 1.7637498 1 P 0 ;0,1,2=66,3=0.000000
L 2.65706683 1.7637498 2.65653366 1.76916614 1 P 0 ;0,1,2=66,3=0.000000
L 2.65653366 1.76916614 2.65573337 1.77208366 1 P 0 ;0,1,2=66,3=0.000000
L 2.65573337 1.77208366 2.6544003 1.7749997 1 P 0 ;0,1,2=66,3=0.000000
L 2.6544003 1.7749997 2.65253346 1.77708337 1 P 0 ;0,1,2=66,3=0.000000
L 2.65253346 1.77708337 2.65066673 1.7775 1 P 0 ;0,1,2=66,3=0.000000
L 2.65066673 1.7775 2.6488 1.77666683 1 P 0 ;0,1,2=66,3=0.000000
L 2.6488 1.77666683 2.64746644 1.77458317 1 P 0 ;0,1,2=66,3=0.000000
L 4.54003996 1.78556004 4.54003996 1.86193996 1 P 0 
L 4.54003996 1.86193996 4.50303996 1.86193996 1 P 0 
L 4.50303996 1.86193996 4.50303996 1.78556004 1 P 0 
L 4.50303996 1.78556004 4.54003996 1.78556004 1 P 0 
L 2.83541634 1.71786663 2.83666683 1.71626644 1 P 0 ;0,1,2=67,3=90.000000
L 2.83666683 1.71626644 2.8375 1.7144002 1 P 0 ;0,1,2=67,3=90.000000
L 2.8375 1.7144002 2.8375 1.71226683 1 P 0 ;0,1,2=67,3=90.000000
L 2.8375 1.71226683 2.83624941 1.70986634 1 P 0 ;0,1,2=67,3=90.000000
L 2.83624941 1.70986634 2.83416654 1.7080001 1 P 0 ;0,1,2=67,3=90.000000
L 2.83416654 1.7080001 2.83166634 1.70666654 1 P 0 ;0,1,2=67,3=90.000000
L 2.83166634 1.70666654 2.8274998 1.70559961 1 P 0 ;0,1,2=67,3=90.000000
L 2.8274998 1.70559961 2.8237498 1.70533297 1 P 0 ;0,1,2=67,3=90.000000
L 2.8237498 1.70533297 2.8199999 1.70586673 1 P 0 ;0,1,2=67,3=90.000000
L 2.8199999 1.70586673 2.81749961 1.70666654 1 P 0 ;0,1,2=67,3=90.000000
L 2.81749961 1.70666654 2.81499941 1.70826663 1 P 0 ;0,1,2=67,3=90.000000
L 2.81499941 1.70826663 2.81333307 1.71013346 1 P 0 ;0,1,2=67,3=90.000000
L 2.81333307 1.71013346 2.8125 1.7119997 1 P 0 ;0,1,2=67,3=90.000000
L 2.8125 1.7119997 2.8125 1.71386644 1 P 0 ;0,1,2=67,3=90.000000
L 2.8125 1.71386644 2.81333307 1.71573327 1 P 0 ;0,1,2=67,3=90.000000
L 2.81333307 1.71573327 2.81458287 1.71733337 1 P 0 ;0,1,2=67,3=90.000000
L 2.81458287 1.71733337 2.81624911 1.71866693 1 P 0 ;0,1,2=67,3=90.000000
L 2.8125 1.7339997 2.8375 1.7339997 1 P 0 ;0,1,2=67,3=90.000000
L 2.8375 1.7339997 2.8325003 1.7307999 1 P 0 ;0,1,2=67,3=90.000000
L 2.8125 1.7307999 2.8125 1.73719951 1 P 0 ;0,1,2=67,3=90.000000
L 2.8375 1.7559997 2.83666683 1.75386634 1 P 0 ;0,1,2=67,3=90.000000
L 2.83666683 1.75386634 2.83458317 1.75226663 1 P 0 ;0,1,2=67,3=90.000000
L 2.83458317 1.75226663 2.83208366 1.7511998 1 P 0 ;0,1,2=67,3=90.000000
L 2.83208366 1.7511998 2.82874951 1.7503999 1 P 0 ;0,1,2=67,3=90.000000
L 2.82874951 1.7503999 2.82499961 1.75013327 1 P 0 ;0,1,2=67,3=90.000000
L 2.82499961 1.75013327 2.82124961 1.7503999 1 P 0 ;0,1,2=67,3=90.000000
L 2.82124961 1.7503999 2.81791624 1.7511998 1 P 0 ;0,1,2=67,3=90.000000
L 2.81791624 1.7511998 2.81541604 1.75226663 1 P 0 ;0,1,2=67,3=90.000000
L 2.81541604 1.75226663 2.81333307 1.75386634 1 P 0 ;0,1,2=67,3=90.000000
L 2.81333307 1.75386634 2.8125 1.7559997 1 P 0 ;0,1,2=67,3=90.000000
L 2.8125 1.7559997 2.81333307 1.75813307 1 P 0 ;0,1,2=67,3=90.000000
L 2.81333307 1.75813307 2.81541604 1.75973327 1 P 0 ;0,1,2=67,3=90.000000
L 2.81541604 1.75973327 2.81791624 1.7608001 1 P 0 ;0,1,2=67,3=90.000000
L 2.81791624 1.7608001 2.82124961 1.7616 1 P 0 ;0,1,2=67,3=90.000000
L 2.82124961 1.7616 2.82499961 1.76186663 1 P 0 ;0,1,2=67,3=90.000000
L 2.82499961 1.76186663 2.82874951 1.7616 1 P 0 ;0,1,2=67,3=90.000000
L 2.82874951 1.7616 2.83208366 1.7608001 1 P 0 ;0,1,2=67,3=90.000000
L 2.83208366 1.7608001 2.83458317 1.75973327 1 P 0 ;0,1,2=67,3=90.000000
L 2.83458317 1.75973327 2.83666683 1.75813307 1 P 0 ;0,1,2=67,3=90.000000
L 2.83666683 1.75813307 2.8375 1.7559997 1 P 0 ;0,1,2=67,3=90.000000
L 2.8125 1.77746654 2.81791624 1.7779997 1 P 0 ;0,1,2=67,3=90.000000
L 2.81791624 1.7779997 2.82249931 1.7788 1 P 0 ;0,1,2=67,3=90.000000
L 2.82249931 1.7788 2.82666663 1.77986644 1 P 0 ;0,1,2=67,3=90.000000
L 2.82666663 1.77986644 2.8312498 1.7812 1 P 0 ;0,1,2=67,3=90.000000
L 2.8312498 1.7812 2.8375 1.78333337 1 P 0 ;0,1,2=67,3=90.000000
L 2.8375 1.78333337 2.8375 1.77266654 1 P 0 ;0,1,2=67,3=90.000000
L 4.69753002 1.82256004 4.62115 1.82256004 1 P 0 
L 4.62115 1.78556004 4.69753002 1.78556004 1 P 0 
L 4.69753002 1.78556004 4.69753002 1.82256004 1 P 0 
L 4.62115 1.82256004 4.62115 1.78556004 1 P 0 
L 4.77713337 1.76541634 4.77873356 1.76666683 1 P 0 ;0,1,2=68,3=0.000000
L 4.77873356 1.76666683 4.7805998 1.7675 1 P 0 ;0,1,2=68,3=0.000000
L 4.7805998 1.7675 4.78273317 1.7675 1 P 0 ;0,1,2=68,3=0.000000
L 4.78273317 1.7675 4.78513366 1.76624941 1 P 0 ;0,1,2=68,3=0.000000
L 4.78513366 1.76624941 4.7869999 1.76416654 1 P 0 ;0,1,2=68,3=0.000000
L 4.7869999 1.76416654 4.78833346 1.76166634 1 P 0 ;0,1,2=68,3=0.000000
L 4.78833346 1.76166634 4.78940039 1.7574998 1 P 0 ;0,1,2=68,3=0.000000
L 4.78940039 1.7574998 4.78966703 1.7537498 1 P 0 ;0,1,2=68,3=0.000000
L 4.78966703 1.7537498 4.78913327 1.7499999 1 P 0 ;0,1,2=68,3=0.000000
L 4.78913327 1.7499999 4.78833346 1.74749961 1 P 0 ;0,1,2=68,3=0.000000
L 4.78833346 1.74749961 4.78673337 1.74499941 1 P 0 ;0,1,2=68,3=0.000000
L 4.78673337 1.74499941 4.78486654 1.74333307 1 P 0 ;0,1,2=68,3=0.000000
L 4.78486654 1.74333307 4.7830003 1.7425 1 P 0 ;0,1,2=68,3=0.000000
L 4.7830003 1.7425 4.78113356 1.7425 1 P 0 ;0,1,2=68,3=0.000000
L 4.78113356 1.7425 4.77926673 1.74333307 1 P 0 ;0,1,2=68,3=0.000000
L 4.77926673 1.74333307 4.77766663 1.74458287 1 P 0 ;0,1,2=68,3=0.000000
L 4.77766663 1.74458287 4.77633307 1.74624911 1 P 0 ;0,1,2=68,3=0.000000
L 4.7610003 1.7425 4.7610003 1.7675 1 P 0 ;0,1,2=68,3=0.000000
L 4.7610003 1.7675 4.7642001 1.7625003 1 P 0 ;0,1,2=68,3=0.000000
L 4.7642001 1.7425 4.75780049 1.7425 1 P 0 ;0,1,2=68,3=0.000000
L 4.74486673 1.74749961 4.74326703 1.74458287 1 P 0 ;0,1,2=68,3=0.000000
L 4.74326703 1.74458287 4.74113366 1.74291654 1 P 0 ;0,1,2=68,3=0.000000
L 4.74113366 1.74291654 4.73873317 1.7425 1 P 0 ;0,1,2=68,3=0.000000
L 4.73873317 1.7425 4.7365998 1.74291654 1 P 0 ;0,1,2=68,3=0.000000
L 4.7365998 1.74291654 4.73446644 1.74499941 1 P 0 ;0,1,2=68,3=0.000000
L 4.73446644 1.74499941 4.73313337 1.74749961 1 P 0 ;0,1,2=68,3=0.000000
L 4.73313337 1.74749961 4.73286683 1.7499999 1 P 0 ;0,1,2=68,3=0.000000
L 4.73286683 1.7499999 4.7334 1.75291594 1 P 0 ;0,1,2=68,3=0.000000
L 4.7334 1.75291594 4.73526673 1.75499961 1 P 0 ;0,1,2=68,3=0.000000
L 4.73526673 1.75499961 4.73713356 1.75583346 1 P 0 ;0,1,2=68,3=0.000000
L 4.73713356 1.75583346 4.73953346 1.75583346 1 P 0 ;0,1,2=68,3=0.000000
L 4.73713356 1.75583346 4.73553337 1.75708327 1 P 0 ;0,1,2=68,3=0.000000
L 4.73553337 1.75708327 4.7341999 1.75916614 1 P 0 ;0,1,2=68,3=0.000000
L 4.7341999 1.75916614 4.73366663 1.76166634 1 P 0 ;0,1,2=68,3=0.000000
L 4.73366663 1.76166634 4.7341999 1.76416654 1 P 0 ;0,1,2=68,3=0.000000
L 4.7341999 1.76416654 4.73553337 1.76624941 1 P 0 ;0,1,2=68,3=0.000000
L 4.73553337 1.76624941 4.73793337 1.7675 1 P 0 ;0,1,2=68,3=0.000000
L 4.73793337 1.7675 4.74033337 1.76708337 1 P 0 ;0,1,2=68,3=0.000000
L 4.74033337 1.76708337 4.74273337 1.76541634 1 P 0 ;0,1,2=68,3=0.000000
L 4.72153366 1.74541604 4.71966683 1.74333307 1 P 0 ;0,1,2=68,3=0.000000
L 4.71966683 1.74333307 4.71753346 1.7425 1 P 0 ;0,1,2=68,3=0.000000
L 4.71753346 1.7425 4.7154001 1.74333307 1 P 0 ;0,1,2=68,3=0.000000
L 4.7154001 1.74333307 4.71353337 1.74583258 1 P 0 ;0,1,2=68,3=0.000000
L 4.71353337 1.74583258 4.7121999 1.74958327 1 P 0 ;0,1,2=68,3=0.000000
L 4.7121999 1.74958327 4.71166663 1.75333327 1 P 0 ;0,1,2=68,3=0.000000
L 4.71166663 1.75333327 4.71166663 1.75791634 1 P 0 ;0,1,2=68,3=0.000000
L 4.71166663 1.75791634 4.7121999 1.76166634 1 P 0 ;0,1,2=68,3=0.000000
L 4.7121999 1.76166634 4.71353337 1.7649997 1 P 0 ;0,1,2=68,3=0.000000
L 4.71353337 1.7649997 4.71513356 1.76666683 1 P 0 ;0,1,2=68,3=0.000000
L 4.71513356 1.76666683 4.7170003 1.7675 1 P 0 ;0,1,2=68,3=0.000000
L 4.7170003 1.7675 4.71913366 1.76666683 1 P 0 ;0,1,2=68,3=0.000000
L 4.71913366 1.76666683 4.72073337 1.7649997 1 P 0 ;0,1,2=68,3=0.000000
L 4.72073337 1.7649997 4.7218002 1.7625003 1 P 0 ;0,1,2=68,3=0.000000
L 4.7218002 1.7625003 4.72233346 1.75916614 1 P 0 ;0,1,2=68,3=0.000000
L 4.72233346 1.75916614 4.7218002 1.7562501 1 P 0 ;0,1,2=68,3=0.000000
L 4.7218002 1.7562501 4.72046673 1.75333327 1 P 0 ;0,1,2=68,3=0.000000
L 4.72046673 1.75333327 4.71886654 1.75166614 1 P 0 ;0,1,2=68,3=0.000000
L 4.71886654 1.75166614 4.7170003 1.75124961 1 P 0 ;0,1,2=68,3=0.000000
L 4.7170003 1.75124961 4.71486693 1.75208278 1 P 0 ;0,1,2=68,3=0.000000
L 4.71486693 1.75208278 4.71326673 1.75416644 1 P 0 ;0,1,2=68,3=0.000000
L 4.71326673 1.75416644 4.71166663 1.75791634 1 P 0 ;0,1,2=68,3=0.000000
L 4.65815 1.70445 4.58176998 1.70445 1 P 0 
L 4.58176998 1.70445 4.58176998 1.66745 1 P 0 
L 4.58176998 1.66745 4.65815 1.66745 1 P 0 
L 4.65815 1.66745 4.65815 1.70445 1 P 0 
L 4.79041634 1.62786663 4.79166683 1.62626644 1 P 0 ;0,1,2=69,3=90.000000
L 4.79166683 1.62626644 4.7925 1.6244002 1 P 0 ;0,1,2=69,3=90.000000
L 4.7925 1.6244002 4.7925 1.62226683 1 P 0 ;0,1,2=69,3=90.000000
L 4.7925 1.62226683 4.79124941 1.61986634 1 P 0 ;0,1,2=69,3=90.000000
L 4.79124941 1.61986634 4.78916654 1.6180001 1 P 0 ;0,1,2=69,3=90.000000
L 4.78916654 1.6180001 4.78666634 1.61666654 1 P 0 ;0,1,2=69,3=90.000000
L 4.78666634 1.61666654 4.7824998 1.61559961 1 P 0 ;0,1,2=69,3=90.000000
L 4.7824998 1.61559961 4.7787498 1.61533297 1 P 0 ;0,1,2=69,3=90.000000
L 4.7787498 1.61533297 4.7749999 1.61586673 1 P 0 ;0,1,2=69,3=90.000000
L 4.7749999 1.61586673 4.77249961 1.61666654 1 P 0 ;0,1,2=69,3=90.000000
L 4.77249961 1.61666654 4.76999941 1.61826663 1 P 0 ;0,1,2=69,3=90.000000
L 4.76999941 1.61826663 4.76833307 1.62013346 1 P 0 ;0,1,2=69,3=90.000000
L 4.76833307 1.62013346 4.7675 1.6219997 1 P 0 ;0,1,2=69,3=90.000000
L 4.7675 1.6219997 4.7675 1.62386644 1 P 0 ;0,1,2=69,3=90.000000
L 4.7675 1.62386644 4.76833307 1.62573327 1 P 0 ;0,1,2=69,3=90.000000
L 4.76833307 1.62573327 4.76958287 1.62733337 1 P 0 ;0,1,2=69,3=90.000000
L 4.76958287 1.62733337 4.77124911 1.62866693 1 P 0 ;0,1,2=69,3=90.000000
L 4.78833337 1.63893317 4.79083287 1.64053327 1 P 0 ;0,1,2=69,3=90.000000
L 4.79083287 1.64053327 4.79208337 1.6424 1 P 0 ;0,1,2=69,3=90.000000
L 4.79208337 1.6424 4.7925 1.64453337 1 P 0 ;0,1,2=69,3=90.000000
L 4.7925 1.64453337 4.79166683 1.6472 1 P 0 ;0,1,2=69,3=90.000000
L 4.79166683 1.6472 4.78958317 1.64906673 1 P 0 ;0,1,2=69,3=90.000000
L 4.78958317 1.64906673 4.78708366 1.6496 1 P 0 ;0,1,2=69,3=90.000000
L 4.78708366 1.6496 4.78458268 1.64933337 1 P 0 ;0,1,2=69,3=90.000000
L 4.78458268 1.64933337 4.7824998 1.64826644 1 P 0 ;0,1,2=69,3=90.000000
L 4.7824998 1.64826644 4.77833327 1.64293327 1 P 0 ;0,1,2=69,3=90.000000
L 4.77833327 1.64293327 4.77541644 1.64053327 1 P 0 ;0,1,2=69,3=90.000000
L 4.77541644 1.64053327 4.77124911 1.63893317 1 P 0 ;0,1,2=69,3=90.000000
L 4.77124911 1.63893317 4.7675 1.6383999 1 P 0 ;0,1,2=69,3=90.000000
L 4.7675 1.6383999 4.7675 1.6496 1 P 0 ;0,1,2=69,3=90.000000
L 4.7675 1.6659997 4.7925 1.6659997 1 P 0 ;0,1,2=69,3=90.000000
L 4.7925 1.6659997 4.7875003 1.6627999 1 P 0 ;0,1,2=69,3=90.000000
L 4.7675 1.6627999 4.7675 1.66919951 1 P 0 ;0,1,2=69,3=90.000000
L 4.7925 1.6879997 4.79166683 1.68586634 1 P 0 ;0,1,2=69,3=90.000000
L 4.79166683 1.68586634 4.78958317 1.68426663 1 P 0 ;0,1,2=69,3=90.000000
L 4.78958317 1.68426663 4.78708366 1.6831998 1 P 0 ;0,1,2=69,3=90.000000
L 4.78708366 1.6831998 4.78374951 1.6823999 1 P 0 ;0,1,2=69,3=90.000000
L 4.78374951 1.6823999 4.77999961 1.68213327 1 P 0 ;0,1,2=69,3=90.000000
L 4.77999961 1.68213327 4.77624961 1.6823999 1 P 0 ;0,1,2=69,3=90.000000
L 4.77624961 1.6823999 4.77291624 1.6831998 1 P 0 ;0,1,2=69,3=90.000000
L 4.77291624 1.6831998 4.77041604 1.68426663 1 P 0 ;0,1,2=69,3=90.000000
L 4.77041604 1.68426663 4.76833307 1.68586634 1 P 0 ;0,1,2=69,3=90.000000
L 4.76833307 1.68586634 4.7675 1.6879997 1 P 0 ;0,1,2=69,3=90.000000
L 4.7675 1.6879997 4.76833307 1.69013307 1 P 0 ;0,1,2=69,3=90.000000
L 4.76833307 1.69013307 4.77041604 1.69173327 1 P 0 ;0,1,2=69,3=90.000000
L 4.77041604 1.69173327 4.77291624 1.6928001 1 P 0 ;0,1,2=69,3=90.000000
L 4.77291624 1.6928001 4.77624961 1.6936 1 P 0 ;0,1,2=69,3=90.000000
L 4.77624961 1.6936 4.77999961 1.69386663 1 P 0 ;0,1,2=69,3=90.000000
L 4.77999961 1.69386663 4.78374951 1.6936 1 P 0 ;0,1,2=69,3=90.000000
L 4.78374951 1.6936 4.78708366 1.6928001 1 P 0 ;0,1,2=69,3=90.000000
L 4.78708366 1.6928001 4.78958317 1.69173327 1 P 0 ;0,1,2=69,3=90.000000
L 4.78958317 1.69173327 4.79166683 1.69013307 1 P 0 ;0,1,2=69,3=90.000000
L 4.79166683 1.69013307 4.7925 1.6879997 1 P 0 ;0,1,2=69,3=90.000000
L 4.69751998 1.58633996 4.62113996 1.58633996 1 P 0 
L 4.62113996 1.58633996 4.62113996 1.54933996 1 P 0 
L 4.62113996 1.54933996 4.69751998 1.54933996 1 P 0 
L 4.69751998 1.54933996 4.69751998 1.58633996 1 P 0 
L 4.77713337 1.59541634 4.77873356 1.59666683 1 P 0 ;0,1,2=70,3=0.000000
L 4.77873356 1.59666683 4.7805998 1.5975 1 P 0 ;0,1,2=70,3=0.000000
L 4.7805998 1.5975 4.78273317 1.5975 1 P 0 ;0,1,2=70,3=0.000000
L 4.78273317 1.5975 4.78513366 1.59624941 1 P 0 ;0,1,2=70,3=0.000000
L 4.78513366 1.59624941 4.7869999 1.59416654 1 P 0 ;0,1,2=70,3=0.000000
L 4.7869999 1.59416654 4.78833346 1.59166634 1 P 0 ;0,1,2=70,3=0.000000
L 4.78833346 1.59166634 4.78940039 1.5874998 1 P 0 ;0,1,2=70,3=0.000000
L 4.78940039 1.5874998 4.78966703 1.5837498 1 P 0 ;0,1,2=70,3=0.000000
L 4.78966703 1.5837498 4.78913327 1.5799999 1 P 0 ;0,1,2=70,3=0.000000
L 4.78913327 1.5799999 4.78833346 1.57749961 1 P 0 ;0,1,2=70,3=0.000000
L 4.78833346 1.57749961 4.78673337 1.57499941 1 P 0 ;0,1,2=70,3=0.000000
L 4.78673337 1.57499941 4.78486654 1.57333307 1 P 0 ;0,1,2=70,3=0.000000
L 4.78486654 1.57333307 4.7830003 1.5725 1 P 0 ;0,1,2=70,3=0.000000
L 4.7830003 1.5725 4.78113356 1.5725 1 P 0 ;0,1,2=70,3=0.000000
L 4.78113356 1.5725 4.77926673 1.57333307 1 P 0 ;0,1,2=70,3=0.000000
L 4.77926673 1.57333307 4.77766663 1.57458287 1 P 0 ;0,1,2=70,3=0.000000
L 4.77766663 1.57458287 4.77633307 1.57624911 1 P 0 ;0,1,2=70,3=0.000000
L 4.7610003 1.5725 4.7610003 1.5975 1 P 0 ;0,1,2=70,3=0.000000
L 4.7610003 1.5975 4.7642001 1.5925003 1 P 0 ;0,1,2=70,3=0.000000
L 4.7642001 1.5725 4.75780049 1.5725 1 P 0 ;0,1,2=70,3=0.000000
L 4.74486673 1.57624911 4.74326703 1.57416624 1 P 0 ;0,1,2=70,3=0.000000
L 4.74326703 1.57416624 4.7414003 1.57291654 1 P 0 ;0,1,2=70,3=0.000000
L 4.7414003 1.57291654 4.7390003 1.5725 1 P 0 ;0,1,2=70,3=0.000000
L 4.7390003 1.5725 4.7365998 1.57333307 1 P 0 ;0,1,2=70,3=0.000000
L 4.7365998 1.57333307 4.73473356 1.57499941 1 P 0 ;0,1,2=70,3=0.000000
L 4.73473356 1.57499941 4.7334 1.57791624 1 P 0 ;0,1,2=70,3=0.000000
L 4.7334 1.57791624 4.73313337 1.58124961 1 P 0 ;0,1,2=70,3=0.000000
L 4.73313337 1.58124961 4.73366663 1.58458297 1 P 0 ;0,1,2=70,3=0.000000
L 4.73366663 1.58458297 4.7350002 1.58666663 1 P 0 ;0,1,2=70,3=0.000000
L 4.7350002 1.58666663 4.73686693 1.58833297 1 P 0 ;0,1,2=70,3=0.000000
L 4.73686693 1.58833297 4.73873317 1.58874951 1 P 0 ;0,1,2=70,3=0.000000
L 4.73873317 1.58874951 4.7406 1.58833297 1 P 0 ;0,1,2=70,3=0.000000
L 4.7406 1.58833297 4.7429999 1.58666663 1 P 0 ;0,1,2=70,3=0.000000
L 4.7429999 1.58666663 4.7422001 1.5975 1 P 0 ;0,1,2=70,3=0.000000
L 4.7422001 1.5975 4.7350002 1.5975 1 P 0 ;0,1,2=70,3=0.000000
L 4.7170003 1.5725 4.7170003 1.5975 1 P 0 ;0,1,2=70,3=0.000000
L 4.7170003 1.5975 4.7202001 1.5925003 1 P 0 ;0,1,2=70,3=0.000000
L 4.7202001 1.5725 4.71380049 1.5725 1 P 0 ;0,1,2=70,3=0.000000
L 4.38493002 1.70445 4.38493002 1.62806998 1 P 0 
L 4.38493002 1.62806998 4.42193002 1.62806998 1 P 0 
L 4.42193002 1.62806998 4.42193002 1.70445 1 P 0 
L 4.42193002 1.70445 4.38493002 1.70445 1 P 0 
L 2.76081634 1.59416663 2.76206683 1.59256644 1 P 0 ;0,1,2=71,3=90.000000
L 2.76206683 1.59256644 2.7629 1.5907002 1 P 0 ;0,1,2=71,3=90.000000
L 2.7629 1.5907002 2.7629 1.58856683 1 P 0 ;0,1,2=71,3=90.000000
L 2.7629 1.58856683 2.76164941 1.58616634 1 P 0 ;0,1,2=71,3=90.000000
L 2.76164941 1.58616634 2.75956654 1.5843001 1 P 0 ;0,1,2=71,3=90.000000
L 2.75956654 1.5843001 2.75706634 1.58296654 1 P 0 ;0,1,2=71,3=90.000000
L 2.75706634 1.58296654 2.7528998 1.58189961 1 P 0 ;0,1,2=71,3=90.000000
L 2.7528998 1.58189961 2.7491498 1.58163297 1 P 0 ;0,1,2=71,3=90.000000
L 2.7491498 1.58163297 2.7453999 1.58216673 1 P 0 ;0,1,2=71,3=90.000000
L 2.7453999 1.58216673 2.74289961 1.58296654 1 P 0 ;0,1,2=71,3=90.000000
L 2.74289961 1.58296654 2.74039941 1.58456663 1 P 0 ;0,1,2=71,3=90.000000
L 2.74039941 1.58456663 2.73873307 1.58643346 1 P 0 ;0,1,2=71,3=90.000000
L 2.73873307 1.58643346 2.7379 1.5882997 1 P 0 ;0,1,2=71,3=90.000000
L 2.7379 1.5882997 2.7379 1.59016644 1 P 0 ;0,1,2=71,3=90.000000
L 2.7379 1.59016644 2.73873307 1.59203327 1 P 0 ;0,1,2=71,3=90.000000
L 2.73873307 1.59203327 2.73998287 1.59363337 1 P 0 ;0,1,2=71,3=90.000000
L 2.73998287 1.59363337 2.74164911 1.59496693 1 P 0 ;0,1,2=71,3=90.000000
L 2.75873337 1.60523317 2.76123287 1.60683327 1 P 0 ;0,1,2=71,3=90.000000
L 2.76123287 1.60683327 2.76248337 1.6087 1 P 0 ;0,1,2=71,3=90.000000
L 2.76248337 1.6087 2.7629 1.61083337 1 P 0 ;0,1,2=71,3=90.000000
L 2.7629 1.61083337 2.76206683 1.6135 1 P 0 ;0,1,2=71,3=90.000000
L 2.76206683 1.6135 2.75998317 1.61536673 1 P 0 ;0,1,2=71,3=90.000000
L 2.75998317 1.61536673 2.75748366 1.6159 1 P 0 ;0,1,2=71,3=90.000000
L 2.75748366 1.6159 2.75498268 1.61563337 1 P 0 ;0,1,2=71,3=90.000000
L 2.75498268 1.61563337 2.7528998 1.61456644 1 P 0 ;0,1,2=71,3=90.000000
L 2.7528998 1.61456644 2.74873327 1.60923327 1 P 0 ;0,1,2=71,3=90.000000
L 2.74873327 1.60923327 2.74581644 1.60683327 1 P 0 ;0,1,2=71,3=90.000000
L 2.74581644 1.60683327 2.74164911 1.60523317 1 P 0 ;0,1,2=71,3=90.000000
L 2.74164911 1.60523317 2.7379 1.6046999 1 P 0 ;0,1,2=71,3=90.000000
L 2.7379 1.6046999 2.7379 1.6159 1 P 0 ;0,1,2=71,3=90.000000
L 2.7629 1.6322997 2.76206683 1.63016634 1 P 0 ;0,1,2=71,3=90.000000
L 2.76206683 1.63016634 2.75998317 1.62856663 1 P 0 ;0,1,2=71,3=90.000000
L 2.75998317 1.62856663 2.75748366 1.6274998 1 P 0 ;0,1,2=71,3=90.000000
L 2.75748366 1.6274998 2.75414951 1.6266999 1 P 0 ;0,1,2=71,3=90.000000
L 2.75414951 1.6266999 2.75039961 1.62643327 1 P 0 ;0,1,2=71,3=90.000000
L 2.75039961 1.62643327 2.74664961 1.6266999 1 P 0 ;0,1,2=71,3=90.000000
L 2.74664961 1.6266999 2.74331624 1.6274998 1 P 0 ;0,1,2=71,3=90.000000
L 2.74331624 1.6274998 2.74081604 1.62856663 1 P 0 ;0,1,2=71,3=90.000000
L 2.74081604 1.62856663 2.73873307 1.63016634 1 P 0 ;0,1,2=71,3=90.000000
L 2.73873307 1.63016634 2.7379 1.6322997 1 P 0 ;0,1,2=71,3=90.000000
L 2.7379 1.6322997 2.73873307 1.63443307 1 P 0 ;0,1,2=71,3=90.000000
L 2.73873307 1.63443307 2.74081604 1.63603327 1 P 0 ;0,1,2=71,3=90.000000
L 2.74081604 1.63603327 2.74331624 1.6371001 1 P 0 ;0,1,2=71,3=90.000000
L 2.74331624 1.6371001 2.74664961 1.6379 1 P 0 ;0,1,2=71,3=90.000000
L 2.74664961 1.6379 2.75039961 1.63816663 1 P 0 ;0,1,2=71,3=90.000000
L 2.75039961 1.63816663 2.75414951 1.6379 1 P 0 ;0,1,2=71,3=90.000000
L 2.75414951 1.6379 2.75748366 1.6371001 1 P 0 ;0,1,2=71,3=90.000000
L 2.75748366 1.6371001 2.75998317 1.63603327 1 P 0 ;0,1,2=71,3=90.000000
L 2.75998317 1.63603327 2.76206683 1.63443307 1 P 0 ;0,1,2=71,3=90.000000
L 2.76206683 1.63443307 2.7629 1.6322997 1 P 0 ;0,1,2=71,3=90.000000
L 2.7379 1.6542997 2.7629 1.6542997 1 P 0 ;0,1,2=71,3=90.000000
L 2.7629 1.6542997 2.7579003 1.6510999 1 P 0 ;0,1,2=71,3=90.000000
L 2.7379 1.6510999 2.7379 1.65749951 1 P 0 ;0,1,2=71,3=90.000000
L 4.4613 1.62571998 4.4243 1.62571998 1 P 0 
L 4.4613 1.54933996 4.4613 1.62571998 1 P 0 
L 4.4243 1.62571998 4.4243 1.54933996 1 P 0 
L 4.4243 1.54933996 4.4613 1.54933996 1 P 0 
L 2.80021634 1.50536663 2.80146683 1.50376644 1 P 0 ;0,1,2=72,3=90.000000
L 2.80146683 1.50376644 2.8023 1.5019002 1 P 0 ;0,1,2=72,3=90.000000
L 2.8023 1.5019002 2.8023 1.49976683 1 P 0 ;0,1,2=72,3=90.000000
L 2.8023 1.49976683 2.80104941 1.49736634 1 P 0 ;0,1,2=72,3=90.000000
L 2.80104941 1.49736634 2.79896654 1.4955001 1 P 0 ;0,1,2=72,3=90.000000
L 2.79896654 1.4955001 2.79646634 1.49416654 1 P 0 ;0,1,2=72,3=90.000000
L 2.79646634 1.49416654 2.7922998 1.49309961 1 P 0 ;0,1,2=72,3=90.000000
L 2.7922998 1.49309961 2.7885498 1.49283297 1 P 0 ;0,1,2=72,3=90.000000
L 2.7885498 1.49283297 2.7847999 1.49336673 1 P 0 ;0,1,2=72,3=90.000000
L 2.7847999 1.49336673 2.78229961 1.49416654 1 P 0 ;0,1,2=72,3=90.000000
L 2.78229961 1.49416654 2.77979941 1.49576663 1 P 0 ;0,1,2=72,3=90.000000
L 2.77979941 1.49576663 2.77813307 1.49763346 1 P 0 ;0,1,2=72,3=90.000000
L 2.77813307 1.49763346 2.7773 1.4994997 1 P 0 ;0,1,2=72,3=90.000000
L 2.7773 1.4994997 2.7773 1.50136644 1 P 0 ;0,1,2=72,3=90.000000
L 2.7773 1.50136644 2.77813307 1.50323327 1 P 0 ;0,1,2=72,3=90.000000
L 2.77813307 1.50323327 2.77938287 1.50483337 1 P 0 ;0,1,2=72,3=90.000000
L 2.77938287 1.50483337 2.78104911 1.50616693 1 P 0 ;0,1,2=72,3=90.000000
L 2.7773 1.5214997 2.8023 1.5214997 1 P 0 ;0,1,2=72,3=90.000000
L 2.8023 1.5214997 2.7973003 1.5182999 1 P 0 ;0,1,2=72,3=90.000000
L 2.7773 1.5182999 2.7773 1.52469951 1 P 0 ;0,1,2=72,3=90.000000
L 2.78771594 1.53843317 2.79063346 1.5402999 1 P 0 ;0,1,2=72,3=90.000000
L 2.79063346 1.5402999 2.7922998 1.5419 1 P 0 ;0,1,2=72,3=90.000000
L 2.7922998 1.5419 2.79313297 1.54403337 1 P 0 ;0,1,2=72,3=90.000000
L 2.79313297 1.54403337 2.7922998 1.5459002 1 P 0 ;0,1,2=72,3=90.000000
L 2.7922998 1.5459002 2.79063346 1.54723327 1 P 0 ;0,1,2=72,3=90.000000
L 2.79063346 1.54723327 2.78813327 1.5483001 1 P 0 ;0,1,2=72,3=90.000000
L 2.78813327 1.5483001 2.78521644 1.54856673 1 P 0 ;0,1,2=72,3=90.000000
L 2.78521644 1.54856673 2.78271624 1.5483001 1 P 0 ;0,1,2=72,3=90.000000
L 2.78271624 1.5483001 2.78021604 1.54723327 1 P 0 ;0,1,2=72,3=90.000000
L 2.78021604 1.54723327 2.77813307 1.54563307 1 P 0 ;0,1,2=72,3=90.000000
L 2.77813307 1.54563307 2.7773 1.54376683 1 P 0 ;0,1,2=72,3=90.000000
L 2.7773 1.54376683 2.77813307 1.54163346 1 P 0 ;0,1,2=72,3=90.000000
L 2.77813307 1.54163346 2.78063258 1.53976663 1 P 0 ;0,1,2=72,3=90.000000
L 2.78063258 1.53976663 2.78438327 1.5386998 1 P 0 ;0,1,2=72,3=90.000000
L 2.78438327 1.5386998 2.7885498 1.53843317 1 P 0 ;0,1,2=72,3=90.000000
L 2.7885498 1.53843317 2.79396614 1.53896634 1 P 0 ;0,1,2=72,3=90.000000
L 2.79396614 1.53896634 2.79688366 1.53976663 1 P 0 ;0,1,2=72,3=90.000000
L 2.79688366 1.53976663 2.7997997 1.5410997 1 P 0 ;0,1,2=72,3=90.000000
L 2.7997997 1.5410997 2.80188337 1.54296654 1 P 0 ;0,1,2=72,3=90.000000
L 2.80188337 1.54296654 2.8023 1.54483327 1 P 0 ;0,1,2=72,3=90.000000
L 2.8023 1.54483327 2.80146683 1.5467 1 P 0 ;0,1,2=72,3=90.000000
L 2.80146683 1.5467 2.79938317 1.54803356 1 P 0 ;0,1,2=72,3=90.000000
L 2.7773 1.5654997 2.8023 1.5654997 1 P 0 ;0,1,2=72,3=90.000000
L 2.8023 1.5654997 2.7973003 1.5622999 1 P 0 ;0,1,2=72,3=90.000000
L 2.7773 1.5622999 2.7773 1.56869951 1 P 0 ;0,1,2=72,3=90.000000
L 4.4243 1.62808002 4.50068002 1.62808002 1 P 0 
L 4.50068002 1.62808002 4.50068002 1.66508002 1 P 0 
L 4.50068002 1.66508002 4.4243 1.66508002 1 P 0 
L 4.4243 1.66508002 4.4243 1.62808002 1 P 0 
L 2.83963337 1.60901634 2.84123356 1.61026683 1 P 0 ;0,1,2=73,3=0.000000
L 2.84123356 1.61026683 2.8430998 1.6111 1 P 0 ;0,1,2=73,3=0.000000
L 2.8430998 1.6111 2.84523317 1.6111 1 P 0 ;0,1,2=73,3=0.000000
L 2.84523317 1.6111 2.84763366 1.60984941 1 P 0 ;0,1,2=73,3=0.000000
L 2.84763366 1.60984941 2.8494999 1.60776654 1 P 0 ;0,1,2=73,3=0.000000
L 2.8494999 1.60776654 2.85083346 1.60526634 1 P 0 ;0,1,2=73,3=0.000000
L 2.85083346 1.60526634 2.85190039 1.6010998 1 P 0 ;0,1,2=73,3=0.000000
L 2.85190039 1.6010998 2.85216703 1.5973498 1 P 0 ;0,1,2=73,3=0.000000
L 2.85216703 1.5973498 2.85163327 1.5935999 1 P 0 ;0,1,2=73,3=0.000000
L 2.85163327 1.5935999 2.85083346 1.59109961 1 P 0 ;0,1,2=73,3=0.000000
L 2.85083346 1.59109961 2.84923337 1.58859941 1 P 0 ;0,1,2=73,3=0.000000
L 2.84923337 1.58859941 2.84736654 1.58693307 1 P 0 ;0,1,2=73,3=0.000000
L 2.84736654 1.58693307 2.8455003 1.5861 1 P 0 ;0,1,2=73,3=0.000000
L 2.8455003 1.5861 2.84363356 1.5861 1 P 0 ;0,1,2=73,3=0.000000
L 2.84363356 1.5861 2.84176673 1.58693307 1 P 0 ;0,1,2=73,3=0.000000
L 2.84176673 1.58693307 2.84016663 1.58818287 1 P 0 ;0,1,2=73,3=0.000000
L 2.84016663 1.58818287 2.83883307 1.58984911 1 P 0 ;0,1,2=73,3=0.000000
L 2.8235003 1.5861 2.8235003 1.6111 1 P 0 ;0,1,2=73,3=0.000000
L 2.8235003 1.6111 2.8267001 1.6061003 1 P 0 ;0,1,2=73,3=0.000000
L 2.8267001 1.5861 2.82030049 1.5861 1 P 0 ;0,1,2=73,3=0.000000
L 2.7983 1.5861 2.7983 1.6111 1 P 0 ;0,1,2=73,3=0.000000
L 2.7983 1.6111 2.80816703 1.59318327 1 P 0 ;0,1,2=73,3=0.000000
L 2.80816703 1.59318327 2.79483307 1.59318327 1 P 0 ;0,1,2=73,3=0.000000
L 2.78003346 1.5861 2.7795003 1.59151624 1 P 0 ;0,1,2=73,3=0.000000
L 2.7795003 1.59151624 2.7787 1.59609931 1 P 0 ;0,1,2=73,3=0.000000
L 2.7787 1.59609931 2.77763356 1.60026663 1 P 0 ;0,1,2=73,3=0.000000
L 2.77763356 1.60026663 2.7763 1.6048498 1 P 0 ;0,1,2=73,3=0.000000
L 2.7763 1.6048498 2.77416663 1.6111 1 P 0 ;0,1,2=73,3=0.000000
L 2.77416663 1.6111 2.78483346 1.6111 1 P 0 ;0,1,2=73,3=0.000000
L 4.50066998 1.62571004 4.46366998 1.62571004 1 P 0 
L 4.46366998 1.62571004 4.46366998 1.54933002 1 P 0 
L 4.46366998 1.54933002 4.50066998 1.54933002 1 P 0 
L 4.50066998 1.54933002 4.50066998 1.62571004 1 P 0 
L 2.83961634 1.50536663 2.84086683 1.50376644 1 P 0 ;0,1,2=74,3=90.000000
L 2.84086683 1.50376644 2.8417 1.5019002 1 P 0 ;0,1,2=74,3=90.000000
L 2.8417 1.5019002 2.8417 1.49976683 1 P 0 ;0,1,2=74,3=90.000000
L 2.8417 1.49976683 2.84044941 1.49736634 1 P 0 ;0,1,2=74,3=90.000000
L 2.84044941 1.49736634 2.83836654 1.4955001 1 P 0 ;0,1,2=74,3=90.000000
L 2.83836654 1.4955001 2.83586634 1.49416654 1 P 0 ;0,1,2=74,3=90.000000
L 2.83586634 1.49416654 2.8316998 1.49309961 1 P 0 ;0,1,2=74,3=90.000000
L 2.8316998 1.49309961 2.8279498 1.49283297 1 P 0 ;0,1,2=74,3=90.000000
L 2.8279498 1.49283297 2.8241999 1.49336673 1 P 0 ;0,1,2=74,3=90.000000
L 2.8241999 1.49336673 2.82169961 1.49416654 1 P 0 ;0,1,2=74,3=90.000000
L 2.82169961 1.49416654 2.81919941 1.49576663 1 P 0 ;0,1,2=74,3=90.000000
L 2.81919941 1.49576663 2.81753307 1.49763346 1 P 0 ;0,1,2=74,3=90.000000
L 2.81753307 1.49763346 2.8167 1.4994997 1 P 0 ;0,1,2=74,3=90.000000
L 2.8167 1.4994997 2.8167 1.50136644 1 P 0 ;0,1,2=74,3=90.000000
L 2.8167 1.50136644 2.81753307 1.50323327 1 P 0 ;0,1,2=74,3=90.000000
L 2.81753307 1.50323327 2.81878287 1.50483337 1 P 0 ;0,1,2=74,3=90.000000
L 2.81878287 1.50483337 2.82044911 1.50616693 1 P 0 ;0,1,2=74,3=90.000000
L 2.8167 1.5214997 2.8417 1.5214997 1 P 0 ;0,1,2=74,3=90.000000
L 2.8417 1.5214997 2.8367003 1.5182999 1 P 0 ;0,1,2=74,3=90.000000
L 2.8167 1.5182999 2.8167 1.52469951 1 P 0 ;0,1,2=74,3=90.000000
L 2.82044911 1.53763327 2.81836624 1.53923297 1 P 0 ;0,1,2=74,3=90.000000
L 2.81836624 1.53923297 2.81711654 1.5410997 1 P 0 ;0,1,2=74,3=90.000000
L 2.81711654 1.5410997 2.8167 1.5434997 1 P 0 ;0,1,2=74,3=90.000000
L 2.8167 1.5434997 2.81753307 1.5459002 1 P 0 ;0,1,2=74,3=90.000000
L 2.81753307 1.5459002 2.81919941 1.54776644 1 P 0 ;0,1,2=74,3=90.000000
L 2.81919941 1.54776644 2.82211624 1.5491 1 P 0 ;0,1,2=74,3=90.000000
L 2.82211624 1.5491 2.82544961 1.54936663 1 P 0 ;0,1,2=74,3=90.000000
L 2.82544961 1.54936663 2.82878297 1.54883337 1 P 0 ;0,1,2=74,3=90.000000
L 2.82878297 1.54883337 2.83086663 1.5474998 1 P 0 ;0,1,2=74,3=90.000000
L 2.83086663 1.5474998 2.83253297 1.54563307 1 P 0 ;0,1,2=74,3=90.000000
L 2.83253297 1.54563307 2.83294951 1.54376683 1 P 0 ;0,1,2=74,3=90.000000
L 2.83294951 1.54376683 2.83253297 1.5419 1 P 0 ;0,1,2=74,3=90.000000
L 2.83253297 1.5419 2.83086663 1.5395001 1 P 0 ;0,1,2=74,3=90.000000
L 2.83086663 1.5395001 2.8417 1.5402999 1 P 0 ;0,1,2=74,3=90.000000
L 2.8417 1.5402999 2.8417 1.5474998 1 P 0 ;0,1,2=74,3=90.000000
L 2.83753337 1.56043317 2.84003287 1.56203327 1 P 0 ;0,1,2=74,3=90.000000
L 2.84003287 1.56203327 2.84128337 1.5639 1 P 0 ;0,1,2=74,3=90.000000
L 2.84128337 1.5639 2.8417 1.56603337 1 P 0 ;0,1,2=74,3=90.000000
L 2.8417 1.56603337 2.84086683 1.5687 1 P 0 ;0,1,2=74,3=90.000000
L 2.84086683 1.5687 2.83878317 1.57056673 1 P 0 ;0,1,2=74,3=90.000000
L 2.83878317 1.57056673 2.83628366 1.5711 1 P 0 ;0,1,2=74,3=90.000000
L 2.83628366 1.5711 2.83378268 1.57083337 1 P 0 ;0,1,2=74,3=90.000000
L 2.83378268 1.57083337 2.8316998 1.56976644 1 P 0 ;0,1,2=74,3=90.000000
L 2.8316998 1.56976644 2.82753327 1.56443327 1 P 0 ;0,1,2=74,3=90.000000
L 2.82753327 1.56443327 2.82461644 1.56203327 1 P 0 ;0,1,2=74,3=90.000000
L 2.82461644 1.56203327 2.82044911 1.56043317 1 P 0 ;0,1,2=74,3=90.000000
L 2.82044911 1.56043317 2.8167 1.5598999 1 P 0 ;0,1,2=74,3=90.000000
L 2.8167 1.5598999 2.8167 1.5711 1 P 0 ;0,1,2=74,3=90.000000
L 4.54003996 1.62806998 4.54003996 1.70445 1 P 0 
L 4.50303996 1.70445 4.50303996 1.62806998 1 P 0 
L 4.50303996 1.62806998 4.54003996 1.62806998 1 P 0 
L 4.54003996 1.70445 4.50303996 1.70445 1 P 0 
L 2.89041634 1.58786663 2.89166683 1.58626644 1 P 0 ;0,1,2=75,3=90.000000
L 2.89166683 1.58626644 2.8925 1.5844002 1 P 0 ;0,1,2=75,3=90.000000
L 2.8925 1.5844002 2.8925 1.58226683 1 P 0 ;0,1,2=75,3=90.000000
L 2.8925 1.58226683 2.89124941 1.57986634 1 P 0 ;0,1,2=75,3=90.000000
L 2.89124941 1.57986634 2.88916654 1.5780001 1 P 0 ;0,1,2=75,3=90.000000
L 2.88916654 1.5780001 2.88666634 1.57666654 1 P 0 ;0,1,2=75,3=90.000000
L 2.88666634 1.57666654 2.8824998 1.57559961 1 P 0 ;0,1,2=75,3=90.000000
L 2.8824998 1.57559961 2.8787498 1.57533297 1 P 0 ;0,1,2=75,3=90.000000
L 2.8787498 1.57533297 2.8749999 1.57586673 1 P 0 ;0,1,2=75,3=90.000000
L 2.8749999 1.57586673 2.87249961 1.57666654 1 P 0 ;0,1,2=75,3=90.000000
L 2.87249961 1.57666654 2.86999941 1.57826663 1 P 0 ;0,1,2=75,3=90.000000
L 2.86999941 1.57826663 2.86833307 1.58013346 1 P 0 ;0,1,2=75,3=90.000000
L 2.86833307 1.58013346 2.8675 1.5819997 1 P 0 ;0,1,2=75,3=90.000000
L 2.8675 1.5819997 2.8675 1.58386644 1 P 0 ;0,1,2=75,3=90.000000
L 2.8675 1.58386644 2.86833307 1.58573327 1 P 0 ;0,1,2=75,3=90.000000
L 2.86833307 1.58573327 2.86958287 1.58733337 1 P 0 ;0,1,2=75,3=90.000000
L 2.86958287 1.58733337 2.87124911 1.58866693 1 P 0 ;0,1,2=75,3=90.000000
L 2.88833337 1.59893317 2.89083287 1.60053327 1 P 0 ;0,1,2=75,3=90.000000
L 2.89083287 1.60053327 2.89208337 1.6024 1 P 0 ;0,1,2=75,3=90.000000
L 2.89208337 1.6024 2.8925 1.60453337 1 P 0 ;0,1,2=75,3=90.000000
L 2.8925 1.60453337 2.89166683 1.6072 1 P 0 ;0,1,2=75,3=90.000000
L 2.89166683 1.6072 2.88958317 1.60906673 1 P 0 ;0,1,2=75,3=90.000000
L 2.88958317 1.60906673 2.88708366 1.6096 1 P 0 ;0,1,2=75,3=90.000000
L 2.88708366 1.6096 2.88458268 1.60933337 1 P 0 ;0,1,2=75,3=90.000000
L 2.88458268 1.60933337 2.8824998 1.60826644 1 P 0 ;0,1,2=75,3=90.000000
L 2.8824998 1.60826644 2.87833327 1.60293327 1 P 0 ;0,1,2=75,3=90.000000
L 2.87833327 1.60293327 2.87541644 1.60053327 1 P 0 ;0,1,2=75,3=90.000000
L 2.87541644 1.60053327 2.87124911 1.59893317 1 P 0 ;0,1,2=75,3=90.000000
L 2.87124911 1.59893317 2.8675 1.5983999 1 P 0 ;0,1,2=75,3=90.000000
L 2.8675 1.5983999 2.8675 1.6096 1 P 0 ;0,1,2=75,3=90.000000
L 2.8925 1.6259997 2.89166683 1.62386634 1 P 0 ;0,1,2=75,3=90.000000
L 2.89166683 1.62386634 2.88958317 1.62226663 1 P 0 ;0,1,2=75,3=90.000000
L 2.88958317 1.62226663 2.88708366 1.6211998 1 P 0 ;0,1,2=75,3=90.000000
L 2.88708366 1.6211998 2.88374951 1.6203999 1 P 0 ;0,1,2=75,3=90.000000
L 2.88374951 1.6203999 2.87999961 1.62013327 1 P 0 ;0,1,2=75,3=90.000000
L 2.87999961 1.62013327 2.87624961 1.6203999 1 P 0 ;0,1,2=75,3=90.000000
L 2.87624961 1.6203999 2.87291624 1.6211998 1 P 0 ;0,1,2=75,3=90.000000
L 2.87291624 1.6211998 2.87041604 1.62226663 1 P 0 ;0,1,2=75,3=90.000000
L 2.87041604 1.62226663 2.86833307 1.62386634 1 P 0 ;0,1,2=75,3=90.000000
L 2.86833307 1.62386634 2.8675 1.6259997 1 P 0 ;0,1,2=75,3=90.000000
L 2.8675 1.6259997 2.86833307 1.62813307 1 P 0 ;0,1,2=75,3=90.000000
L 2.86833307 1.62813307 2.87041604 1.62973327 1 P 0 ;0,1,2=75,3=90.000000
L 2.87041604 1.62973327 2.87291624 1.6308001 1 P 0 ;0,1,2=75,3=90.000000
L 2.87291624 1.6308001 2.87624961 1.6316 1 P 0 ;0,1,2=75,3=90.000000
L 2.87624961 1.6316 2.87999961 1.63186663 1 P 0 ;0,1,2=75,3=90.000000
L 2.87999961 1.63186663 2.88374951 1.6316 1 P 0 ;0,1,2=75,3=90.000000
L 2.88374951 1.6316 2.88708366 1.6308001 1 P 0 ;0,1,2=75,3=90.000000
L 2.88708366 1.6308001 2.88958317 1.62973327 1 P 0 ;0,1,2=75,3=90.000000
L 2.88958317 1.62973327 2.89166683 1.62813307 1 P 0 ;0,1,2=75,3=90.000000
L 2.89166683 1.62813307 2.8925 1.6259997 1 P 0 ;0,1,2=75,3=90.000000
L 2.8675 1.64746654 2.87291624 1.6479997 1 P 0 ;0,1,2=75,3=90.000000
L 2.87291624 1.6479997 2.87749931 1.6488 1 P 0 ;0,1,2=75,3=90.000000
L 2.87749931 1.6488 2.88166663 1.64986644 1 P 0 ;0,1,2=75,3=90.000000
L 2.88166663 1.64986644 2.8862498 1.6512 1 P 0 ;0,1,2=75,3=90.000000
L 2.8862498 1.6512 2.8925 1.65333337 1 P 0 ;0,1,2=75,3=90.000000
L 2.8925 1.65333337 2.8925 1.64266654 1 P 0 ;0,1,2=75,3=90.000000
L 4.4613 1.94066998 4.38491998 1.94066998 1 P 0 
L 4.38491998 1.94066998 4.38491998 1.90366998 1 P 0 
L 4.38491998 1.90366998 4.4613 1.90366998 1 P 0 
L 4.4613 1.90366998 4.4613 1.94066998 1 P 0 
L 4.44713337 1.97041634 4.44873356 1.97166683 1 P 0 ;0,1,2=76,3=0.000000
L 4.44873356 1.97166683 4.4505998 1.9725 1 P 0 ;0,1,2=76,3=0.000000
L 4.4505998 1.9725 4.45273317 1.9725 1 P 0 ;0,1,2=76,3=0.000000
L 4.45273317 1.9725 4.45513366 1.97124941 1 P 0 ;0,1,2=76,3=0.000000
L 4.45513366 1.97124941 4.4569999 1.96916654 1 P 0 ;0,1,2=76,3=0.000000
L 4.4569999 1.96916654 4.45833346 1.96666634 1 P 0 ;0,1,2=76,3=0.000000
L 4.45833346 1.96666634 4.45940039 1.9624998 1 P 0 ;0,1,2=76,3=0.000000
L 4.45940039 1.9624998 4.45966703 1.9587498 1 P 0 ;0,1,2=76,3=0.000000
L 4.45966703 1.9587498 4.45913327 1.9549999 1 P 0 ;0,1,2=76,3=0.000000
L 4.45913327 1.9549999 4.45833346 1.95249961 1 P 0 ;0,1,2=76,3=0.000000
L 4.45833346 1.95249961 4.45673337 1.94999941 1 P 0 ;0,1,2=76,3=0.000000
L 4.45673337 1.94999941 4.45486654 1.94833307 1 P 0 ;0,1,2=76,3=0.000000
L 4.45486654 1.94833307 4.4530003 1.9475 1 P 0 ;0,1,2=76,3=0.000000
L 4.4530003 1.9475 4.45113356 1.9475 1 P 0 ;0,1,2=76,3=0.000000
L 4.45113356 1.9475 4.44926673 1.94833307 1 P 0 ;0,1,2=76,3=0.000000
L 4.44926673 1.94833307 4.44766663 1.94958287 1 P 0 ;0,1,2=76,3=0.000000
L 4.44766663 1.94958287 4.44633307 1.95124911 1 P 0 ;0,1,2=76,3=0.000000
L 4.4310003 1.9475 4.4310003 1.9725 1 P 0 ;0,1,2=76,3=0.000000
L 4.4310003 1.9725 4.4342001 1.9675003 1 P 0 ;0,1,2=76,3=0.000000
L 4.4342001 1.9475 4.42780049 1.9475 1 P 0 ;0,1,2=76,3=0.000000
L 4.41486673 1.95249961 4.41326703 1.94958287 1 P 0 ;0,1,2=76,3=0.000000
L 4.41326703 1.94958287 4.41113366 1.94791654 1 P 0 ;0,1,2=76,3=0.000000
L 4.41113366 1.94791654 4.40873317 1.9475 1 P 0 ;0,1,2=76,3=0.000000
L 4.40873317 1.9475 4.4065998 1.94791654 1 P 0 ;0,1,2=76,3=0.000000
L 4.4065998 1.94791654 4.40446644 1.94999941 1 P 0 ;0,1,2=76,3=0.000000
L 4.40446644 1.94999941 4.40313337 1.95249961 1 P 0 ;0,1,2=76,3=0.000000
L 4.40313337 1.95249961 4.40286683 1.9549999 1 P 0 ;0,1,2=76,3=0.000000
L 4.40286683 1.9549999 4.4034 1.95791594 1 P 0 ;0,1,2=76,3=0.000000
L 4.4034 1.95791594 4.40526673 1.95999961 1 P 0 ;0,1,2=76,3=0.000000
L 4.40526673 1.95999961 4.40713356 1.96083346 1 P 0 ;0,1,2=76,3=0.000000
L 4.40713356 1.96083346 4.40953346 1.96083346 1 P 0 ;0,1,2=76,3=0.000000
L 4.40713356 1.96083346 4.40553337 1.96208327 1 P 0 ;0,1,2=76,3=0.000000
L 4.40553337 1.96208327 4.4041999 1.96416614 1 P 0 ;0,1,2=76,3=0.000000
L 4.4041999 1.96416614 4.40366663 1.96666634 1 P 0 ;0,1,2=76,3=0.000000
L 4.40366663 1.96666634 4.4041999 1.96916654 1 P 0 ;0,1,2=76,3=0.000000
L 4.4041999 1.96916654 4.40553337 1.97124941 1 P 0 ;0,1,2=76,3=0.000000
L 4.40553337 1.97124941 4.40793337 1.9725 1 P 0 ;0,1,2=76,3=0.000000
L 4.40793337 1.9725 4.41033337 1.97208337 1 P 0 ;0,1,2=76,3=0.000000
L 4.41033337 1.97208337 4.41273337 1.97041634 1 P 0 ;0,1,2=76,3=0.000000
L 4.39206683 1.96833337 4.39046673 1.97083287 1 P 0 ;0,1,2=76,3=0.000000
L 4.39046673 1.97083287 4.3886 1.97208337 1 P 0 ;0,1,2=76,3=0.000000
L 4.3886 1.97208337 4.38646663 1.9725 1 P 0 ;0,1,2=76,3=0.000000
L 4.38646663 1.9725 4.3838 1.97166683 1 P 0 ;0,1,2=76,3=0.000000
L 4.3838 1.97166683 4.38193327 1.96958317 1 P 0 ;0,1,2=76,3=0.000000
L 4.38193327 1.96958317 4.3814 1.96708366 1 P 0 ;0,1,2=76,3=0.000000
L 4.3814 1.96708366 4.38166663 1.96458268 1 P 0 ;0,1,2=76,3=0.000000
L 4.38166663 1.96458268 4.38273356 1.9624998 1 P 0 ;0,1,2=76,3=0.000000
L 4.38273356 1.9624998 4.38806673 1.95833327 1 P 0 ;0,1,2=76,3=0.000000
L 4.38806673 1.95833327 4.39046673 1.95541644 1 P 0 ;0,1,2=76,3=0.000000
L 4.39046673 1.95541644 4.39206683 1.95124911 1 P 0 ;0,1,2=76,3=0.000000
L 4.39206683 1.95124911 4.3926001 1.9475 1 P 0 ;0,1,2=76,3=0.000000
L 4.3926001 1.9475 4.3814 1.9475 1 P 0 ;0,1,2=76,3=0.000000
L 4.50066004 1.98003996 4.46366004 1.98003996 1 P 0 
L 4.50066004 1.90366004 4.50066004 1.98003996 1 P 0 
L 4.46366004 1.98003996 4.46366004 1.90366004 1 P 0 
L 4.46366004 1.90366004 4.50066004 1.90366004 1 P 0 
L 4.53041634 1.98786663 4.53166683 1.98626644 1 P 0 ;0,1,2=77,3=90.000000
L 4.53166683 1.98626644 4.5325 1.9844002 1 P 0 ;0,1,2=77,3=90.000000
L 4.5325 1.9844002 4.5325 1.98226683 1 P 0 ;0,1,2=77,3=90.000000
L 4.5325 1.98226683 4.53124941 1.97986634 1 P 0 ;0,1,2=77,3=90.000000
L 4.53124941 1.97986634 4.52916654 1.9780001 1 P 0 ;0,1,2=77,3=90.000000
L 4.52916654 1.9780001 4.52666634 1.97666654 1 P 0 ;0,1,2=77,3=90.000000
L 4.52666634 1.97666654 4.5224998 1.97559961 1 P 0 ;0,1,2=77,3=90.000000
L 4.5224998 1.97559961 4.5187498 1.97533297 1 P 0 ;0,1,2=77,3=90.000000
L 4.5187498 1.97533297 4.5149999 1.97586673 1 P 0 ;0,1,2=77,3=90.000000
L 4.5149999 1.97586673 4.51249961 1.97666654 1 P 0 ;0,1,2=77,3=90.000000
L 4.51249961 1.97666654 4.50999941 1.97826663 1 P 0 ;0,1,2=77,3=90.000000
L 4.50999941 1.97826663 4.50833307 1.98013346 1 P 0 ;0,1,2=77,3=90.000000
L 4.50833307 1.98013346 4.5075 1.9819997 1 P 0 ;0,1,2=77,3=90.000000
L 4.5075 1.9819997 4.5075 1.98386644 1 P 0 ;0,1,2=77,3=90.000000
L 4.5075 1.98386644 4.50833307 1.98573327 1 P 0 ;0,1,2=77,3=90.000000
L 4.50833307 1.98573327 4.50958287 1.98733337 1 P 0 ;0,1,2=77,3=90.000000
L 4.50958287 1.98733337 4.51124911 1.98866693 1 P 0 ;0,1,2=77,3=90.000000
L 4.5075 2.0039997 4.5325 2.0039997 1 P 0 ;0,1,2=77,3=90.000000
L 4.5325 2.0039997 4.5275003 2.0007999 1 P 0 ;0,1,2=77,3=90.000000
L 4.5075 2.0007999 4.5075 2.00719951 1 P 0 ;0,1,2=77,3=90.000000
L 4.52833337 2.02093317 4.53083287 2.02253327 1 P 0 ;0,1,2=77,3=90.000000
L 4.53083287 2.02253327 4.53208337 2.0244 1 P 0 ;0,1,2=77,3=90.000000
L 4.53208337 2.0244 4.5325 2.02653337 1 P 0 ;0,1,2=77,3=90.000000
L 4.5325 2.02653337 4.53166683 2.0292 1 P 0 ;0,1,2=77,3=90.000000
L 4.53166683 2.0292 4.52958317 2.03106673 1 P 0 ;0,1,2=77,3=90.000000
L 4.52958317 2.03106673 4.52708366 2.0316 1 P 0 ;0,1,2=77,3=90.000000
L 4.52708366 2.0316 4.52458268 2.03133337 1 P 0 ;0,1,2=77,3=90.000000
L 4.52458268 2.03133337 4.5224998 2.03026644 1 P 0 ;0,1,2=77,3=90.000000
L 4.5224998 2.03026644 4.51833327 2.02493327 1 P 0 ;0,1,2=77,3=90.000000
L 4.51833327 2.02493327 4.51541644 2.02253327 1 P 0 ;0,1,2=77,3=90.000000
L 4.51541644 2.02253327 4.51124911 2.02093317 1 P 0 ;0,1,2=77,3=90.000000
L 4.51124911 2.02093317 4.5075 2.0203999 1 P 0 ;0,1,2=77,3=90.000000
L 4.5075 2.0203999 4.5075 2.0316 1 P 0 ;0,1,2=77,3=90.000000
L 4.51791594 2.04293317 4.52083346 2.0447999 1 P 0 ;0,1,2=77,3=90.000000
L 4.52083346 2.0447999 4.5224998 2.0464 1 P 0 ;0,1,2=77,3=90.000000
L 4.5224998 2.0464 4.52333297 2.04853337 1 P 0 ;0,1,2=77,3=90.000000
L 4.52333297 2.04853337 4.5224998 2.0504002 1 P 0 ;0,1,2=77,3=90.000000
L 4.5224998 2.0504002 4.52083346 2.05173327 1 P 0 ;0,1,2=77,3=90.000000
L 4.52083346 2.05173327 4.51833327 2.0528001 1 P 0 ;0,1,2=77,3=90.000000
L 4.51833327 2.0528001 4.51541644 2.05306673 1 P 0 ;0,1,2=77,3=90.000000
L 4.51541644 2.05306673 4.51291624 2.0528001 1 P 0 ;0,1,2=77,3=90.000000
L 4.51291624 2.0528001 4.51041604 2.05173327 1 P 0 ;0,1,2=77,3=90.000000
L 4.51041604 2.05173327 4.50833307 2.05013307 1 P 0 ;0,1,2=77,3=90.000000
L 4.50833307 2.05013307 4.5075 2.04826683 1 P 0 ;0,1,2=77,3=90.000000
L 4.5075 2.04826683 4.50833307 2.04613346 1 P 0 ;0,1,2=77,3=90.000000
L 4.50833307 2.04613346 4.51083258 2.04426663 1 P 0 ;0,1,2=77,3=90.000000
L 4.51083258 2.04426663 4.51458327 2.0431998 1 P 0 ;0,1,2=77,3=90.000000
L 4.51458327 2.0431998 4.5187498 2.04293317 1 P 0 ;0,1,2=77,3=90.000000
L 4.5187498 2.04293317 4.52416614 2.04346634 1 P 0 ;0,1,2=77,3=90.000000
L 4.52416614 2.04346634 4.52708366 2.04426663 1 P 0 ;0,1,2=77,3=90.000000
L 4.52708366 2.04426663 4.5299997 2.0455997 1 P 0 ;0,1,2=77,3=90.000000
L 4.5299997 2.0455997 4.53208337 2.04746654 1 P 0 ;0,1,2=77,3=90.000000
L 4.53208337 2.04746654 4.5325 2.04933327 1 P 0 ;0,1,2=77,3=90.000000
L 4.5325 2.04933327 4.53166683 2.0512 1 P 0 ;0,1,2=77,3=90.000000
L 4.53166683 2.0512 4.52958317 2.05253356 1 P 0 ;0,1,2=77,3=90.000000
L 4.65815 1.82493002 4.65815 1.90131004 1 P 0 
L 4.65815 1.90131004 4.62115 1.90131004 1 P 0 
L 4.62115 1.90131004 4.62115 1.82493002 1 P 0 
L 4.62115 1.82493002 4.65815 1.82493002 1 P 0 
L 4.72541634 1.90286663 4.72666683 1.90126644 1 P 0 ;0,1,2=78,3=90.000000
L 4.72666683 1.90126644 4.7275 1.8994002 1 P 0 ;0,1,2=78,3=90.000000
L 4.7275 1.8994002 4.7275 1.89726683 1 P 0 ;0,1,2=78,3=90.000000
L 4.7275 1.89726683 4.72624941 1.89486634 1 P 0 ;0,1,2=78,3=90.000000
L 4.72624941 1.89486634 4.72416654 1.8930001 1 P 0 ;0,1,2=78,3=90.000000
L 4.72416654 1.8930001 4.72166634 1.89166654 1 P 0 ;0,1,2=78,3=90.000000
L 4.72166634 1.89166654 4.7174998 1.89059961 1 P 0 ;0,1,2=78,3=90.000000
L 4.7174998 1.89059961 4.7137498 1.89033297 1 P 0 ;0,1,2=78,3=90.000000
L 4.7137498 1.89033297 4.7099999 1.89086673 1 P 0 ;0,1,2=78,3=90.000000
L 4.7099999 1.89086673 4.70749961 1.89166654 1 P 0 ;0,1,2=78,3=90.000000
L 4.70749961 1.89166654 4.70499941 1.89326663 1 P 0 ;0,1,2=78,3=90.000000
L 4.70499941 1.89326663 4.70333307 1.89513346 1 P 0 ;0,1,2=78,3=90.000000
L 4.70333307 1.89513346 4.7025 1.8969997 1 P 0 ;0,1,2=78,3=90.000000
L 4.7025 1.8969997 4.7025 1.89886644 1 P 0 ;0,1,2=78,3=90.000000
L 4.7025 1.89886644 4.70333307 1.90073327 1 P 0 ;0,1,2=78,3=90.000000
L 4.70333307 1.90073327 4.70458287 1.90233337 1 P 0 ;0,1,2=78,3=90.000000
L 4.70458287 1.90233337 4.70624911 1.90366693 1 P 0 ;0,1,2=78,3=90.000000
L 4.72333337 1.91393317 4.72583287 1.91553327 1 P 0 ;0,1,2=78,3=90.000000
L 4.72583287 1.91553327 4.72708337 1.9174 1 P 0 ;0,1,2=78,3=90.000000
L 4.72708337 1.9174 4.7275 1.91953337 1 P 0 ;0,1,2=78,3=90.000000
L 4.7275 1.91953337 4.72666683 1.9222 1 P 0 ;0,1,2=78,3=90.000000
L 4.72666683 1.9222 4.72458317 1.92406673 1 P 0 ;0,1,2=78,3=90.000000
L 4.72458317 1.92406673 4.72208366 1.9246 1 P 0 ;0,1,2=78,3=90.000000
L 4.72208366 1.9246 4.71958268 1.92433337 1 P 0 ;0,1,2=78,3=90.000000
L 4.71958268 1.92433337 4.7174998 1.92326644 1 P 0 ;0,1,2=78,3=90.000000
L 4.7174998 1.92326644 4.71333327 1.91793327 1 P 0 ;0,1,2=78,3=90.000000
L 4.71333327 1.91793327 4.71041644 1.91553327 1 P 0 ;0,1,2=78,3=90.000000
L 4.71041644 1.91553327 4.70624911 1.91393317 1 P 0 ;0,1,2=78,3=90.000000
L 4.70624911 1.91393317 4.7025 1.9133999 1 P 0 ;0,1,2=78,3=90.000000
L 4.7025 1.9133999 4.7025 1.9246 1 P 0 ;0,1,2=78,3=90.000000
L 4.7275 1.9409997 4.72666683 1.93886634 1 P 0 ;0,1,2=78,3=90.000000
L 4.72666683 1.93886634 4.72458317 1.93726663 1 P 0 ;0,1,2=78,3=90.000000
L 4.72458317 1.93726663 4.72208366 1.9361998 1 P 0 ;0,1,2=78,3=90.000000
L 4.72208366 1.9361998 4.71874951 1.9353999 1 P 0 ;0,1,2=78,3=90.000000
L 4.71874951 1.9353999 4.71499961 1.93513327 1 P 0 ;0,1,2=78,3=90.000000
L 4.71499961 1.93513327 4.71124961 1.9353999 1 P 0 ;0,1,2=78,3=90.000000
L 4.71124961 1.9353999 4.70791624 1.9361998 1 P 0 ;0,1,2=78,3=90.000000
L 4.70791624 1.9361998 4.70541604 1.93726663 1 P 0 ;0,1,2=78,3=90.000000
L 4.70541604 1.93726663 4.70333307 1.93886634 1 P 0 ;0,1,2=78,3=90.000000
L 4.70333307 1.93886634 4.7025 1.9409997 1 P 0 ;0,1,2=78,3=90.000000
L 4.7025 1.9409997 4.70333307 1.94313307 1 P 0 ;0,1,2=78,3=90.000000
L 4.70333307 1.94313307 4.70541604 1.94473327 1 P 0 ;0,1,2=78,3=90.000000
L 4.70541604 1.94473327 4.70791624 1.9458001 1 P 0 ;0,1,2=78,3=90.000000
L 4.70791624 1.9458001 4.71124961 1.9466 1 P 0 ;0,1,2=78,3=90.000000
L 4.71124961 1.9466 4.71499961 1.94686663 1 P 0 ;0,1,2=78,3=90.000000
L 4.71499961 1.94686663 4.71874951 1.9466 1 P 0 ;0,1,2=78,3=90.000000
L 4.71874951 1.9466 4.72208366 1.9458001 1 P 0 ;0,1,2=78,3=90.000000
L 4.72208366 1.9458001 4.72458317 1.94473327 1 P 0 ;0,1,2=78,3=90.000000
L 4.72458317 1.94473327 4.72666683 1.94313307 1 P 0 ;0,1,2=78,3=90.000000
L 4.72666683 1.94313307 4.7275 1.9409997 1 P 0 ;0,1,2=78,3=90.000000
L 4.72333337 1.95793317 4.72583287 1.95953327 1 P 0 ;0,1,2=78,3=90.000000
L 4.72583287 1.95953327 4.72708337 1.9614 1 P 0 ;0,1,2=78,3=90.000000
L 4.72708337 1.9614 4.7275 1.96353337 1 P 0 ;0,1,2=78,3=90.000000
L 4.7275 1.96353337 4.72666683 1.9662 1 P 0 ;0,1,2=78,3=90.000000
L 4.72666683 1.9662 4.72458317 1.96806673 1 P 0 ;0,1,2=78,3=90.000000
L 4.72458317 1.96806673 4.72208366 1.9686 1 P 0 ;0,1,2=78,3=90.000000
L 4.72208366 1.9686 4.71958268 1.96833337 1 P 0 ;0,1,2=78,3=90.000000
L 4.71958268 1.96833337 4.7174998 1.96726644 1 P 0 ;0,1,2=78,3=90.000000
L 4.7174998 1.96726644 4.71333327 1.96193327 1 P 0 ;0,1,2=78,3=90.000000
L 4.71333327 1.96193327 4.71041644 1.95953327 1 P 0 ;0,1,2=78,3=90.000000
L 4.71041644 1.95953327 4.70624911 1.95793317 1 P 0 ;0,1,2=78,3=90.000000
L 4.70624911 1.95793317 4.7025 1.9573999 1 P 0 ;0,1,2=78,3=90.000000
L 4.7025 1.9573999 4.7025 1.9686 1 P 0 ;0,1,2=78,3=90.000000
L 4.58178002 1.90366998 4.65816004 1.90366998 1 P 0 
L 4.65816004 1.90366998 4.65816004 1.94066998 1 P 0 
L 4.65816004 1.94066998 4.58178002 1.94066998 1 P 0 
L 4.58178002 1.94066998 4.58178002 1.90366998 1 P 0 
L 4.62213337 2.01041634 4.62373356 2.01166683 1 P 0 ;0,1,2=79,3=0.000000
L 4.62373356 2.01166683 4.6255998 2.0125 1 P 0 ;0,1,2=79,3=0.000000
L 4.6255998 2.0125 4.62773317 2.0125 1 P 0 ;0,1,2=79,3=0.000000
L 4.62773317 2.0125 4.63013366 2.01124941 1 P 0 ;0,1,2=79,3=0.000000
L 4.63013366 2.01124941 4.6319999 2.00916654 1 P 0 ;0,1,2=79,3=0.000000
L 4.6319999 2.00916654 4.63333346 2.00666634 1 P 0 ;0,1,2=79,3=0.000000
L 4.63333346 2.00666634 4.63440039 2.0024998 1 P 0 ;0,1,2=79,3=0.000000
L 4.63440039 2.0024998 4.63466703 1.9987498 1 P 0 ;0,1,2=79,3=0.000000
L 4.63466703 1.9987498 4.63413327 1.9949999 1 P 0 ;0,1,2=79,3=0.000000
L 4.63413327 1.9949999 4.63333346 1.99249961 1 P 0 ;0,1,2=79,3=0.000000
L 4.63333346 1.99249961 4.63173337 1.98999941 1 P 0 ;0,1,2=79,3=0.000000
L 4.63173337 1.98999941 4.62986654 1.98833307 1 P 0 ;0,1,2=79,3=0.000000
L 4.62986654 1.98833307 4.6280003 1.9875 1 P 0 ;0,1,2=79,3=0.000000
L 4.6280003 1.9875 4.62613356 1.9875 1 P 0 ;0,1,2=79,3=0.000000
L 4.62613356 1.9875 4.62426673 1.98833307 1 P 0 ;0,1,2=79,3=0.000000
L 4.62426673 1.98833307 4.62266663 1.98958287 1 P 0 ;0,1,2=79,3=0.000000
L 4.62266663 1.98958287 4.62133307 1.99124911 1 P 0 ;0,1,2=79,3=0.000000
L 4.61106683 2.00833337 4.60946673 2.01083287 1 P 0 ;0,1,2=79,3=0.000000
L 4.60946673 2.01083287 4.6076 2.01208337 1 P 0 ;0,1,2=79,3=0.000000
L 4.6076 2.01208337 4.60546663 2.0125 1 P 0 ;0,1,2=79,3=0.000000
L 4.60546663 2.0125 4.6028 2.01166683 1 P 0 ;0,1,2=79,3=0.000000
L 4.6028 2.01166683 4.60093327 2.00958317 1 P 0 ;0,1,2=79,3=0.000000
L 4.60093327 2.00958317 4.6004 2.00708366 1 P 0 ;0,1,2=79,3=0.000000
L 4.6004 2.00708366 4.60066663 2.00458268 1 P 0 ;0,1,2=79,3=0.000000
L 4.60066663 2.00458268 4.60173356 2.0024998 1 P 0 ;0,1,2=79,3=0.000000
L 4.60173356 2.0024998 4.60706673 1.99833327 1 P 0 ;0,1,2=79,3=0.000000
L 4.60706673 1.99833327 4.60946673 1.99541644 1 P 0 ;0,1,2=79,3=0.000000
L 4.60946673 1.99541644 4.61106683 1.99124911 1 P 0 ;0,1,2=79,3=0.000000
L 4.61106683 1.99124911 4.6116001 1.9875 1 P 0 ;0,1,2=79,3=0.000000
L 4.6116001 1.9875 4.6004 1.9875 1 P 0 ;0,1,2=79,3=0.000000
L 4.5840003 1.9875 4.5840003 2.0125 1 P 0 ;0,1,2=79,3=0.000000
L 4.5840003 2.0125 4.5872001 2.0075003 1 P 0 ;0,1,2=79,3=0.000000
L 4.5872001 1.9875 4.58080049 1.9875 1 P 0 ;0,1,2=79,3=0.000000
L 4.56786673 1.99124911 4.56626703 1.98916624 1 P 0 ;0,1,2=79,3=0.000000
L 4.56626703 1.98916624 4.5644003 1.98791654 1 P 0 ;0,1,2=79,3=0.000000
L 4.5644003 1.98791654 4.5620003 1.9875 1 P 0 ;0,1,2=79,3=0.000000
L 4.5620003 1.9875 4.5595998 1.98833307 1 P 0 ;0,1,2=79,3=0.000000
L 4.5595998 1.98833307 4.55773356 1.98999941 1 P 0 ;0,1,2=79,3=0.000000
L 4.55773356 1.98999941 4.5564 1.99291624 1 P 0 ;0,1,2=79,3=0.000000
L 4.5564 1.99291624 4.55613337 1.99624961 1 P 0 ;0,1,2=79,3=0.000000
L 4.55613337 1.99624961 4.55666663 1.99958297 1 P 0 ;0,1,2=79,3=0.000000
L 4.55666663 1.99958297 4.5580002 2.00166663 1 P 0 ;0,1,2=79,3=0.000000
L 4.5580002 2.00166663 4.55986693 2.00333297 1 P 0 ;0,1,2=79,3=0.000000
L 4.55986693 2.00333297 4.56173317 2.00374951 1 P 0 ;0,1,2=79,3=0.000000
L 4.56173317 2.00374951 4.5636 2.00333297 1 P 0 ;0,1,2=79,3=0.000000
L 4.5636 2.00333297 4.5659999 2.00166663 1 P 0 ;0,1,2=79,3=0.000000
L 4.5659999 2.00166663 4.5652001 2.0125 1 P 0 ;0,1,2=79,3=0.000000
L 4.5652001 2.0125 4.5580002 2.0125 1 P 0 ;0,1,2=79,3=0.000000
L 4.42193002 1.62571004 4.38493002 1.62571004 1 P 0 
L 4.38493002 1.62571004 4.38493002 1.54933002 1 P 0 
L 4.38493002 1.54933002 4.42193002 1.54933002 1 P 0 
L 4.42193002 1.54933002 4.42193002 1.62571004 1 P 0 
L 2.76081634 1.50536663 2.76206683 1.50376644 1 P 0 ;0,1,2=80,3=90.000000
L 2.76206683 1.50376644 2.7629 1.5019002 1 P 0 ;0,1,2=80,3=90.000000
L 2.7629 1.5019002 2.7629 1.49976683 1 P 0 ;0,1,2=80,3=90.000000
L 2.7629 1.49976683 2.76164941 1.49736634 1 P 0 ;0,1,2=80,3=90.000000
L 2.76164941 1.49736634 2.75956654 1.4955001 1 P 0 ;0,1,2=80,3=90.000000
L 2.75956654 1.4955001 2.75706634 1.49416654 1 P 0 ;0,1,2=80,3=90.000000
L 2.75706634 1.49416654 2.7528998 1.49309961 1 P 0 ;0,1,2=80,3=90.000000
L 2.7528998 1.49309961 2.7491498 1.49283297 1 P 0 ;0,1,2=80,3=90.000000
L 2.7491498 1.49283297 2.7453999 1.49336673 1 P 0 ;0,1,2=80,3=90.000000
L 2.7453999 1.49336673 2.74289961 1.49416654 1 P 0 ;0,1,2=80,3=90.000000
L 2.74289961 1.49416654 2.74039941 1.49576663 1 P 0 ;0,1,2=80,3=90.000000
L 2.74039941 1.49576663 2.73873307 1.49763346 1 P 0 ;0,1,2=80,3=90.000000
L 2.73873307 1.49763346 2.7379 1.4994997 1 P 0 ;0,1,2=80,3=90.000000
L 2.7379 1.4994997 2.7379 1.50136644 1 P 0 ;0,1,2=80,3=90.000000
L 2.7379 1.50136644 2.73873307 1.50323327 1 P 0 ;0,1,2=80,3=90.000000
L 2.73873307 1.50323327 2.73998287 1.50483337 1 P 0 ;0,1,2=80,3=90.000000
L 2.73998287 1.50483337 2.74164911 1.50616693 1 P 0 ;0,1,2=80,3=90.000000
L 2.7379 1.5214997 2.7629 1.5214997 1 P 0 ;0,1,2=80,3=90.000000
L 2.7629 1.5214997 2.7579003 1.5182999 1 P 0 ;0,1,2=80,3=90.000000
L 2.7379 1.5182999 2.7379 1.52469951 1 P 0 ;0,1,2=80,3=90.000000
L 2.7379 1.54296654 2.74331624 1.5434997 1 P 0 ;0,1,2=80,3=90.000000
L 2.74331624 1.5434997 2.74789931 1.5443 1 P 0 ;0,1,2=80,3=90.000000
L 2.74789931 1.5443 2.75206663 1.54536644 1 P 0 ;0,1,2=80,3=90.000000
L 2.75206663 1.54536644 2.7566498 1.5467 1 P 0 ;0,1,2=80,3=90.000000
L 2.7566498 1.5467 2.7629 1.54883337 1 P 0 ;0,1,2=80,3=90.000000
L 2.7629 1.54883337 2.7629 1.53816654 1 P 0 ;0,1,2=80,3=90.000000
L 2.7379 1.5654997 2.7629 1.5654997 1 P 0 ;0,1,2=80,3=90.000000
L 2.7629 1.5654997 2.7579003 1.5622999 1 P 0 ;0,1,2=80,3=90.000000
L 2.7379 1.5622999 2.7379 1.56869951 1 P 0 ;0,1,2=80,3=90.000000
L 4.61878002 1.42885 4.5424 1.42885 1 P 0 
L 4.5424 1.42885 4.5424 1.39185 1 P 0 
L 4.5424 1.39185 4.61878002 1.39185 1 P 0 
L 4.61878002 1.39185 4.61878002 1.42885 1 P 0 
L 4.61713337 1.46041634 4.61873356 1.46166683 1 P 0 ;0,1,2=81,3=0.000000
L 4.61873356 1.46166683 4.6205998 1.4625 1 P 0 ;0,1,2=81,3=0.000000
L 4.6205998 1.4625 4.62273317 1.4625 1 P 0 ;0,1,2=81,3=0.000000
L 4.62273317 1.4625 4.62513366 1.46124941 1 P 0 ;0,1,2=81,3=0.000000
L 4.62513366 1.46124941 4.6269999 1.45916654 1 P 0 ;0,1,2=81,3=0.000000
L 4.6269999 1.45916654 4.62833346 1.45666634 1 P 0 ;0,1,2=81,3=0.000000
L 4.62833346 1.45666634 4.62940039 1.4524998 1 P 0 ;0,1,2=81,3=0.000000
L 4.62940039 1.4524998 4.62966703 1.4487498 1 P 0 ;0,1,2=81,3=0.000000
L 4.62966703 1.4487498 4.62913327 1.4449999 1 P 0 ;0,1,2=81,3=0.000000
L 4.62913327 1.4449999 4.62833346 1.44249961 1 P 0 ;0,1,2=81,3=0.000000
L 4.62833346 1.44249961 4.62673337 1.43999941 1 P 0 ;0,1,2=81,3=0.000000
L 4.62673337 1.43999941 4.62486654 1.43833307 1 P 0 ;0,1,2=81,3=0.000000
L 4.62486654 1.43833307 4.6230003 1.4375 1 P 0 ;0,1,2=81,3=0.000000
L 4.6230003 1.4375 4.62113356 1.4375 1 P 0 ;0,1,2=81,3=0.000000
L 4.62113356 1.4375 4.61926673 1.43833307 1 P 0 ;0,1,2=81,3=0.000000
L 4.61926673 1.43833307 4.61766663 1.43958287 1 P 0 ;0,1,2=81,3=0.000000
L 4.61766663 1.43958287 4.61633307 1.44124911 1 P 0 ;0,1,2=81,3=0.000000
L 4.6010003 1.4375 4.6010003 1.4625 1 P 0 ;0,1,2=81,3=0.000000
L 4.6010003 1.4625 4.6042001 1.4575003 1 P 0 ;0,1,2=81,3=0.000000
L 4.6042001 1.4375 4.59780049 1.4375 1 P 0 ;0,1,2=81,3=0.000000
L 4.58406683 1.45833337 4.58246673 1.46083287 1 P 0 ;0,1,2=81,3=0.000000
L 4.58246673 1.46083287 4.5806 1.46208337 1 P 0 ;0,1,2=81,3=0.000000
L 4.5806 1.46208337 4.57846663 1.4625 1 P 0 ;0,1,2=81,3=0.000000
L 4.57846663 1.4625 4.5758 1.46166683 1 P 0 ;0,1,2=81,3=0.000000
L 4.5758 1.46166683 4.57393327 1.45958317 1 P 0 ;0,1,2=81,3=0.000000
L 4.57393327 1.45958317 4.5734 1.45708366 1 P 0 ;0,1,2=81,3=0.000000
L 4.5734 1.45708366 4.57366663 1.45458268 1 P 0 ;0,1,2=81,3=0.000000
L 4.57366663 1.45458268 4.57473356 1.4524998 1 P 0 ;0,1,2=81,3=0.000000
L 4.57473356 1.4524998 4.58006673 1.44833327 1 P 0 ;0,1,2=81,3=0.000000
L 4.58006673 1.44833327 4.58246673 1.44541644 1 P 0 ;0,1,2=81,3=0.000000
L 4.58246673 1.44541644 4.58406683 1.44124911 1 P 0 ;0,1,2=81,3=0.000000
L 4.58406683 1.44124911 4.5846001 1.4375 1 P 0 ;0,1,2=81,3=0.000000
L 4.5846001 1.4375 4.5734 1.4375 1 P 0 ;0,1,2=81,3=0.000000
L 4.55753346 1.4375 4.5570003 1.44291624 1 P 0 ;0,1,2=81,3=0.000000
L 4.5570003 1.44291624 4.5562 1.44749931 1 P 0 ;0,1,2=81,3=0.000000
L 4.5562 1.44749931 4.55513356 1.45166663 1 P 0 ;0,1,2=81,3=0.000000
L 4.55513356 1.45166663 4.5538 1.4562498 1 P 0 ;0,1,2=81,3=0.000000
L 4.5538 1.4562498 4.55166663 1.4625 1 P 0 ;0,1,2=81,3=0.000000
L 4.55166663 1.4625 4.56233346 1.4625 1 P 0 ;0,1,2=81,3=0.000000
L 4.74816004 1.44655 4.74816004 1.37016998 1 P 0 
L 4.74816004 1.37016998 4.78516004 1.37016998 1 P 0 
L 4.78516004 1.37016998 4.78516004 1.44655 1 P 0 
L 4.78516004 1.44655 4.74816004 1.44655 1 P 0 
L 4.82041634 1.42786663 4.82166683 1.42626644 1 P 0 ;0,1,2=82,3=90.000000
L 4.82166683 1.42626644 4.8225 1.4244002 1 P 0 ;0,1,2=82,3=90.000000
L 4.8225 1.4244002 4.8225 1.42226683 1 P 0 ;0,1,2=82,3=90.000000
L 4.8225 1.42226683 4.82124941 1.41986634 1 P 0 ;0,1,2=82,3=90.000000
L 4.82124941 1.41986634 4.81916654 1.4180001 1 P 0 ;0,1,2=82,3=90.000000
L 4.81916654 1.4180001 4.81666634 1.41666654 1 P 0 ;0,1,2=82,3=90.000000
L 4.81666634 1.41666654 4.8124998 1.41559961 1 P 0 ;0,1,2=82,3=90.000000
L 4.8124998 1.41559961 4.8087498 1.41533297 1 P 0 ;0,1,2=82,3=90.000000
L 4.8087498 1.41533297 4.8049999 1.41586673 1 P 0 ;0,1,2=82,3=90.000000
L 4.8049999 1.41586673 4.80249961 1.41666654 1 P 0 ;0,1,2=82,3=90.000000
L 4.80249961 1.41666654 4.79999941 1.41826663 1 P 0 ;0,1,2=82,3=90.000000
L 4.79999941 1.41826663 4.79833307 1.42013346 1 P 0 ;0,1,2=82,3=90.000000
L 4.79833307 1.42013346 4.7975 1.4219997 1 P 0 ;0,1,2=82,3=90.000000
L 4.7975 1.4219997 4.7975 1.42386644 1 P 0 ;0,1,2=82,3=90.000000
L 4.7975 1.42386644 4.79833307 1.42573327 1 P 0 ;0,1,2=82,3=90.000000
L 4.79833307 1.42573327 4.79958287 1.42733337 1 P 0 ;0,1,2=82,3=90.000000
L 4.79958287 1.42733337 4.80124911 1.42866693 1 P 0 ;0,1,2=82,3=90.000000
L 4.7975 1.4439997 4.8225 1.4439997 1 P 0 ;0,1,2=82,3=90.000000
L 4.8225 1.4439997 4.8175003 1.4407999 1 P 0 ;0,1,2=82,3=90.000000
L 4.7975 1.4407999 4.7975 1.44719951 1 P 0 ;0,1,2=82,3=90.000000
L 4.81833337 1.46093317 4.82083287 1.46253327 1 P 0 ;0,1,2=82,3=90.000000
L 4.82083287 1.46253327 4.82208337 1.4644 1 P 0 ;0,1,2=82,3=90.000000
L 4.82208337 1.4644 4.8225 1.46653337 1 P 0 ;0,1,2=82,3=90.000000
L 4.8225 1.46653337 4.82166683 1.4692 1 P 0 ;0,1,2=82,3=90.000000
L 4.82166683 1.4692 4.81958317 1.47106673 1 P 0 ;0,1,2=82,3=90.000000
L 4.81958317 1.47106673 4.81708366 1.4716 1 P 0 ;0,1,2=82,3=90.000000
L 4.81708366 1.4716 4.81458268 1.47133337 1 P 0 ;0,1,2=82,3=90.000000
L 4.81458268 1.47133337 4.8124998 1.47026644 1 P 0 ;0,1,2=82,3=90.000000
L 4.8124998 1.47026644 4.80833327 1.46493327 1 P 0 ;0,1,2=82,3=90.000000
L 4.80833327 1.46493327 4.80541644 1.46253327 1 P 0 ;0,1,2=82,3=90.000000
L 4.80541644 1.46253327 4.80124911 1.46093317 1 P 0 ;0,1,2=82,3=90.000000
L 4.80124911 1.46093317 4.7975 1.4603999 1 P 0 ;0,1,2=82,3=90.000000
L 4.7975 1.4603999 4.7975 1.4716 1 P 0 ;0,1,2=82,3=90.000000
L 4.81833337 1.48293317 4.82083287 1.48453327 1 P 0 ;0,1,2=82,3=90.000000
L 4.82083287 1.48453327 4.82208337 1.4864 1 P 0 ;0,1,2=82,3=90.000000
L 4.82208337 1.4864 4.8225 1.48853337 1 P 0 ;0,1,2=82,3=90.000000
L 4.8225 1.48853337 4.82166683 1.4912 1 P 0 ;0,1,2=82,3=90.000000
L 4.82166683 1.4912 4.81958317 1.49306673 1 P 0 ;0,1,2=82,3=90.000000
L 4.81958317 1.49306673 4.81708366 1.4936 1 P 0 ;0,1,2=82,3=90.000000
L 4.81708366 1.4936 4.81458268 1.49333337 1 P 0 ;0,1,2=82,3=90.000000
L 4.81458268 1.49333337 4.8124998 1.49226644 1 P 0 ;0,1,2=82,3=90.000000
L 4.8124998 1.49226644 4.80833327 1.48693327 1 P 0 ;0,1,2=82,3=90.000000
L 4.80833327 1.48693327 4.80541644 1.48453327 1 P 0 ;0,1,2=82,3=90.000000
L 4.80541644 1.48453327 4.80124911 1.48293317 1 P 0 ;0,1,2=82,3=90.000000
L 4.80124911 1.48293317 4.7975 1.4823999 1 P 0 ;0,1,2=82,3=90.000000
L 4.7975 1.4823999 4.7975 1.4936 1 P 0 ;0,1,2=82,3=90.000000
L 4.54003996 2.06115 4.54003996 2.09815 1 P 0 
L 4.54003996 2.09815 4.46366004 2.09815 1 P 0 
L 4.46366004 2.09815 4.46366004 2.06115 1 P 0 
L 4.46366004 2.06115 4.54003996 2.06115 1 P 0 
L 4.52713337 2.13541634 4.52873356 2.13666683 1 P 0 ;0,1,2=83,3=0.000000
L 4.52873356 2.13666683 4.5305998 2.1375 1 P 0 ;0,1,2=83,3=0.000000
L 4.5305998 2.1375 4.53273317 2.1375 1 P 0 ;0,1,2=83,3=0.000000
L 4.53273317 2.1375 4.53513366 2.13624941 1 P 0 ;0,1,2=83,3=0.000000
L 4.53513366 2.13624941 4.5369999 2.13416654 1 P 0 ;0,1,2=83,3=0.000000
L 4.5369999 2.13416654 4.53833346 2.13166634 1 P 0 ;0,1,2=83,3=0.000000
L 4.53833346 2.13166634 4.53940039 2.1274998 1 P 0 ;0,1,2=83,3=0.000000
L 4.53940039 2.1274998 4.53966703 2.1237498 1 P 0 ;0,1,2=83,3=0.000000
L 4.53966703 2.1237498 4.53913327 2.1199999 1 P 0 ;0,1,2=83,3=0.000000
L 4.53913327 2.1199999 4.53833346 2.11749961 1 P 0 ;0,1,2=83,3=0.000000
L 4.53833346 2.11749961 4.53673337 2.11499941 1 P 0 ;0,1,2=83,3=0.000000
L 4.53673337 2.11499941 4.53486654 2.11333307 1 P 0 ;0,1,2=83,3=0.000000
L 4.53486654 2.11333307 4.5330003 2.1125 1 P 0 ;0,1,2=83,3=0.000000
L 4.5330003 2.1125 4.53113356 2.1125 1 P 0 ;0,1,2=83,3=0.000000
L 4.53113356 2.1125 4.52926673 2.11333307 1 P 0 ;0,1,2=83,3=0.000000
L 4.52926673 2.11333307 4.52766663 2.11458287 1 P 0 ;0,1,2=83,3=0.000000
L 4.52766663 2.11458287 4.52633307 2.11624911 1 P 0 ;0,1,2=83,3=0.000000
L 4.5110003 2.1125 4.5110003 2.1375 1 P 0 ;0,1,2=83,3=0.000000
L 4.5110003 2.1375 4.5142001 2.1325003 1 P 0 ;0,1,2=83,3=0.000000
L 4.5142001 2.1125 4.50780049 2.1125 1 P 0 ;0,1,2=83,3=0.000000
L 4.49486673 2.11749961 4.49326703 2.11458287 1 P 0 ;0,1,2=83,3=0.000000
L 4.49326703 2.11458287 4.49113366 2.11291654 1 P 0 ;0,1,2=83,3=0.000000
L 4.49113366 2.11291654 4.48873317 2.1125 1 P 0 ;0,1,2=83,3=0.000000
L 4.48873317 2.1125 4.4865998 2.11291654 1 P 0 ;0,1,2=83,3=0.000000
L 4.4865998 2.11291654 4.48446644 2.11499941 1 P 0 ;0,1,2=83,3=0.000000
L 4.48446644 2.11499941 4.48313337 2.11749961 1 P 0 ;0,1,2=83,3=0.000000
L 4.48313337 2.11749961 4.48286683 2.1199999 1 P 0 ;0,1,2=83,3=0.000000
L 4.48286683 2.1199999 4.4834 2.12291594 1 P 0 ;0,1,2=83,3=0.000000
L 4.4834 2.12291594 4.48526673 2.12499961 1 P 0 ;0,1,2=83,3=0.000000
L 4.48526673 2.12499961 4.48713356 2.12583346 1 P 0 ;0,1,2=83,3=0.000000
L 4.48713356 2.12583346 4.48953346 2.12583346 1 P 0 ;0,1,2=83,3=0.000000
L 4.48713356 2.12583346 4.48553337 2.12708327 1 P 0 ;0,1,2=83,3=0.000000
L 4.48553337 2.12708327 4.4841999 2.12916614 1 P 0 ;0,1,2=83,3=0.000000
L 4.4841999 2.12916614 4.48366663 2.13166634 1 P 0 ;0,1,2=83,3=0.000000
L 4.48366663 2.13166634 4.4841999 2.13416654 1 P 0 ;0,1,2=83,3=0.000000
L 4.4841999 2.13416654 4.48553337 2.13624941 1 P 0 ;0,1,2=83,3=0.000000
L 4.48553337 2.13624941 4.48793337 2.1375 1 P 0 ;0,1,2=83,3=0.000000
L 4.48793337 2.1375 4.49033337 2.13708337 1 P 0 ;0,1,2=83,3=0.000000
L 4.49033337 2.13708337 4.49273337 2.13541634 1 P 0 ;0,1,2=83,3=0.000000
L 4.4638 2.1125 4.4638 2.1375 1 P 0 ;0,1,2=83,3=0.000000
L 4.4638 2.1375 4.47366703 2.11958327 1 P 0 ;0,1,2=83,3=0.000000
L 4.47366703 2.11958327 4.46033307 2.11958327 1 P 0 ;0,1,2=83,3=0.000000
L 4.42193002 2.21626998 4.38493002 2.21626998 1 P 0 
L 4.42193002 2.13988996 4.42193002 2.21626998 1 P 0 
L 4.38493002 2.21626998 4.38493002 2.13988996 1 P 0 
L 4.38493002 2.13988996 4.42193002 2.13988996 1 P 0 
L 4.41541634 2.23786663 4.41666683 2.23626644 1 P 0 ;0,1,2=84,3=90.000000
L 4.41666683 2.23626644 4.4175 2.2344002 1 P 0 ;0,1,2=84,3=90.000000
L 4.4175 2.2344002 4.4175 2.23226683 1 P 0 ;0,1,2=84,3=90.000000
L 4.4175 2.23226683 4.41624941 2.22986634 1 P 0 ;0,1,2=84,3=90.000000
L 4.41624941 2.22986634 4.41416654 2.2280001 1 P 0 ;0,1,2=84,3=90.000000
L 4.41416654 2.2280001 4.41166634 2.22666654 1 P 0 ;0,1,2=84,3=90.000000
L 4.41166634 2.22666654 4.4074998 2.22559961 1 P 0 ;0,1,2=84,3=90.000000
L 4.4074998 2.22559961 4.4037498 2.22533297 1 P 0 ;0,1,2=84,3=90.000000
L 4.4037498 2.22533297 4.3999999 2.22586673 1 P 0 ;0,1,2=84,3=90.000000
L 4.3999999 2.22586673 4.39749961 2.22666654 1 P 0 ;0,1,2=84,3=90.000000
L 4.39749961 2.22666654 4.39499941 2.22826663 1 P 0 ;0,1,2=84,3=90.000000
L 4.39499941 2.22826663 4.39333307 2.23013346 1 P 0 ;0,1,2=84,3=90.000000
L 4.39333307 2.23013346 4.3925 2.2319997 1 P 0 ;0,1,2=84,3=90.000000
L 4.3925 2.2319997 4.3925 2.23386644 1 P 0 ;0,1,2=84,3=90.000000
L 4.3925 2.23386644 4.39333307 2.23573327 1 P 0 ;0,1,2=84,3=90.000000
L 4.39333307 2.23573327 4.39458287 2.23733337 1 P 0 ;0,1,2=84,3=90.000000
L 4.39458287 2.23733337 4.39624911 2.23866693 1 P 0 ;0,1,2=84,3=90.000000
L 4.41333337 2.24893317 4.41583287 2.25053327 1 P 0 ;0,1,2=84,3=90.000000
L 4.41583287 2.25053327 4.41708337 2.2524 1 P 0 ;0,1,2=84,3=90.000000
L 4.41708337 2.2524 4.4175 2.25453337 1 P 0 ;0,1,2=84,3=90.000000
L 4.4175 2.25453337 4.41666683 2.2572 1 P 0 ;0,1,2=84,3=90.000000
L 4.41666683 2.2572 4.41458317 2.25906673 1 P 0 ;0,1,2=84,3=90.000000
L 4.41458317 2.25906673 4.41208366 2.2596 1 P 0 ;0,1,2=84,3=90.000000
L 4.41208366 2.2596 4.40958268 2.25933337 1 P 0 ;0,1,2=84,3=90.000000
L 4.40958268 2.25933337 4.4074998 2.25826644 1 P 0 ;0,1,2=84,3=90.000000
L 4.4074998 2.25826644 4.40333327 2.25293327 1 P 0 ;0,1,2=84,3=90.000000
L 4.40333327 2.25293327 4.40041644 2.25053327 1 P 0 ;0,1,2=84,3=90.000000
L 4.40041644 2.25053327 4.39624911 2.24893317 1 P 0 ;0,1,2=84,3=90.000000
L 4.39624911 2.24893317 4.3925 2.2483999 1 P 0 ;0,1,2=84,3=90.000000
L 4.3925 2.2483999 4.3925 2.2596 1 P 0 ;0,1,2=84,3=90.000000
L 4.41333337 2.27093317 4.41583287 2.27253327 1 P 0 ;0,1,2=84,3=90.000000
L 4.41583287 2.27253327 4.41708337 2.2744 1 P 0 ;0,1,2=84,3=90.000000
L 4.41708337 2.2744 4.4175 2.27653337 1 P 0 ;0,1,2=84,3=90.000000
L 4.4175 2.27653337 4.41666683 2.2792 1 P 0 ;0,1,2=84,3=90.000000
L 4.41666683 2.2792 4.41458317 2.28106673 1 P 0 ;0,1,2=84,3=90.000000
L 4.41458317 2.28106673 4.41208366 2.2816 1 P 0 ;0,1,2=84,3=90.000000
L 4.41208366 2.2816 4.40958268 2.28133337 1 P 0 ;0,1,2=84,3=90.000000
L 4.40958268 2.28133337 4.4074998 2.28026644 1 P 0 ;0,1,2=84,3=90.000000
L 4.4074998 2.28026644 4.40333327 2.27493327 1 P 0 ;0,1,2=84,3=90.000000
L 4.40333327 2.27493327 4.40041644 2.27253327 1 P 0 ;0,1,2=84,3=90.000000
L 4.40041644 2.27253327 4.39624911 2.27093317 1 P 0 ;0,1,2=84,3=90.000000
L 4.39624911 2.27093317 4.3925 2.2703999 1 P 0 ;0,1,2=84,3=90.000000
L 4.3925 2.2703999 4.3925 2.2816 1 P 0 ;0,1,2=84,3=90.000000
L 4.39749961 2.29213327 4.39458287 2.29373297 1 P 0 ;0,1,2=84,3=90.000000
L 4.39458287 2.29373297 4.39291654 2.29586634 1 P 0 ;0,1,2=84,3=90.000000
L 4.39291654 2.29586634 4.3925 2.29826683 1 P 0 ;0,1,2=84,3=90.000000
L 4.3925 2.29826683 4.39291654 2.3004002 1 P 0 ;0,1,2=84,3=90.000000
L 4.39291654 2.3004002 4.39499941 2.30253356 1 P 0 ;0,1,2=84,3=90.000000
L 4.39499941 2.30253356 4.39749961 2.30386663 1 P 0 ;0,1,2=84,3=90.000000
L 4.39749961 2.30386663 4.3999999 2.30413317 1 P 0 ;0,1,2=84,3=90.000000
L 4.3999999 2.30413317 4.40291594 2.3036 1 P 0 ;0,1,2=84,3=90.000000
L 4.40291594 2.3036 4.40499961 2.30173327 1 P 0 ;0,1,2=84,3=90.000000
L 4.40499961 2.30173327 4.40583346 2.29986644 1 P 0 ;0,1,2=84,3=90.000000
L 4.40583346 2.29986644 4.40583346 2.29746654 1 P 0 ;0,1,2=84,3=90.000000
L 4.40583346 2.29986644 4.40708327 2.30146663 1 P 0 ;0,1,2=84,3=90.000000
L 4.40708327 2.30146663 4.40916614 2.3028001 1 P 0 ;0,1,2=84,3=90.000000
L 4.40916614 2.3028001 4.41166634 2.30333337 1 P 0 ;0,1,2=84,3=90.000000
L 4.41166634 2.30333337 4.41416654 2.3028001 1 P 0 ;0,1,2=84,3=90.000000
L 4.41416654 2.3028001 4.41624941 2.30146663 1 P 0 ;0,1,2=84,3=90.000000
L 4.41624941 2.30146663 4.4175 2.29906663 1 P 0 ;0,1,2=84,3=90.000000
L 4.4175 2.29906663 4.41708337 2.29666663 1 P 0 ;0,1,2=84,3=90.000000
L 4.41708337 2.29666663 4.41541634 2.29426663 1 P 0 ;0,1,2=84,3=90.000000
L 4.65816004 1.98003996 4.58178002 1.98003996 1 P 0 
L 4.58178002 1.94303996 4.65816004 1.94303996 1 P 0 
L 4.65816004 1.94303996 4.65816004 1.98003996 1 P 0 
L 4.58178002 1.98003996 4.58178002 1.94303996 1 P 0 
L 4.62213337 2.04541634 4.62373356 2.04666683 1 P 0 ;0,1,2=85,3=0.000000
L 4.62373356 2.04666683 4.6255998 2.0475 1 P 0 ;0,1,2=85,3=0.000000
L 4.6255998 2.0475 4.62773317 2.0475 1 P 0 ;0,1,2=85,3=0.000000
L 4.62773317 2.0475 4.63013366 2.04624941 1 P 0 ;0,1,2=85,3=0.000000
L 4.63013366 2.04624941 4.6319999 2.04416654 1 P 0 ;0,1,2=85,3=0.000000
L 4.6319999 2.04416654 4.63333346 2.04166634 1 P 0 ;0,1,2=85,3=0.000000
L 4.63333346 2.04166634 4.63440039 2.0374998 1 P 0 ;0,1,2=85,3=0.000000
L 4.63440039 2.0374998 4.63466703 2.0337498 1 P 0 ;0,1,2=85,3=0.000000
L 4.63466703 2.0337498 4.63413327 2.0299999 1 P 0 ;0,1,2=85,3=0.000000
L 4.63413327 2.0299999 4.63333346 2.02749961 1 P 0 ;0,1,2=85,3=0.000000
L 4.63333346 2.02749961 4.63173337 2.02499941 1 P 0 ;0,1,2=85,3=0.000000
L 4.63173337 2.02499941 4.62986654 2.02333307 1 P 0 ;0,1,2=85,3=0.000000
L 4.62986654 2.02333307 4.6280003 2.0225 1 P 0 ;0,1,2=85,3=0.000000
L 4.6280003 2.0225 4.62613356 2.0225 1 P 0 ;0,1,2=85,3=0.000000
L 4.62613356 2.0225 4.62426673 2.02333307 1 P 0 ;0,1,2=85,3=0.000000
L 4.62426673 2.02333307 4.62266663 2.02458287 1 P 0 ;0,1,2=85,3=0.000000
L 4.62266663 2.02458287 4.62133307 2.02624911 1 P 0 ;0,1,2=85,3=0.000000
L 4.6060003 2.0225 4.6060003 2.0475 1 P 0 ;0,1,2=85,3=0.000000
L 4.6060003 2.0475 4.6092001 2.0425003 1 P 0 ;0,1,2=85,3=0.000000
L 4.6092001 2.0225 4.60280049 2.0225 1 P 0 ;0,1,2=85,3=0.000000
L 4.58986673 2.02749961 4.58826703 2.02458287 1 P 0 ;0,1,2=85,3=0.000000
L 4.58826703 2.02458287 4.58613366 2.02291654 1 P 0 ;0,1,2=85,3=0.000000
L 4.58613366 2.02291654 4.58373317 2.0225 1 P 0 ;0,1,2=85,3=0.000000
L 4.58373317 2.0225 4.5815998 2.02291654 1 P 0 ;0,1,2=85,3=0.000000
L 4.5815998 2.02291654 4.57946644 2.02499941 1 P 0 ;0,1,2=85,3=0.000000
L 4.57946644 2.02499941 4.57813337 2.02749961 1 P 0 ;0,1,2=85,3=0.000000
L 4.57813337 2.02749961 4.57786683 2.0299999 1 P 0 ;0,1,2=85,3=0.000000
L 4.57786683 2.0299999 4.5784 2.03291594 1 P 0 ;0,1,2=85,3=0.000000
L 4.5784 2.03291594 4.58026673 2.03499961 1 P 0 ;0,1,2=85,3=0.000000
L 4.58026673 2.03499961 4.58213356 2.03583346 1 P 0 ;0,1,2=85,3=0.000000
L 4.58213356 2.03583346 4.58453346 2.03583346 1 P 0 ;0,1,2=85,3=0.000000
L 4.58213356 2.03583346 4.58053337 2.03708327 1 P 0 ;0,1,2=85,3=0.000000
L 4.58053337 2.03708327 4.5791999 2.03916614 1 P 0 ;0,1,2=85,3=0.000000
L 4.5791999 2.03916614 4.57866663 2.04166634 1 P 0 ;0,1,2=85,3=0.000000
L 4.57866663 2.04166634 4.5791999 2.04416654 1 P 0 ;0,1,2=85,3=0.000000
L 4.5791999 2.04416654 4.58053337 2.04624941 1 P 0 ;0,1,2=85,3=0.000000
L 4.58053337 2.04624941 4.58293337 2.0475 1 P 0 ;0,1,2=85,3=0.000000
L 4.58293337 2.0475 4.58533337 2.04708337 1 P 0 ;0,1,2=85,3=0.000000
L 4.58533337 2.04708337 4.58773337 2.04541634 1 P 0 ;0,1,2=85,3=0.000000
L 4.5620003 2.0475 4.56413366 2.04666683 1 P 0 ;0,1,2=85,3=0.000000
L 4.56413366 2.04666683 4.56573337 2.04458317 1 P 0 ;0,1,2=85,3=0.000000
L 4.56573337 2.04458317 4.5668002 2.04208366 1 P 0 ;0,1,2=85,3=0.000000
L 4.5668002 2.04208366 4.5676001 2.03874951 1 P 0 ;0,1,2=85,3=0.000000
L 4.5676001 2.03874951 4.56786673 2.03499961 1 P 0 ;0,1,2=85,3=0.000000
L 4.56786673 2.03499961 4.5676001 2.03124961 1 P 0 ;0,1,2=85,3=0.000000
L 4.5676001 2.03124961 4.5668002 2.02791624 1 P 0 ;0,1,2=85,3=0.000000
L 4.5668002 2.02791624 4.56573337 2.02541604 1 P 0 ;0,1,2=85,3=0.000000
L 4.56573337 2.02541604 4.56413366 2.02333307 1 P 0 ;0,1,2=85,3=0.000000
L 4.56413366 2.02333307 4.5620003 2.0225 1 P 0 ;0,1,2=85,3=0.000000
L 4.5620003 2.0225 4.55986693 2.02333307 1 P 0 ;0,1,2=85,3=0.000000
L 4.55986693 2.02333307 4.55826673 2.02541604 1 P 0 ;0,1,2=85,3=0.000000
L 4.55826673 2.02541604 4.5571999 2.02791624 1 P 0 ;0,1,2=85,3=0.000000
L 4.5571999 2.02791624 4.5564 2.03124961 1 P 0 ;0,1,2=85,3=0.000000
L 4.5564 2.03124961 4.55613337 2.03499961 1 P 0 ;0,1,2=85,3=0.000000
L 4.55613337 2.03499961 4.5564 2.03874951 1 P 0 ;0,1,2=85,3=0.000000
L 4.5564 2.03874951 4.5571999 2.04208366 1 P 0 ;0,1,2=85,3=0.000000
L 4.5571999 2.04208366 4.55826673 2.04458317 1 P 0 ;0,1,2=85,3=0.000000
L 4.55826673 2.04458317 4.55986693 2.04666683 1 P 0 ;0,1,2=85,3=0.000000
L 4.55986693 2.04666683 4.5620003 2.0475 1 P 0 ;0,1,2=85,3=0.000000
L 3.99123002 1.5887 4.02823002 1.5887 1 P 0 
L 3.99123002 1.66508002 3.99123002 1.5887 1 P 0 
L 4.02823002 1.66508002 3.99123002 1.66508002 1 P 0 
L 4.02823002 1.5887 4.02823002 1.66508002 1 P 0 
L 2.36541634 1.56286663 2.36666683 1.56126644 1 P 0 ;0,1,2=86,3=90.000000
L 2.36666683 1.56126644 2.3675 1.5594002 1 P 0 ;0,1,2=86,3=90.000000
L 2.3675 1.5594002 2.3675 1.55726683 1 P 0 ;0,1,2=86,3=90.000000
L 2.3675 1.55726683 2.36624941 1.55486634 1 P 0 ;0,1,2=86,3=90.000000
L 2.36624941 1.55486634 2.36416654 1.5530001 1 P 0 ;0,1,2=86,3=90.000000
L 2.36416654 1.5530001 2.36166634 1.55166654 1 P 0 ;0,1,2=86,3=90.000000
L 2.36166634 1.55166654 2.3574998 1.55059961 1 P 0 ;0,1,2=86,3=90.000000
L 2.3574998 1.55059961 2.3537498 1.55033297 1 P 0 ;0,1,2=86,3=90.000000
L 2.3537498 1.55033297 2.3499999 1.55086673 1 P 0 ;0,1,2=86,3=90.000000
L 2.3499999 1.55086673 2.34749961 1.55166654 1 P 0 ;0,1,2=86,3=90.000000
L 2.34749961 1.55166654 2.34499941 1.55326663 1 P 0 ;0,1,2=86,3=90.000000
L 2.34499941 1.55326663 2.34333307 1.55513346 1 P 0 ;0,1,2=86,3=90.000000
L 2.34333307 1.55513346 2.3425 1.5569997 1 P 0 ;0,1,2=86,3=90.000000
L 2.3425 1.5569997 2.3425 1.55886644 1 P 0 ;0,1,2=86,3=90.000000
L 2.3425 1.55886644 2.34333307 1.56073327 1 P 0 ;0,1,2=86,3=90.000000
L 2.34333307 1.56073327 2.34458287 1.56233337 1 P 0 ;0,1,2=86,3=90.000000
L 2.34458287 1.56233337 2.34624911 1.56366693 1 P 0 ;0,1,2=86,3=90.000000
L 2.3425 1.5789997 2.3675 1.5789997 1 P 0 ;0,1,2=86,3=90.000000
L 2.3675 1.5789997 2.3625003 1.5757999 1 P 0 ;0,1,2=86,3=90.000000
L 2.3425 1.5757999 2.3425 1.58219951 1 P 0 ;0,1,2=86,3=90.000000
L 2.34749961 1.59513327 2.34458287 1.59673297 1 P 0 ;0,1,2=86,3=90.000000
L 2.34458287 1.59673297 2.34291654 1.59886634 1 P 0 ;0,1,2=86,3=90.000000
L 2.34291654 1.59886634 2.3425 1.60126683 1 P 0 ;0,1,2=86,3=90.000000
L 2.3425 1.60126683 2.34291654 1.6034002 1 P 0 ;0,1,2=86,3=90.000000
L 2.34291654 1.6034002 2.34499941 1.60553356 1 P 0 ;0,1,2=86,3=90.000000
L 2.34499941 1.60553356 2.34749961 1.60686663 1 P 0 ;0,1,2=86,3=90.000000
L 2.34749961 1.60686663 2.3499999 1.60713317 1 P 0 ;0,1,2=86,3=90.000000
L 2.3499999 1.60713317 2.35291594 1.6066 1 P 0 ;0,1,2=86,3=90.000000
L 2.35291594 1.6066 2.35499961 1.60473327 1 P 0 ;0,1,2=86,3=90.000000
L 2.35499961 1.60473327 2.35583346 1.60286644 1 P 0 ;0,1,2=86,3=90.000000
L 2.35583346 1.60286644 2.35583346 1.60046654 1 P 0 ;0,1,2=86,3=90.000000
L 2.35583346 1.60286644 2.35708327 1.60446663 1 P 0 ;0,1,2=86,3=90.000000
L 2.35708327 1.60446663 2.35916614 1.6058001 1 P 0 ;0,1,2=86,3=90.000000
L 2.35916614 1.6058001 2.36166634 1.60633337 1 P 0 ;0,1,2=86,3=90.000000
L 2.36166634 1.60633337 2.36416654 1.6058001 1 P 0 ;0,1,2=86,3=90.000000
L 2.36416654 1.6058001 2.36624941 1.60446663 1 P 0 ;0,1,2=86,3=90.000000
L 2.36624941 1.60446663 2.3675 1.60206663 1 P 0 ;0,1,2=86,3=90.000000
L 2.3675 1.60206663 2.36708337 1.59966663 1 P 0 ;0,1,2=86,3=90.000000
L 2.36708337 1.59966663 2.36541634 1.59726663 1 P 0 ;0,1,2=86,3=90.000000
L 2.3425 1.6229997 2.3675 1.6229997 1 P 0 ;0,1,2=86,3=90.000000
L 2.3675 1.6229997 2.3625003 1.6197999 1 P 0 ;0,1,2=86,3=90.000000
L 2.3425 1.6197999 2.3425 1.62619951 1 P 0 ;0,1,2=86,3=90.000000
L 3.91248002 1.54696998 3.91248002 1.50996998 1 P 0 
L 3.98886004 1.54696998 3.91248002 1.54696998 1 P 0 
L 3.98886004 1.50996998 3.98886004 1.54696998 1 P 0 
L 3.91248002 1.50996998 3.98886004 1.50996998 1 P 0 
L 2.30213337 1.50041634 2.30373356 1.50166683 1 P 0 ;0,1,2=87,3=0.000000
L 2.30373356 1.50166683 2.3055998 1.5025 1 P 0 ;0,1,2=87,3=0.000000
L 2.3055998 1.5025 2.30773317 1.5025 1 P 0 ;0,1,2=87,3=0.000000
L 2.30773317 1.5025 2.31013366 1.50124941 1 P 0 ;0,1,2=87,3=0.000000
L 2.31013366 1.50124941 2.3119999 1.49916654 1 P 0 ;0,1,2=87,3=0.000000
L 2.3119999 1.49916654 2.31333346 1.49666634 1 P 0 ;0,1,2=87,3=0.000000
L 2.31333346 1.49666634 2.31440039 1.4924998 1 P 0 ;0,1,2=87,3=0.000000
L 2.31440039 1.4924998 2.31466703 1.4887498 1 P 0 ;0,1,2=87,3=0.000000
L 2.31466703 1.4887498 2.31413327 1.4849999 1 P 0 ;0,1,2=87,3=0.000000
L 2.31413327 1.4849999 2.31333346 1.48249961 1 P 0 ;0,1,2=87,3=0.000000
L 2.31333346 1.48249961 2.31173337 1.47999941 1 P 0 ;0,1,2=87,3=0.000000
L 2.31173337 1.47999941 2.30986654 1.47833307 1 P 0 ;0,1,2=87,3=0.000000
L 2.30986654 1.47833307 2.3080003 1.4775 1 P 0 ;0,1,2=87,3=0.000000
L 2.3080003 1.4775 2.30613356 1.4775 1 P 0 ;0,1,2=87,3=0.000000
L 2.30613356 1.4775 2.30426673 1.47833307 1 P 0 ;0,1,2=87,3=0.000000
L 2.30426673 1.47833307 2.30266663 1.47958287 1 P 0 ;0,1,2=87,3=0.000000
L 2.30266663 1.47958287 2.30133307 1.48124911 1 P 0 ;0,1,2=87,3=0.000000
L 2.2860003 1.4775 2.2860003 1.5025 1 P 0 ;0,1,2=87,3=0.000000
L 2.2860003 1.5025 2.2892001 1.4975003 1 P 0 ;0,1,2=87,3=0.000000
L 2.2892001 1.4775 2.28280049 1.4775 1 P 0 ;0,1,2=87,3=0.000000
L 2.2640003 1.4775 2.2640003 1.5025 1 P 0 ;0,1,2=87,3=0.000000
L 2.2640003 1.5025 2.2672001 1.4975003 1 P 0 ;0,1,2=87,3=0.000000
L 2.2672001 1.4775 2.26080049 1.4775 1 P 0 ;0,1,2=87,3=0.000000
L 2.24253346 1.4775 2.2420003 1.48291624 1 P 0 ;0,1,2=87,3=0.000000
L 2.2420003 1.48291624 2.2412 1.48749931 1 P 0 ;0,1,2=87,3=0.000000
L 2.2412 1.48749931 2.24013356 1.49166663 1 P 0 ;0,1,2=87,3=0.000000
L 2.24013356 1.49166663 2.2388 1.4962498 1 P 0 ;0,1,2=87,3=0.000000
L 2.2388 1.4962498 2.23666663 1.5025 1 P 0 ;0,1,2=87,3=0.000000
L 2.23666663 1.5025 2.24733346 1.5025 1 P 0 ;0,1,2=87,3=0.000000
L 4.02823002 1.90366998 4.02823002 1.94066998 1 P 0 
L 4.02823002 1.94066998 3.95185 1.94066998 1 P 0 
L 3.95185 1.94066998 3.95185 1.90366998 1 P 0 
L 3.95185 1.90366998 4.02823002 1.90366998 1 P 0 
L 3.97213337 1.89241634 3.97373356 1.89366683 1 P 0 ;0,1,2=88,3=0.000000
L 3.97373356 1.89366683 3.9755998 1.8945 1 P 0 ;0,1,2=88,3=0.000000
L 3.9755998 1.8945 3.97773317 1.8945 1 P 0 ;0,1,2=88,3=0.000000
L 3.97773317 1.8945 3.98013366 1.89324941 1 P 0 ;0,1,2=88,3=0.000000
L 3.98013366 1.89324941 3.9819999 1.89116654 1 P 0 ;0,1,2=88,3=0.000000
L 3.9819999 1.89116654 3.98333346 1.88866634 1 P 0 ;0,1,2=88,3=0.000000
L 3.98333346 1.88866634 3.98440039 1.8844998 1 P 0 ;0,1,2=88,3=0.000000
L 3.98440039 1.8844998 3.98466703 1.8807498 1 P 0 ;0,1,2=88,3=0.000000
L 3.98466703 1.8807498 3.98413327 1.8769999 1 P 0 ;0,1,2=88,3=0.000000
L 3.98413327 1.8769999 3.98333346 1.87449961 1 P 0 ;0,1,2=88,3=0.000000
L 3.98333346 1.87449961 3.98173337 1.87199941 1 P 0 ;0,1,2=88,3=0.000000
L 3.98173337 1.87199941 3.97986654 1.87033307 1 P 0 ;0,1,2=88,3=0.000000
L 3.97986654 1.87033307 3.9780003 1.8695 1 P 0 ;0,1,2=88,3=0.000000
L 3.9780003 1.8695 3.97613356 1.8695 1 P 0 ;0,1,2=88,3=0.000000
L 3.97613356 1.8695 3.97426673 1.87033307 1 P 0 ;0,1,2=88,3=0.000000
L 3.97426673 1.87033307 3.97266663 1.87158287 1 P 0 ;0,1,2=88,3=0.000000
L 3.97266663 1.87158287 3.97133307 1.87324911 1 P 0 ;0,1,2=88,3=0.000000
L 3.9560003 1.8695 3.9560003 1.8945 1 P 0 ;0,1,2=88,3=0.000000
L 3.9560003 1.8945 3.9592001 1.8895003 1 P 0 ;0,1,2=88,3=0.000000
L 3.9592001 1.8695 3.95280049 1.8695 1 P 0 ;0,1,2=88,3=0.000000
L 3.93906683 1.87991594 3.9372001 1.88283346 1 P 0 ;0,1,2=88,3=0.000000
L 3.9372001 1.88283346 3.9356 1.8844998 1 P 0 ;0,1,2=88,3=0.000000
L 3.9356 1.8844998 3.93346663 1.88533297 1 P 0 ;0,1,2=88,3=0.000000
L 3.93346663 1.88533297 3.9315998 1.8844998 1 P 0 ;0,1,2=88,3=0.000000
L 3.9315998 1.8844998 3.93026673 1.88283346 1 P 0 ;0,1,2=88,3=0.000000
L 3.93026673 1.88283346 3.9291999 1.88033327 1 P 0 ;0,1,2=88,3=0.000000
L 3.9291999 1.88033327 3.92893327 1.87741644 1 P 0 ;0,1,2=88,3=0.000000
L 3.92893327 1.87741644 3.9291999 1.87491624 1 P 0 ;0,1,2=88,3=0.000000
L 3.9291999 1.87491624 3.93026673 1.87241604 1 P 0 ;0,1,2=88,3=0.000000
L 3.93026673 1.87241604 3.93186693 1.87033307 1 P 0 ;0,1,2=88,3=0.000000
L 3.93186693 1.87033307 3.93373317 1.8695 1 P 0 ;0,1,2=88,3=0.000000
L 3.93373317 1.8695 3.93586654 1.87033307 1 P 0 ;0,1,2=88,3=0.000000
L 3.93586654 1.87033307 3.93773337 1.87283258 1 P 0 ;0,1,2=88,3=0.000000
L 3.93773337 1.87283258 3.9388002 1.87658327 1 P 0 ;0,1,2=88,3=0.000000
L 3.9388002 1.87658327 3.93906683 1.8807498 1 P 0 ;0,1,2=88,3=0.000000
L 3.93906683 1.8807498 3.93853366 1.88616614 1 P 0 ;0,1,2=88,3=0.000000
L 3.93853366 1.88616614 3.93773337 1.88908366 1 P 0 ;0,1,2=88,3=0.000000
L 3.93773337 1.88908366 3.9364003 1.8919997 1 P 0 ;0,1,2=88,3=0.000000
L 3.9364003 1.8919997 3.93453346 1.89408337 1 P 0 ;0,1,2=88,3=0.000000
L 3.93453346 1.89408337 3.93266673 1.8945 1 P 0 ;0,1,2=88,3=0.000000
L 3.93266673 1.8945 3.9308 1.89366683 1 P 0 ;0,1,2=88,3=0.000000
L 3.9308 1.89366683 3.92946644 1.89158317 1 P 0 ;0,1,2=88,3=0.000000
L 3.91253346 1.8695 3.9120003 1.87491624 1 P 0 ;0,1,2=88,3=0.000000
L 3.9120003 1.87491624 3.9112 1.87949931 1 P 0 ;0,1,2=88,3=0.000000
L 3.9112 1.87949931 3.91013356 1.88366663 1 P 0 ;0,1,2=88,3=0.000000
L 3.91013356 1.88366663 3.9088 1.8882498 1 P 0 ;0,1,2=88,3=0.000000
L 3.9088 1.8882498 3.90666663 1.8945 1 P 0 ;0,1,2=88,3=0.000000
L 3.90666663 1.8945 3.91733346 1.8945 1 P 0 ;0,1,2=88,3=0.000000
L 4.22508002 1.66508002 4.18808002 1.66508002 1 P 0 
L 4.18808002 1.66508002 4.18808002 1.5887 1 P 0 
L 4.18808002 1.5887 4.22508002 1.5887 1 P 0 
L 4.22508002 1.5887 4.22508002 1.66508002 1 P 0 
L 2.58901634 1.55976663 2.59026683 1.55816644 1 P 0 ;0,1,2=89,3=90.000000
L 2.59026683 1.55816644 2.5911 1.5563002 1 P 0 ;0,1,2=89,3=90.000000
L 2.5911 1.5563002 2.5911 1.55416683 1 P 0 ;0,1,2=89,3=90.000000
L 2.5911 1.55416683 2.58984941 1.55176634 1 P 0 ;0,1,2=89,3=90.000000
L 2.58984941 1.55176634 2.58776654 1.5499001 1 P 0 ;0,1,2=89,3=90.000000
L 2.58776654 1.5499001 2.58526634 1.54856654 1 P 0 ;0,1,2=89,3=90.000000
L 2.58526634 1.54856654 2.5810998 1.54749961 1 P 0 ;0,1,2=89,3=90.000000
L 2.5810998 1.54749961 2.5773498 1.54723297 1 P 0 ;0,1,2=89,3=90.000000
L 2.5773498 1.54723297 2.5735999 1.54776673 1 P 0 ;0,1,2=89,3=90.000000
L 2.5735999 1.54776673 2.57109961 1.54856654 1 P 0 ;0,1,2=89,3=90.000000
L 2.57109961 1.54856654 2.56859941 1.55016663 1 P 0 ;0,1,2=89,3=90.000000
L 2.56859941 1.55016663 2.56693307 1.55203346 1 P 0 ;0,1,2=89,3=90.000000
L 2.56693307 1.55203346 2.5661 1.5538997 1 P 0 ;0,1,2=89,3=90.000000
L 2.5661 1.5538997 2.5661 1.55576644 1 P 0 ;0,1,2=89,3=90.000000
L 2.5661 1.55576644 2.56693307 1.55763327 1 P 0 ;0,1,2=89,3=90.000000
L 2.56693307 1.55763327 2.56818287 1.55923337 1 P 0 ;0,1,2=89,3=90.000000
L 2.56818287 1.55923337 2.56984911 1.56056693 1 P 0 ;0,1,2=89,3=90.000000
L 2.5661 1.5758997 2.5911 1.5758997 1 P 0 ;0,1,2=89,3=90.000000
L 2.5911 1.5758997 2.5861003 1.5726999 1 P 0 ;0,1,2=89,3=90.000000
L 2.5661 1.5726999 2.5661 1.57909951 1 P 0 ;0,1,2=89,3=90.000000
L 2.58693337 1.59283317 2.58943287 1.59443327 1 P 0 ;0,1,2=89,3=90.000000
L 2.58943287 1.59443327 2.59068337 1.5963 1 P 0 ;0,1,2=89,3=90.000000
L 2.59068337 1.5963 2.5911 1.59843337 1 P 0 ;0,1,2=89,3=90.000000
L 2.5911 1.59843337 2.59026683 1.6011 1 P 0 ;0,1,2=89,3=90.000000
L 2.59026683 1.6011 2.58818317 1.60296673 1 P 0 ;0,1,2=89,3=90.000000
L 2.58818317 1.60296673 2.58568366 1.6035 1 P 0 ;0,1,2=89,3=90.000000
L 2.58568366 1.6035 2.58318268 1.60323337 1 P 0 ;0,1,2=89,3=90.000000
L 2.58318268 1.60323337 2.5810998 1.60216644 1 P 0 ;0,1,2=89,3=90.000000
L 2.5810998 1.60216644 2.57693327 1.59683327 1 P 0 ;0,1,2=89,3=90.000000
L 2.57693327 1.59683327 2.57401644 1.59443327 1 P 0 ;0,1,2=89,3=90.000000
L 2.57401644 1.59443327 2.56984911 1.59283317 1 P 0 ;0,1,2=89,3=90.000000
L 2.56984911 1.59283317 2.5661 1.5922999 1 P 0 ;0,1,2=89,3=90.000000
L 2.5661 1.5922999 2.5661 1.6035 1 P 0 ;0,1,2=89,3=90.000000
L 2.5911 1.6198997 2.59026683 1.61776634 1 P 0 ;0,1,2=89,3=90.000000
L 2.59026683 1.61776634 2.58818317 1.61616663 1 P 0 ;0,1,2=89,3=90.000000
L 2.58818317 1.61616663 2.58568366 1.6150998 1 P 0 ;0,1,2=89,3=90.000000
L 2.58568366 1.6150998 2.58234951 1.6142999 1 P 0 ;0,1,2=89,3=90.000000
L 2.58234951 1.6142999 2.57859961 1.61403327 1 P 0 ;0,1,2=89,3=90.000000
L 2.57859961 1.61403327 2.57484961 1.6142999 1 P 0 ;0,1,2=89,3=90.000000
L 2.57484961 1.6142999 2.57151624 1.6150998 1 P 0 ;0,1,2=89,3=90.000000
L 2.57151624 1.6150998 2.56901604 1.61616663 1 P 0 ;0,1,2=89,3=90.000000
L 2.56901604 1.61616663 2.56693307 1.61776634 1 P 0 ;0,1,2=89,3=90.000000
L 2.56693307 1.61776634 2.5661 1.6198997 1 P 0 ;0,1,2=89,3=90.000000
L 2.5661 1.6198997 2.56693307 1.62203307 1 P 0 ;0,1,2=89,3=90.000000
L 2.56693307 1.62203307 2.56901604 1.62363327 1 P 0 ;0,1,2=89,3=90.000000
L 2.56901604 1.62363327 2.57151624 1.6247001 1 P 0 ;0,1,2=89,3=90.000000
L 2.57151624 1.6247001 2.57484961 1.6255 1 P 0 ;0,1,2=89,3=90.000000
L 2.57484961 1.6255 2.57859961 1.62576663 1 P 0 ;0,1,2=89,3=90.000000
L 2.57859961 1.62576663 2.58234951 1.6255 1 P 0 ;0,1,2=89,3=90.000000
L 2.58234951 1.6255 2.58568366 1.6247001 1 P 0 ;0,1,2=89,3=90.000000
L 2.58568366 1.6247001 2.58818317 1.62363327 1 P 0 ;0,1,2=89,3=90.000000
L 2.58818317 1.62363327 2.59026683 1.62203307 1 P 0 ;0,1,2=89,3=90.000000
L 2.59026683 1.62203307 2.5911 1.6198997 1 P 0 ;0,1,2=89,3=90.000000
L 4.0676 1.98005 4.0306 1.98005 1 P 0 
L 4.0676 1.90366998 4.0676 1.98005 1 P 0 
L 4.0306 1.98005 4.0306 1.90366998 1 P 0 
L 4.0306 1.90366998 4.0676 1.90366998 1 P 0 
L 4.05041634 1.99786663 4.05166683 1.99626644 1 P 0 ;0,1,2=90,3=90.000000
L 4.05166683 1.99626644 4.0525 1.9944002 1 P 0 ;0,1,2=90,3=90.000000
L 4.0525 1.9944002 4.0525 1.99226683 1 P 0 ;0,1,2=90,3=90.000000
L 4.0525 1.99226683 4.05124941 1.98986634 1 P 0 ;0,1,2=90,3=90.000000
L 4.05124941 1.98986634 4.04916654 1.9880001 1 P 0 ;0,1,2=90,3=90.000000
L 4.04916654 1.9880001 4.04666634 1.98666654 1 P 0 ;0,1,2=90,3=90.000000
L 4.04666634 1.98666654 4.0424998 1.98559961 1 P 0 ;0,1,2=90,3=90.000000
L 4.0424998 1.98559961 4.0387498 1.98533297 1 P 0 ;0,1,2=90,3=90.000000
L 4.0387498 1.98533297 4.0349999 1.98586673 1 P 0 ;0,1,2=90,3=90.000000
L 4.0349999 1.98586673 4.03249961 1.98666654 1 P 0 ;0,1,2=90,3=90.000000
L 4.03249961 1.98666654 4.02999941 1.98826663 1 P 0 ;0,1,2=90,3=90.000000
L 4.02999941 1.98826663 4.02833307 1.99013346 1 P 0 ;0,1,2=90,3=90.000000
L 4.02833307 1.99013346 4.0275 1.9919997 1 P 0 ;0,1,2=90,3=90.000000
L 4.0275 1.9919997 4.0275 1.99386644 1 P 0 ;0,1,2=90,3=90.000000
L 4.0275 1.99386644 4.02833307 1.99573327 1 P 0 ;0,1,2=90,3=90.000000
L 4.02833307 1.99573327 4.02958287 1.99733337 1 P 0 ;0,1,2=90,3=90.000000
L 4.02958287 1.99733337 4.03124911 1.99866693 1 P 0 ;0,1,2=90,3=90.000000
L 4.0275 2.0139997 4.0525 2.0139997 1 P 0 ;0,1,2=90,3=90.000000
L 4.0525 2.0139997 4.0475003 2.0107999 1 P 0 ;0,1,2=90,3=90.000000
L 4.0275 2.0107999 4.0275 2.01719951 1 P 0 ;0,1,2=90,3=90.000000
L 4.0275 2.03546654 4.03291624 2.0359997 1 P 0 ;0,1,2=90,3=90.000000
L 4.03291624 2.0359997 4.03749931 2.0368 1 P 0 ;0,1,2=90,3=90.000000
L 4.03749931 2.0368 4.04166663 2.03786644 1 P 0 ;0,1,2=90,3=90.000000
L 4.04166663 2.03786644 4.0462498 2.0392 1 P 0 ;0,1,2=90,3=90.000000
L 4.0462498 2.0392 4.0525 2.04133337 1 P 0 ;0,1,2=90,3=90.000000
L 4.0525 2.04133337 4.0525 2.03066654 1 P 0 ;0,1,2=90,3=90.000000
L 4.0525 2.0579997 4.05166683 2.05586634 1 P 0 ;0,1,2=90,3=90.000000
L 4.05166683 2.05586634 4.04958317 2.05426663 1 P 0 ;0,1,2=90,3=90.000000
L 4.04958317 2.05426663 4.04708366 2.0531998 1 P 0 ;0,1,2=90,3=90.000000
L 4.04708366 2.0531998 4.04374951 2.0523999 1 P 0 ;0,1,2=90,3=90.000000
L 4.04374951 2.0523999 4.03999961 2.05213327 1 P 0 ;0,1,2=90,3=90.000000
L 4.03999961 2.05213327 4.03624961 2.0523999 1 P 0 ;0,1,2=90,3=90.000000
L 4.03624961 2.0523999 4.03291624 2.0531998 1 P 0 ;0,1,2=90,3=90.000000
L 4.03291624 2.0531998 4.03041604 2.05426663 1 P 0 ;0,1,2=90,3=90.000000
L 4.03041604 2.05426663 4.02833307 2.05586634 1 P 0 ;0,1,2=90,3=90.000000
L 4.02833307 2.05586634 4.0275 2.0579997 1 P 0 ;0,1,2=90,3=90.000000
L 4.0275 2.0579997 4.02833307 2.06013307 1 P 0 ;0,1,2=90,3=90.000000
L 4.02833307 2.06013307 4.03041604 2.06173327 1 P 0 ;0,1,2=90,3=90.000000
L 4.03041604 2.06173327 4.03291624 2.0628001 1 P 0 ;0,1,2=90,3=90.000000
L 4.03291624 2.0628001 4.03624961 2.0636 1 P 0 ;0,1,2=90,3=90.000000
L 4.03624961 2.0636 4.03999961 2.06386663 1 P 0 ;0,1,2=90,3=90.000000
L 4.03999961 2.06386663 4.04374951 2.0636 1 P 0 ;0,1,2=90,3=90.000000
L 4.04374951 2.0636 4.04708366 2.0628001 1 P 0 ;0,1,2=90,3=90.000000
L 4.04708366 2.0628001 4.04958317 2.06173327 1 P 0 ;0,1,2=90,3=90.000000
L 4.04958317 2.06173327 4.05166683 2.06013307 1 P 0 ;0,1,2=90,3=90.000000
L 4.05166683 2.06013307 4.0525 2.0579997 1 P 0 ;0,1,2=90,3=90.000000
L 4.4243 1.66745 4.50068002 1.66745 1 P 0 
L 4.50068002 1.66745 4.50068002 1.70445 1 P 0 
L 4.50068002 1.70445 4.4243 1.70445 1 P 0 
L 4.4243 1.70445 4.4243 1.66745 1 P 0 
L 2.83963337 1.64841634 2.84123356 1.64966683 1 P 0 ;0,1,2=91,3=0.000000
L 2.84123356 1.64966683 2.8430998 1.6505 1 P 0 ;0,1,2=91,3=0.000000
L 2.8430998 1.6505 2.84523317 1.6505 1 P 0 ;0,1,2=91,3=0.000000
L 2.84523317 1.6505 2.84763366 1.64924941 1 P 0 ;0,1,2=91,3=0.000000
L 2.84763366 1.64924941 2.8494999 1.64716654 1 P 0 ;0,1,2=91,3=0.000000
L 2.8494999 1.64716654 2.85083346 1.64466634 1 P 0 ;0,1,2=91,3=0.000000
L 2.85083346 1.64466634 2.85190039 1.6404998 1 P 0 ;0,1,2=91,3=0.000000
L 2.85190039 1.6404998 2.85216703 1.6367498 1 P 0 ;0,1,2=91,3=0.000000
L 2.85216703 1.6367498 2.85163327 1.6329999 1 P 0 ;0,1,2=91,3=0.000000
L 2.85163327 1.6329999 2.85083346 1.63049961 1 P 0 ;0,1,2=91,3=0.000000
L 2.85083346 1.63049961 2.84923337 1.62799941 1 P 0 ;0,1,2=91,3=0.000000
L 2.84923337 1.62799941 2.84736654 1.62633307 1 P 0 ;0,1,2=91,3=0.000000
L 2.84736654 1.62633307 2.8455003 1.6255 1 P 0 ;0,1,2=91,3=0.000000
L 2.8455003 1.6255 2.84363356 1.6255 1 P 0 ;0,1,2=91,3=0.000000
L 2.84363356 1.6255 2.84176673 1.62633307 1 P 0 ;0,1,2=91,3=0.000000
L 2.84176673 1.62633307 2.84016663 1.62758287 1 P 0 ;0,1,2=91,3=0.000000
L 2.84016663 1.62758287 2.83883307 1.62924911 1 P 0 ;0,1,2=91,3=0.000000
L 2.8235003 1.6255 2.8235003 1.6505 1 P 0 ;0,1,2=91,3=0.000000
L 2.8235003 1.6505 2.8267001 1.6455003 1 P 0 ;0,1,2=91,3=0.000000
L 2.8267001 1.6255 2.82030049 1.6255 1 P 0 ;0,1,2=91,3=0.000000
L 2.80736673 1.63049961 2.80576703 1.62758287 1 P 0 ;0,1,2=91,3=0.000000
L 2.80576703 1.62758287 2.80363366 1.62591654 1 P 0 ;0,1,2=91,3=0.000000
L 2.80363366 1.62591654 2.80123317 1.6255 1 P 0 ;0,1,2=91,3=0.000000
L 2.80123317 1.6255 2.7990998 1.62591654 1 P 0 ;0,1,2=91,3=0.000000
L 2.7990998 1.62591654 2.79696644 1.62799941 1 P 0 ;0,1,2=91,3=0.000000
L 2.79696644 1.62799941 2.79563337 1.63049961 1 P 0 ;0,1,2=91,3=0.000000
L 2.79563337 1.63049961 2.79536683 1.6329999 1 P 0 ;0,1,2=91,3=0.000000
L 2.79536683 1.6329999 2.7959 1.63591594 1 P 0 ;0,1,2=91,3=0.000000
L 2.7959 1.63591594 2.79776673 1.63799961 1 P 0 ;0,1,2=91,3=0.000000
L 2.79776673 1.63799961 2.79963356 1.63883346 1 P 0 ;0,1,2=91,3=0.000000
L 2.79963356 1.63883346 2.80203346 1.63883346 1 P 0 ;0,1,2=91,3=0.000000
L 2.79963356 1.63883346 2.79803337 1.64008327 1 P 0 ;0,1,2=91,3=0.000000
L 2.79803337 1.64008327 2.7966999 1.64216614 1 P 0 ;0,1,2=91,3=0.000000
L 2.7966999 1.64216614 2.79616663 1.64466634 1 P 0 ;0,1,2=91,3=0.000000
L 2.79616663 1.64466634 2.7966999 1.64716654 1 P 0 ;0,1,2=91,3=0.000000
L 2.7966999 1.64716654 2.79803337 1.64924941 1 P 0 ;0,1,2=91,3=0.000000
L 2.79803337 1.64924941 2.80043337 1.6505 1 P 0 ;0,1,2=91,3=0.000000
L 2.80043337 1.6505 2.80283337 1.65008337 1 P 0 ;0,1,2=91,3=0.000000
L 2.80283337 1.65008337 2.80523337 1.64841634 1 P 0 ;0,1,2=91,3=0.000000
L 2.7795003 1.6255 2.77763356 1.62591654 1 P 0 ;0,1,2=91,3=0.000000
L 2.77763356 1.62591654 2.7755002 1.62716624 1 P 0 ;0,1,2=91,3=0.000000
L 2.7755002 1.62716624 2.77416663 1.62924911 1 P 0 ;0,1,2=91,3=0.000000
L 2.77416663 1.62924911 2.77363337 1.63216673 1 P 0 ;0,1,2=91,3=0.000000
L 2.77363337 1.63216673 2.77416663 1.63508278 1 P 0 ;0,1,2=91,3=0.000000
L 2.77416663 1.63508278 2.77576673 1.63758297 1 P 0 ;0,1,2=91,3=0.000000
L 2.77576673 1.63758297 2.77816673 1.63883346 1 P 0 ;0,1,2=91,3=0.000000
L 2.77816673 1.63883346 2.78083337 1.63883346 1 P 0 ;0,1,2=91,3=0.000000
L 2.78083337 1.63883346 2.78243346 1.63966663 1 P 0 ;0,1,2=91,3=0.000000
L 2.78243346 1.63966663 2.78376703 1.64174951 1 P 0 ;0,1,2=91,3=0.000000
L 2.78376703 1.64174951 2.7843002 1.64466634 1 P 0 ;0,1,2=91,3=0.000000
L 2.7843002 1.64466634 2.7834999 1.64758317 1 P 0 ;0,1,2=91,3=0.000000
L 2.7834999 1.64758317 2.78163366 1.64966683 1 P 0 ;0,1,2=91,3=0.000000
L 2.78163366 1.64966683 2.7795003 1.6505 1 P 0 ;0,1,2=91,3=0.000000
L 2.7795003 1.6505 2.77736693 1.64966683 1 P 0 ;0,1,2=91,3=0.000000
L 2.77736693 1.64966683 2.7755002 1.64758317 1 P 0 ;0,1,2=91,3=0.000000
L 2.7755002 1.64758317 2.7746999 1.64466634 1 P 0 ;0,1,2=91,3=0.000000
L 2.7746999 1.64466634 2.77523356 1.64174951 1 P 0 ;0,1,2=91,3=0.000000
L 2.77523356 1.64174951 2.77656663 1.63966663 1 P 0 ;0,1,2=91,3=0.000000
L 2.77656663 1.63966663 2.77816673 1.63883346 1 P 0 ;0,1,2=91,3=0.000000
L 2.77816673 1.63883346 2.78083337 1.63883346 1 P 0 ;0,1,2=91,3=0.000000
L 2.78083337 1.63883346 2.78323337 1.63758297 1 P 0 ;0,1,2=91,3=0.000000
L 2.78323337 1.63758297 2.78483346 1.63508278 1 P 0 ;0,1,2=91,3=0.000000
L 2.78483346 1.63508278 2.78536673 1.63216673 1 P 0 ;0,1,2=91,3=0.000000
L 2.78536673 1.63216673 2.78483346 1.62924911 1 P 0 ;0,1,2=91,3=0.000000
L 2.78483346 1.62924911 2.7834999 1.62716624 1 P 0 ;0,1,2=91,3=0.000000
L 2.7834999 1.62716624 2.78136654 1.62591654 1 P 0 ;0,1,2=91,3=0.000000
L 2.78136654 1.62591654 2.7795003 1.6255 1 P 0 ;0,1,2=91,3=0.000000
L 4.54003996 1.35246998 4.54003996 1.42885 1 P 0 
L 4.54003996 1.42885 4.50303996 1.42885 1 P 0 
L 4.50303996 1.42885 4.50303996 1.35246998 1 P 0 
L 4.50303996 1.35246998 4.54003996 1.35246998 1 P 0 
L 4.49541634 1.33286663 4.49666683 1.33126644 1 P 0 ;0,1,2=92,3=90.000000
L 4.49666683 1.33126644 4.4975 1.3294002 1 P 0 ;0,1,2=92,3=90.000000
L 4.4975 1.3294002 4.4975 1.32726683 1 P 0 ;0,1,2=92,3=90.000000
L 4.4975 1.32726683 4.49624941 1.32486634 1 P 0 ;0,1,2=92,3=90.000000
L 4.49624941 1.32486634 4.49416654 1.3230001 1 P 0 ;0,1,2=92,3=90.000000
L 4.49416654 1.3230001 4.49166634 1.32166654 1 P 0 ;0,1,2=92,3=90.000000
L 4.49166634 1.32166654 4.4874998 1.32059961 1 P 0 ;0,1,2=92,3=90.000000
L 4.4874998 1.32059961 4.4837498 1.32033297 1 P 0 ;0,1,2=92,3=90.000000
L 4.4837498 1.32033297 4.4799999 1.32086673 1 P 0 ;0,1,2=92,3=90.000000
L 4.4799999 1.32086673 4.47749961 1.32166654 1 P 0 ;0,1,2=92,3=90.000000
L 4.47749961 1.32166654 4.47499941 1.32326663 1 P 0 ;0,1,2=92,3=90.000000
L 4.47499941 1.32326663 4.47333307 1.32513346 1 P 0 ;0,1,2=92,3=90.000000
L 4.47333307 1.32513346 4.4725 1.3269997 1 P 0 ;0,1,2=92,3=90.000000
L 4.4725 1.3269997 4.4725 1.32886644 1 P 0 ;0,1,2=92,3=90.000000
L 4.4725 1.32886644 4.47333307 1.33073327 1 P 0 ;0,1,2=92,3=90.000000
L 4.47333307 1.33073327 4.47458287 1.33233337 1 P 0 ;0,1,2=92,3=90.000000
L 4.47458287 1.33233337 4.47624911 1.33366693 1 P 0 ;0,1,2=92,3=90.000000
L 4.4725 1.3489997 4.4975 1.3489997 1 P 0 ;0,1,2=92,3=90.000000
L 4.4975 1.3489997 4.4925003 1.3457999 1 P 0 ;0,1,2=92,3=90.000000
L 4.4725 1.3457999 4.4725 1.35219951 1 P 0 ;0,1,2=92,3=90.000000
L 4.48291594 1.36593317 4.48583346 1.3677999 1 P 0 ;0,1,2=92,3=90.000000
L 4.48583346 1.3677999 4.4874998 1.3694 1 P 0 ;0,1,2=92,3=90.000000
L 4.4874998 1.3694 4.48833297 1.37153337 1 P 0 ;0,1,2=92,3=90.000000
L 4.48833297 1.37153337 4.4874998 1.3734002 1 P 0 ;0,1,2=92,3=90.000000
L 4.4874998 1.3734002 4.48583346 1.37473327 1 P 0 ;0,1,2=92,3=90.000000
L 4.48583346 1.37473327 4.48333327 1.3758001 1 P 0 ;0,1,2=92,3=90.000000
L 4.48333327 1.3758001 4.48041644 1.37606673 1 P 0 ;0,1,2=92,3=90.000000
L 4.48041644 1.37606673 4.47791624 1.3758001 1 P 0 ;0,1,2=92,3=90.000000
L 4.47791624 1.3758001 4.47541604 1.37473327 1 P 0 ;0,1,2=92,3=90.000000
L 4.47541604 1.37473327 4.47333307 1.37313307 1 P 0 ;0,1,2=92,3=90.000000
L 4.47333307 1.37313307 4.4725 1.37126683 1 P 0 ;0,1,2=92,3=90.000000
L 4.4725 1.37126683 4.47333307 1.36913346 1 P 0 ;0,1,2=92,3=90.000000
L 4.47333307 1.36913346 4.47583258 1.36726663 1 P 0 ;0,1,2=92,3=90.000000
L 4.47583258 1.36726663 4.47958327 1.3661998 1 P 0 ;0,1,2=92,3=90.000000
L 4.47958327 1.3661998 4.4837498 1.36593317 1 P 0 ;0,1,2=92,3=90.000000
L 4.4837498 1.36593317 4.48916614 1.36646634 1 P 0 ;0,1,2=92,3=90.000000
L 4.48916614 1.36646634 4.49208366 1.36726663 1 P 0 ;0,1,2=92,3=90.000000
L 4.49208366 1.36726663 4.4949997 1.3685997 1 P 0 ;0,1,2=92,3=90.000000
L 4.4949997 1.3685997 4.49708337 1.37046654 1 P 0 ;0,1,2=92,3=90.000000
L 4.49708337 1.37046654 4.4975 1.37233327 1 P 0 ;0,1,2=92,3=90.000000
L 4.4975 1.37233327 4.49666683 1.3742 1 P 0 ;0,1,2=92,3=90.000000
L 4.49666683 1.3742 4.49458317 1.37553356 1 P 0 ;0,1,2=92,3=90.000000
L 4.4975 1.3929997 4.49666683 1.39086634 1 P 0 ;0,1,2=92,3=90.000000
L 4.49666683 1.39086634 4.49458317 1.38926663 1 P 0 ;0,1,2=92,3=90.000000
L 4.49458317 1.38926663 4.49208366 1.3881998 1 P 0 ;0,1,2=92,3=90.000000
L 4.49208366 1.3881998 4.48874951 1.3873999 1 P 0 ;0,1,2=92,3=90.000000
L 4.48874951 1.3873999 4.48499961 1.38713327 1 P 0 ;0,1,2=92,3=90.000000
L 4.48499961 1.38713327 4.48124961 1.3873999 1 P 0 ;0,1,2=92,3=90.000000
L 4.48124961 1.3873999 4.47791624 1.3881998 1 P 0 ;0,1,2=92,3=90.000000
L 4.47791624 1.3881998 4.47541604 1.38926663 1 P 0 ;0,1,2=92,3=90.000000
L 4.47541604 1.38926663 4.47333307 1.39086634 1 P 0 ;0,1,2=92,3=90.000000
L 4.47333307 1.39086634 4.4725 1.3929997 1 P 0 ;0,1,2=92,3=90.000000
L 4.4725 1.3929997 4.47333307 1.39513307 1 P 0 ;0,1,2=92,3=90.000000
L 4.47333307 1.39513307 4.47541604 1.39673327 1 P 0 ;0,1,2=92,3=90.000000
L 4.47541604 1.39673327 4.47791624 1.3978001 1 P 0 ;0,1,2=92,3=90.000000
L 4.47791624 1.3978001 4.48124961 1.3986 1 P 0 ;0,1,2=92,3=90.000000
L 4.48124961 1.3986 4.48499961 1.39886663 1 P 0 ;0,1,2=92,3=90.000000
L 4.48499961 1.39886663 4.48874951 1.3986 1 P 0 ;0,1,2=92,3=90.000000
L 4.48874951 1.3986 4.49208366 1.3978001 1 P 0 ;0,1,2=92,3=90.000000
L 4.49208366 1.3978001 4.49458317 1.39673327 1 P 0 ;0,1,2=92,3=90.000000
L 4.49458317 1.39673327 4.49666683 1.39513307 1 P 0 ;0,1,2=92,3=90.000000
L 4.49666683 1.39513307 4.4975 1.3929997 1 P 0 ;0,1,2=92,3=90.000000
L 4.61878002 1.50996998 4.61878002 1.58635 1 P 0 
L 4.61878002 1.58635 4.58178002 1.58635 1 P 0 
L 4.58178002 1.58635 4.58178002 1.50996998 1 P 0 
L 4.58178002 1.50996998 4.61878002 1.50996998 1 P 0 
L 4.57541634 1.53886663 4.57666683 1.53726644 1 P 0 ;0,1,2=93,3=90.000000
L 4.57666683 1.53726644 4.5775 1.5354002 1 P 0 ;0,1,2=93,3=90.000000
L 4.5775 1.5354002 4.5775 1.53326683 1 P 0 ;0,1,2=93,3=90.000000
L 4.5775 1.53326683 4.57624941 1.53086634 1 P 0 ;0,1,2=93,3=90.000000
L 4.57624941 1.53086634 4.57416654 1.5290001 1 P 0 ;0,1,2=93,3=90.000000
L 4.57416654 1.5290001 4.57166634 1.52766654 1 P 0 ;0,1,2=93,3=90.000000
L 4.57166634 1.52766654 4.5674998 1.52659961 1 P 0 ;0,1,2=93,3=90.000000
L 4.5674998 1.52659961 4.5637498 1.52633297 1 P 0 ;0,1,2=93,3=90.000000
L 4.5637498 1.52633297 4.5599999 1.52686673 1 P 0 ;0,1,2=93,3=90.000000
L 4.5599999 1.52686673 4.55749961 1.52766654 1 P 0 ;0,1,2=93,3=90.000000
L 4.55749961 1.52766654 4.55499941 1.52926663 1 P 0 ;0,1,2=93,3=90.000000
L 4.55499941 1.52926663 4.55333307 1.53113346 1 P 0 ;0,1,2=93,3=90.000000
L 4.55333307 1.53113346 4.5525 1.5329997 1 P 0 ;0,1,2=93,3=90.000000
L 4.5525 1.5329997 4.5525 1.53486644 1 P 0 ;0,1,2=93,3=90.000000
L 4.5525 1.53486644 4.55333307 1.53673327 1 P 0 ;0,1,2=93,3=90.000000
L 4.55333307 1.53673327 4.55458287 1.53833337 1 P 0 ;0,1,2=93,3=90.000000
L 4.55458287 1.53833337 4.55624911 1.53966693 1 P 0 ;0,1,2=93,3=90.000000
L 4.55541604 1.55046634 4.55333307 1.55233317 1 P 0 ;0,1,2=93,3=90.000000
L 4.55333307 1.55233317 4.5525 1.55446654 1 P 0 ;0,1,2=93,3=90.000000
L 4.5525 1.55446654 4.55333307 1.5565999 1 P 0 ;0,1,2=93,3=90.000000
L 4.55333307 1.5565999 4.55583258 1.55846663 1 P 0 ;0,1,2=93,3=90.000000
L 4.55583258 1.55846663 4.55958327 1.5598001 1 P 0 ;0,1,2=93,3=90.000000
L 4.55958327 1.5598001 4.56333327 1.56033337 1 P 0 ;0,1,2=93,3=90.000000
L 4.56333327 1.56033337 4.56791634 1.56033337 1 P 0 ;0,1,2=93,3=90.000000
L 4.56791634 1.56033337 4.57166634 1.5598001 1 P 0 ;0,1,2=93,3=90.000000
L 4.57166634 1.5598001 4.5749997 1.55846663 1 P 0 ;0,1,2=93,3=90.000000
L 4.5749997 1.55846663 4.57666683 1.55686644 1 P 0 ;0,1,2=93,3=90.000000
L 4.57666683 1.55686644 4.5775 1.5549997 1 P 0 ;0,1,2=93,3=90.000000
L 4.5775 1.5549997 4.57666683 1.55286634 1 P 0 ;0,1,2=93,3=90.000000
L 4.57666683 1.55286634 4.5749997 1.55126663 1 P 0 ;0,1,2=93,3=90.000000
L 4.5749997 1.55126663 4.5725003 1.5501998 1 P 0 ;0,1,2=93,3=90.000000
L 4.5725003 1.5501998 4.56916614 1.54966654 1 P 0 ;0,1,2=93,3=90.000000
L 4.56916614 1.54966654 4.5662501 1.5501998 1 P 0 ;0,1,2=93,3=90.000000
L 4.5662501 1.5501998 4.56333327 1.55153327 1 P 0 ;0,1,2=93,3=90.000000
L 4.56333327 1.55153327 4.56166614 1.55313346 1 P 0 ;0,1,2=93,3=90.000000
L 4.56166614 1.55313346 4.56124961 1.5549997 1 P 0 ;0,1,2=93,3=90.000000
L 4.56124961 1.5549997 4.56208278 1.55713307 1 P 0 ;0,1,2=93,3=90.000000
L 4.56208278 1.55713307 4.56416644 1.55873327 1 P 0 ;0,1,2=93,3=90.000000
L 4.56416644 1.55873327 4.56791634 1.56033337 1 P 0 ;0,1,2=93,3=90.000000
L 4.55749961 1.57113327 4.55458287 1.57273297 1 P 0 ;0,1,2=93,3=90.000000
L 4.55458287 1.57273297 4.55291654 1.57486634 1 P 0 ;0,1,2=93,3=90.000000
L 4.55291654 1.57486634 4.5525 1.57726683 1 P 0 ;0,1,2=93,3=90.000000
L 4.5525 1.57726683 4.55291654 1.5794002 1 P 0 ;0,1,2=93,3=90.000000
L 4.55291654 1.5794002 4.55499941 1.58153356 1 P 0 ;0,1,2=93,3=90.000000
L 4.55499941 1.58153356 4.55749961 1.58286663 1 P 0 ;0,1,2=93,3=90.000000
L 4.55749961 1.58286663 4.5599999 1.58313317 1 P 0 ;0,1,2=93,3=90.000000
L 4.5599999 1.58313317 4.56291594 1.5826 1 P 0 ;0,1,2=93,3=90.000000
L 4.56291594 1.5826 4.56499961 1.58073327 1 P 0 ;0,1,2=93,3=90.000000
L 4.56499961 1.58073327 4.56583346 1.57886644 1 P 0 ;0,1,2=93,3=90.000000
L 4.56583346 1.57886644 4.56583346 1.57646654 1 P 0 ;0,1,2=93,3=90.000000
L 4.56583346 1.57886644 4.56708327 1.58046663 1 P 0 ;0,1,2=93,3=90.000000
L 4.56708327 1.58046663 4.56916614 1.5818001 1 P 0 ;0,1,2=93,3=90.000000
L 4.56916614 1.5818001 4.57166634 1.58233337 1 P 0 ;0,1,2=93,3=90.000000
L 4.57166634 1.58233337 4.57416654 1.5818001 1 P 0 ;0,1,2=93,3=90.000000
L 4.57416654 1.5818001 4.57624941 1.58046663 1 P 0 ;0,1,2=93,3=90.000000
L 4.57624941 1.58046663 4.5775 1.57806663 1 P 0 ;0,1,2=93,3=90.000000
L 4.5775 1.57806663 4.57708337 1.57566663 1 P 0 ;0,1,2=93,3=90.000000
L 4.57708337 1.57566663 4.57541634 1.57326663 1 P 0 ;0,1,2=93,3=90.000000
L 4.69751998 2.1769 4.66051998 2.1769 1 P 0 
L 4.69751998 2.10051998 4.69751998 2.1769 1 P 0 
L 4.66051998 2.1769 4.66051998 2.10051998 1 P 0 
L 4.66051998 2.10051998 4.69751998 2.10051998 1 P 0 
L 4.69291624 2.23693327 4.69446683 2.23463307 1 P 0 ;0,1,2=94,3=90.000000
L 4.69446683 2.23463307 4.6955 2.2319503 1 P 0 ;0,1,2=94,3=90.000000
L 4.6955 2.2319503 4.6955 2.22888356 1 P 0 ;0,1,2=94,3=90.000000
L 4.6955 2.22888356 4.69394931 2.22543287 1 P 0 ;0,1,2=94,3=90.000000
L 4.69394931 2.22543287 4.69136654 2.2227501 1 P 0 ;0,1,2=94,3=90.000000
L 4.69136654 2.2227501 4.68826624 2.22083317 1 P 0 ;0,1,2=94,3=90.000000
L 4.68826624 2.22083317 4.6830998 2.21929951 1 P 0 ;0,1,2=94,3=90.000000
L 4.6830998 2.21929951 4.6784498 2.21891624 1 P 0 ;0,1,2=94,3=90.000000
L 4.6784498 2.21891624 4.6737999 2.21968337 1 P 0 ;0,1,2=94,3=90.000000
L 4.6737999 2.21968337 4.67069961 2.22083317 1 P 0 ;0,1,2=94,3=90.000000
L 4.67069961 2.22083317 4.66759931 2.22313337 1 P 0 ;0,1,2=94,3=90.000000
L 4.66759931 2.22313337 4.66553307 2.22581683 1 P 0 ;0,1,2=94,3=90.000000
L 4.66553307 2.22581683 4.6645 2.22849961 1 P 0 ;0,1,2=94,3=90.000000
L 4.6645 2.22849961 4.6645 2.23118307 1 P 0 ;0,1,2=94,3=90.000000
L 4.6645 2.23118307 4.66553307 2.23386654 1 P 0 ;0,1,2=94,3=90.000000
L 4.66553307 2.23386654 4.66708278 2.23616673 1 P 0 ;0,1,2=94,3=90.000000
L 4.66708278 2.23616673 4.66914892 2.23808366 1 P 0 ;0,1,2=94,3=90.000000
L 4.6645 2.25949961 4.6955 2.25949961 1 P 0 ;0,1,2=94,3=90.000000
L 4.6955 2.25949961 4.6893003 2.2548999 1 P 0 ;0,1,2=94,3=90.000000
L 4.6645 2.2548999 4.6645 2.26409931 1 P 0 ;0,1,2=94,3=90.000000
L 4.66914892 2.28206663 4.66656614 2.28436614 1 P 0 ;0,1,2=94,3=90.000000
L 4.66656614 2.28436614 4.66501654 2.28704961 1 P 0 ;0,1,2=94,3=90.000000
L 4.66501654 2.28704961 4.6645 2.29049961 1 P 0 ;0,1,2=94,3=90.000000
L 4.6645 2.29049961 4.66553307 2.2939503 1 P 0 ;0,1,2=94,3=90.000000
L 4.66553307 2.2939503 4.66759931 2.29663307 1 P 0 ;0,1,2=94,3=90.000000
L 4.66759931 2.29663307 4.67121614 2.29855 1 P 0 ;0,1,2=94,3=90.000000
L 4.67121614 2.29855 4.67534951 2.29893327 1 P 0 ;0,1,2=94,3=90.000000
L 4.67534951 2.29893327 4.67948287 2.29816673 1 P 0 ;0,1,2=94,3=90.000000
L 4.67948287 2.29816673 4.68206663 2.2962498 1 P 0 ;0,1,2=94,3=90.000000
L 4.68206663 2.2962498 4.68413287 2.29356634 1 P 0 ;0,1,2=94,3=90.000000
L 4.68413287 2.29356634 4.68464941 2.29088356 1 P 0 ;0,1,2=94,3=90.000000
L 4.68464941 2.29088356 4.68413287 2.2882001 1 P 0 ;0,1,2=94,3=90.000000
L 4.68413287 2.2882001 4.68206663 2.2847501 1 P 0 ;0,1,2=94,3=90.000000
L 4.68206663 2.2847501 4.6955 2.2858999 1 P 0 ;0,1,2=94,3=90.000000
L 4.6955 2.2858999 4.6955 2.2962498 1 P 0 ;0,1,2=94,3=90.000000
L 4.6645 2.3261 4.6955 2.3261 1 P 0 ;0,1,2=94,3=90.000000
L 4.6955 2.3261 4.67328327 2.31191624 1 P 0 ;0,1,2=94,3=90.000000
L 4.67328327 2.31191624 4.67328327 2.33108366 1 P 0 ;0,1,2=94,3=90.000000
L 3.593 1.367 3.697 1.367 1 P 0 
L 3.593 1.423 3.593 1.367 1 P 0 
L 3.697 1.423 3.593 1.423 1 P 0 
L 3.697 1.367 3.697 1.423 1 P 0 
L 3.68866683 1.3555 3.68866683 1.3245 1 P 0 ;0,1,2=95,3=0.000000
L 3.68866683 1.3245 3.67333327 1.3245 1 P 0 ;0,1,2=95,3=0.000000
L 3.65843337 1.33069961 3.65613386 1.32708278 1 P 0 ;0,1,2=95,3=0.000000
L 3.65613386 1.32708278 3.65306713 1.32501654 1 P 0 ;0,1,2=95,3=0.000000
L 3.65306713 1.32501654 3.64961644 1.3245 1 P 0 ;0,1,2=95,3=0.000000
L 3.64961644 1.3245 3.6465497 1.32501654 1 P 0 ;0,1,2=95,3=0.000000
L 3.6465497 1.32501654 3.64348297 1.32759931 1 P 0 ;0,1,2=95,3=0.000000
L 3.64348297 1.32759931 3.64156673 1.33069961 1 P 0 ;0,1,2=95,3=0.000000
L 3.64156673 1.33069961 3.64118346 1.3337999 1 P 0 ;0,1,2=95,3=0.000000
L 3.64118346 1.3337999 3.64195 1.33741575 1 P 0 ;0,1,2=95,3=0.000000
L 3.64195 1.33741575 3.64463346 1.33999951 1 P 0 ;0,1,2=95,3=0.000000
L 3.64463346 1.33999951 3.64731693 1.34103356 1 P 0 ;0,1,2=95,3=0.000000
L 3.64731693 1.34103356 3.65076693 1.34103356 1 P 0 ;0,1,2=95,3=0.000000
L 3.64731693 1.34103356 3.64501673 1.34258317 1 P 0 ;0,1,2=95,3=0.000000
L 3.64501673 1.34258317 3.6430998 1.34516594 1 P 0 ;0,1,2=95,3=0.000000
L 3.6430998 1.34516594 3.64233327 1.34826624 1 P 0 ;0,1,2=95,3=0.000000
L 3.64233327 1.34826624 3.6430998 1.35136654 1 P 0 ;0,1,2=95,3=0.000000
L 3.6430998 1.35136654 3.64501673 1.35394931 1 P 0 ;0,1,2=95,3=0.000000
L 3.64501673 1.35394931 3.64846673 1.3555 1 P 0 ;0,1,2=95,3=0.000000
L 3.64846673 1.3555 3.65191663 1.35498337 1 P 0 ;0,1,2=95,3=0.000000
L 3.65191663 1.35498337 3.65536663 1.35291624 1 P 0 ;0,1,2=95,3=0.000000
L 3.62743337 1.32914892 3.62513386 1.32656614 1 P 0 ;0,1,2=95,3=0.000000
L 3.62513386 1.32656614 3.62245039 1.32501654 1 P 0 ;0,1,2=95,3=0.000000
L 3.62245039 1.32501654 3.61900039 1.3245 1 P 0 ;0,1,2=95,3=0.000000
L 3.61900039 1.3245 3.6155497 1.32553307 1 P 0 ;0,1,2=95,3=0.000000
L 3.6155497 1.32553307 3.61286693 1.32759931 1 P 0 ;0,1,2=95,3=0.000000
L 3.61286693 1.32759931 3.61095 1.33121614 1 P 0 ;0,1,2=95,3=0.000000
L 3.61095 1.33121614 3.61056673 1.33534951 1 P 0 ;0,1,2=95,3=0.000000
L 3.61056673 1.33534951 3.61133327 1.33948287 1 P 0 ;0,1,2=95,3=0.000000
L 3.61133327 1.33948287 3.6132502 1.34206663 1 P 0 ;0,1,2=95,3=0.000000
L 3.6132502 1.34206663 3.61593366 1.34413287 1 P 0 ;0,1,2=95,3=0.000000
L 3.61593366 1.34413287 3.61861644 1.34464941 1 P 0 ;0,1,2=95,3=0.000000
L 3.61861644 1.34464941 3.6212999 1.34413287 1 P 0 ;0,1,2=95,3=0.000000
L 3.6212999 1.34413287 3.6247499 1.34206663 1 P 0 ;0,1,2=95,3=0.000000
L 3.6247499 1.34206663 3.6236001 1.3555 1 P 0 ;0,1,2=95,3=0.000000
L 3.6236001 1.3555 3.6132502 1.3555 1 P 0 ;0,1,2=95,3=0.000000
L 2.232 0.598 2.288 0.598 1 P 0 
L 2.232 0.702 2.232 0.598 1 P 0 
L 2.288 0.702 2.232 0.702 1 P 0 
L 2.288 0.598 2.288 0.702 1 P 0 
L 2.2805 0.77633317 2.2495 0.77633317 1 P 0 ;0,1,2=96,3=90.000000
L 2.2495 0.77633317 2.2495 0.79166673 1 P 0 ;0,1,2=96,3=90.000000
L 2.27533346 0.80771644 2.27843278 0.81001663 1 P 0 ;0,1,2=96,3=90.000000
L 2.27843278 0.81001663 2.27998337 0.8127001 1 P 0 ;0,1,2=96,3=90.000000
L 2.27998337 0.8127001 2.2805 0.81576683 1 P 0 ;0,1,2=96,3=90.000000
L 2.2805 0.81576683 2.27946683 0.8196 1 P 0 ;0,1,2=96,3=90.000000
L 2.27946683 0.8196 2.27688307 0.82228346 1 P 0 ;0,1,2=96,3=90.000000
L 2.27688307 0.82228346 2.27378376 0.82305 1 P 0 ;0,1,2=96,3=90.000000
L 2.27378376 0.82305 2.27068258 0.82266673 1 P 0 ;0,1,2=96,3=90.000000
L 2.27068258 0.82266673 2.2680998 0.82113307 1 P 0 ;0,1,2=96,3=90.000000
L 2.2680998 0.82113307 2.26293327 0.81346663 1 P 0 ;0,1,2=96,3=90.000000
L 2.26293327 0.81346663 2.25931644 0.81001663 1 P 0 ;0,1,2=96,3=90.000000
L 2.25931644 0.81001663 2.25414892 0.80771644 1 P 0 ;0,1,2=96,3=90.000000
L 2.25414892 0.80771644 2.2495 0.8069499 1 P 0 ;0,1,2=96,3=90.000000
L 2.2495 0.8069499 2.2495 0.82305 1 P 0 ;0,1,2=96,3=90.000000
L 2.2495 0.84599961 2.2805 0.84599961 1 P 0 ;0,1,2=96,3=90.000000
L 2.2805 0.84599961 2.2743003 0.8413999 1 P 0 ;0,1,2=96,3=90.000000
L 2.2495 0.8413999 2.2495 0.85059931 1 P 0 ;0,1,2=96,3=90.000000
L 3.213 2.932 3.157 2.932 1 P 0 
L 3.213 2.828 3.213 2.932 1 P 0 
L 3.157 2.932 3.157 2.828 1 P 0 
L 3.157 2.828 3.213 2.828 1 P 0 
L 3.1905 2.97683317 3.1595 2.97683317 1 P 0 ;0,1,2=97,3=90.000000
L 3.1595 2.97683317 3.1595 2.99216673 1 P 0 ;0,1,2=97,3=90.000000
L 3.16569961 3.00706663 3.16208278 3.00936614 1 P 0 ;0,1,2=97,3=90.000000
L 3.16208278 3.00936614 3.16001654 3.01243287 1 P 0 ;0,1,2=97,3=90.000000
L 3.16001654 3.01243287 3.1595 3.01588356 1 P 0 ;0,1,2=97,3=90.000000
L 3.1595 3.01588356 3.16001654 3.0189503 1 P 0 ;0,1,2=97,3=90.000000
L 3.16001654 3.0189503 3.16259931 3.02201703 1 P 0 ;0,1,2=97,3=90.000000
L 3.16259931 3.02201703 3.16569961 3.02393327 1 P 0 ;0,1,2=97,3=90.000000
L 3.16569961 3.02393327 3.1687999 3.02431654 1 P 0 ;0,1,2=97,3=90.000000
L 3.1687999 3.02431654 3.17241575 3.02355 1 P 0 ;0,1,2=97,3=90.000000
L 3.17241575 3.02355 3.17499951 3.02086654 1 P 0 ;0,1,2=97,3=90.000000
L 3.17499951 3.02086654 3.17603356 3.01818307 1 P 0 ;0,1,2=97,3=90.000000
L 3.17603356 3.01818307 3.17603356 3.01473307 1 P 0 ;0,1,2=97,3=90.000000
L 3.17603356 3.01818307 3.17758317 3.02048327 1 P 0 ;0,1,2=97,3=90.000000
L 3.17758317 3.02048327 3.18016594 3.0224002 1 P 0 ;0,1,2=97,3=90.000000
L 3.18016594 3.0224002 3.18326624 3.02316673 1 P 0 ;0,1,2=97,3=90.000000
L 3.18326624 3.02316673 3.18636654 3.0224002 1 P 0 ;0,1,2=97,3=90.000000
L 3.18636654 3.0224002 3.18894931 3.02048327 1 P 0 ;0,1,2=97,3=90.000000
L 3.18894931 3.02048327 3.1905 3.01703327 1 P 0 ;0,1,2=97,3=90.000000
L 3.1905 3.01703327 3.18998337 3.01358337 1 P 0 ;0,1,2=97,3=90.000000
L 3.18998337 3.01358337 3.18791624 3.01013337 1 P 0 ;0,1,2=97,3=90.000000
L 4.12 2.263 4.12 2.387 1 P 0 
L 4.12 2.387 3.95 2.387 1 P 0 
L 3.95 2.387 3.95 2.263 1 P 0 
L 3.95 2.263 4.12 2.263 1 P 0 
L 4.06306673 2.42291624 4.06536693 2.42446683 1 P 0 ;0,1,2=98,3=0.000000
L 4.06536693 2.42446683 4.0680497 2.4255 1 P 0 ;0,1,2=98,3=0.000000
L 4.0680497 2.4255 4.07111644 2.4255 1 P 0 ;0,1,2=98,3=0.000000
L 4.07111644 2.4255 4.07456713 2.42394931 1 P 0 ;0,1,2=98,3=0.000000
L 4.07456713 2.42394931 4.0772499 2.42136654 1 P 0 ;0,1,2=98,3=0.000000
L 4.0772499 2.42136654 4.07916683 2.41826624 1 P 0 ;0,1,2=98,3=0.000000
L 4.07916683 2.41826624 4.08070049 2.4130998 1 P 0 ;0,1,2=98,3=0.000000
L 4.08070049 2.4130998 4.08108376 2.4084498 1 P 0 ;0,1,2=98,3=0.000000
L 4.08108376 2.4084498 4.08031663 2.4037999 1 P 0 ;0,1,2=98,3=0.000000
L 4.08031663 2.4037999 4.07916683 2.40069961 1 P 0 ;0,1,2=98,3=0.000000
L 4.07916683 2.40069961 4.07686663 2.39759931 1 P 0 ;0,1,2=98,3=0.000000
L 4.07686663 2.39759931 4.07418317 2.39553307 1 P 0 ;0,1,2=98,3=0.000000
L 4.07418317 2.39553307 4.07150039 2.3945 1 P 0 ;0,1,2=98,3=0.000000
L 4.07150039 2.3945 4.06881693 2.3945 1 P 0 ;0,1,2=98,3=0.000000
L 4.06881693 2.3945 4.06613346 2.39553307 1 P 0 ;0,1,2=98,3=0.000000
L 4.06613346 2.39553307 4.06383327 2.39708278 1 P 0 ;0,1,2=98,3=0.000000
L 4.06383327 2.39708278 4.06191634 2.39914892 1 P 0 ;0,1,2=98,3=0.000000
L 4.04050039 2.3945 4.04050039 2.4255 1 P 0 ;0,1,2=98,3=0.000000
L 4.04050039 2.4255 4.0451001 2.4193003 1 P 0 ;0,1,2=98,3=0.000000
L 4.0451001 2.3945 4.03590069 2.3945 1 P 0 ;0,1,2=98,3=0.000000
L 4.01026693 2.3945 4.00950039 2.40121614 1 P 0 ;0,1,2=98,3=0.000000
L 4.00950039 2.40121614 4.0083499 2.40689921 1 P 0 ;0,1,2=98,3=0.000000
L 4.0083499 2.40689921 4.00681693 2.41206663 1 P 0 ;0,1,2=98,3=0.000000
L 4.00681693 2.41206663 4.0049 2.4177497 1 P 0 ;0,1,2=98,3=0.000000
L 4.0049 2.4177497 4.00183327 2.4255 1 P 0 ;0,1,2=98,3=0.000000
L 4.00183327 2.4255 4.01716683 2.4255 1 P 0 ;0,1,2=98,3=0.000000
L 3.98578356 2.42033346 3.98348337 2.42343278 1 P 0 ;0,1,2=98,3=0.000000
L 3.98348337 2.42343278 3.9807999 2.42498337 1 P 0 ;0,1,2=98,3=0.000000
L 3.9807999 2.42498337 3.97773317 2.4255 1 P 0 ;0,1,2=98,3=0.000000
L 3.97773317 2.4255 3.9739 2.42446683 1 P 0 ;0,1,2=98,3=0.000000
L 3.9739 2.42446683 3.97121654 2.42188307 1 P 0 ;0,1,2=98,3=0.000000
L 3.97121654 2.42188307 3.97045 2.41878376 1 P 0 ;0,1,2=98,3=0.000000
L 3.97045 2.41878376 3.97083327 2.41568258 1 P 0 ;0,1,2=98,3=0.000000
L 3.97083327 2.41568258 3.97236693 2.4130998 1 P 0 ;0,1,2=98,3=0.000000
L 3.97236693 2.4130998 3.98003337 2.40793327 1 P 0 ;0,1,2=98,3=0.000000
L 3.98003337 2.40793327 3.98348337 2.40431644 1 P 0 ;0,1,2=98,3=0.000000
L 3.98348337 2.40431644 3.98578356 2.39914892 1 P 0 ;0,1,2=98,3=0.000000
L 3.98578356 2.39914892 3.9865501 2.3945 1 P 0 ;0,1,2=98,3=0.000000
L 3.9865501 2.3945 3.97045 2.3945 1 P 0 ;0,1,2=98,3=0.000000
L 1.057 3.16 1.057 3.07 1 P 0 
L 1.057 3.07 1.013 3.07 1 P 0 
L 1.013 3.07 1.013 3.16 1 P 0 
L 1.013 3.16 1.057 3.16 1 P 0 
L 1.00291624 3.09243327 1.00446683 3.09013307 1 P 0 ;0,1,2=99,3=90.000000
L 1.00446683 3.09013307 1.0055 3.0874503 1 P 0 ;0,1,2=99,3=90.000000
L 1.0055 3.0874503 1.0055 3.08438356 1 P 0 ;0,1,2=99,3=90.000000
L 1.0055 3.08438356 1.00394931 3.08093287 1 P 0 ;0,1,2=99,3=90.000000
L 1.00394931 3.08093287 1.00136654 3.0782501 1 P 0 ;0,1,2=99,3=90.000000
L 1.00136654 3.0782501 0.99826624 3.07633317 1 P 0 ;0,1,2=99,3=90.000000
L 0.99826624 3.07633317 0.9930998 3.07479951 1 P 0 ;0,1,2=99,3=90.000000
L 0.9930998 3.07479951 0.9884498 3.07441624 1 P 0 ;0,1,2=99,3=90.000000
L 0.9884498 3.07441624 0.9837999 3.07518337 1 P 0 ;0,1,2=99,3=90.000000
L 0.9837999 3.07518337 0.98069961 3.07633317 1 P 0 ;0,1,2=99,3=90.000000
L 0.98069961 3.07633317 0.97759931 3.07863337 1 P 0 ;0,1,2=99,3=90.000000
L 0.97759931 3.07863337 0.97553307 3.08131683 1 P 0 ;0,1,2=99,3=90.000000
L 0.97553307 3.08131683 0.9745 3.08399961 1 P 0 ;0,1,2=99,3=90.000000
L 0.9745 3.08399961 0.9745 3.08668307 1 P 0 ;0,1,2=99,3=90.000000
L 0.9745 3.08668307 0.97553307 3.08936654 1 P 0 ;0,1,2=99,3=90.000000
L 0.97553307 3.08936654 0.97708278 3.09166673 1 P 0 ;0,1,2=99,3=90.000000
L 0.97708278 3.09166673 0.97914892 3.09358366 1 P 0 ;0,1,2=99,3=90.000000
L 0.97811585 3.10848287 0.97553307 3.11116634 1 P 0 ;0,1,2=99,3=90.000000
L 0.97553307 3.11116634 0.9745 3.11423307 1 P 0 ;0,1,2=99,3=90.000000
L 0.9745 3.11423307 0.97553307 3.1172998 1 P 0 ;0,1,2=99,3=90.000000
L 0.97553307 3.1172998 0.97863238 3.11998327 1 P 0 ;0,1,2=99,3=90.000000
L 0.97863238 3.11998327 0.98328327 3.1219002 1 P 0 ;0,1,2=99,3=90.000000
L 0.98328327 3.1219002 0.98793327 3.12266673 1 P 0 ;0,1,2=99,3=90.000000
L 0.98793327 3.12266673 0.99361634 3.12266673 1 P 0 ;0,1,2=99,3=90.000000
L 0.99361634 3.12266673 0.99826624 3.1219002 1 P 0 ;0,1,2=99,3=90.000000
L 0.99826624 3.1219002 1.0023997 3.11998327 1 P 0 ;0,1,2=99,3=90.000000
L 1.0023997 3.11998327 1.00446683 3.11768307 1 P 0 ;0,1,2=99,3=90.000000
L 1.00446683 3.11768307 1.0055 3.11499961 1 P 0 ;0,1,2=99,3=90.000000
L 1.0055 3.11499961 1.00446683 3.11193287 1 P 0 ;0,1,2=99,3=90.000000
L 1.00446683 3.11193287 1.0023997 3.10963337 1 P 0 ;0,1,2=99,3=90.000000
L 1.0023997 3.10963337 0.9993003 3.1080997 1 P 0 ;0,1,2=99,3=90.000000
L 0.9993003 3.1080997 0.99516594 3.10733317 1 P 0 ;0,1,2=99,3=90.000000
L 0.99516594 3.10733317 0.9915501 3.1080997 1 P 0 ;0,1,2=99,3=90.000000
L 0.9915501 3.1080997 0.98793327 3.11001663 1 P 0 ;0,1,2=99,3=90.000000
L 0.98793327 3.11001663 0.98586604 3.11231683 1 P 0 ;0,1,2=99,3=90.000000
L 0.98586604 3.11231683 0.98534951 3.11499961 1 P 0 ;0,1,2=99,3=90.000000
L 0.98534951 3.11499961 0.98638268 3.11806634 1 P 0 ;0,1,2=99,3=90.000000
L 0.98638268 3.11806634 0.98896634 3.12036654 1 P 0 ;0,1,2=99,3=90.000000
L 0.98896634 3.12036654 0.99361634 3.12266673 1 P 0 ;0,1,2=99,3=90.000000
L 1.0055 3.14599961 1.00446683 3.14293287 1 P 0 ;0,1,2=99,3=90.000000
L 1.00446683 3.14293287 1.00188307 3.14063337 1 P 0 ;0,1,2=99,3=90.000000
L 1.00188307 3.14063337 0.99878376 3.1390997 1 P 0 ;0,1,2=99,3=90.000000
L 0.99878376 3.1390997 0.99464941 3.1379499 1 P 0 ;0,1,2=99,3=90.000000
L 0.99464941 3.1379499 0.98999951 3.13756663 1 P 0 ;0,1,2=99,3=90.000000
L 0.98999951 3.13756663 0.98534951 3.1379499 1 P 0 ;0,1,2=99,3=90.000000
L 0.98534951 3.1379499 0.98121614 3.1390997 1 P 0 ;0,1,2=99,3=90.000000
L 0.98121614 3.1390997 0.97811585 3.14063337 1 P 0 ;0,1,2=99,3=90.000000
L 0.97811585 3.14063337 0.97553307 3.14293287 1 P 0 ;0,1,2=99,3=90.000000
L 0.97553307 3.14293287 0.9745 3.14599961 1 P 0 ;0,1,2=99,3=90.000000
L 0.9745 3.14599961 0.97553307 3.14906634 1 P 0 ;0,1,2=99,3=90.000000
L 0.97553307 3.14906634 0.97811585 3.15136654 1 P 0 ;0,1,2=99,3=90.000000
L 0.97811585 3.15136654 0.98121614 3.1529002 1 P 0 ;0,1,2=99,3=90.000000
L 0.98121614 3.1529002 0.98534951 3.15405 1 P 0 ;0,1,2=99,3=90.000000
L 0.98534951 3.15405 0.98999951 3.15443327 1 P 0 ;0,1,2=99,3=90.000000
L 0.98999951 3.15443327 0.99464941 3.15405 1 P 0 ;0,1,2=99,3=90.000000
L 0.99464941 3.15405 0.99878376 3.1529002 1 P 0 ;0,1,2=99,3=90.000000
L 0.99878376 3.1529002 1.00188307 3.15136654 1 P 0 ;0,1,2=99,3=90.000000
L 1.00188307 3.15136654 1.00446683 3.14906634 1 P 0 ;0,1,2=99,3=90.000000
L 1.00446683 3.14906634 1.0055 3.14599961 1 P 0 ;0,1,2=99,3=90.000000
L 1.397 3.625 1.397 3.535 1 P 0 
L 1.353 3.625 1.397 3.625 1 P 0 
L 1.397 3.535 1.353 3.535 1 P 0 
L 1.353 3.535 1.353 3.625 1 P 0 
L 1.37791624 3.67743327 1.37946683 3.67513307 1 P 0 ;0,1,2=100,3=90.000000
L 1.37946683 3.67513307 1.3805 3.6724503 1 P 0 ;0,1,2=100,3=90.000000
L 1.3805 3.6724503 1.3805 3.66938356 1 P 0 ;0,1,2=100,3=90.000000
L 1.3805 3.66938356 1.37894931 3.66593287 1 P 0 ;0,1,2=100,3=90.000000
L 1.37894931 3.66593287 1.37636654 3.6632501 1 P 0 ;0,1,2=100,3=90.000000
L 1.37636654 3.6632501 1.37326624 3.66133317 1 P 0 ;0,1,2=100,3=90.000000
L 1.37326624 3.66133317 1.3680998 3.65979951 1 P 0 ;0,1,2=100,3=90.000000
L 1.3680998 3.65979951 1.3634498 3.65941624 1 P 0 ;0,1,2=100,3=90.000000
L 1.3634498 3.65941624 1.3587999 3.66018337 1 P 0 ;0,1,2=100,3=90.000000
L 1.3587999 3.66018337 1.35569961 3.66133317 1 P 0 ;0,1,2=100,3=90.000000
L 1.35569961 3.66133317 1.35259931 3.66363337 1 P 0 ;0,1,2=100,3=90.000000
L 1.35259931 3.66363337 1.35053307 3.66631683 1 P 0 ;0,1,2=100,3=90.000000
L 1.35053307 3.66631683 1.3495 3.66899961 1 P 0 ;0,1,2=100,3=90.000000
L 1.3495 3.66899961 1.3495 3.67168307 1 P 0 ;0,1,2=100,3=90.000000
L 1.3495 3.67168307 1.35053307 3.67436654 1 P 0 ;0,1,2=100,3=90.000000
L 1.35053307 3.67436654 1.35208278 3.67666673 1 P 0 ;0,1,2=100,3=90.000000
L 1.35208278 3.67666673 1.35414892 3.67858366 1 P 0 ;0,1,2=100,3=90.000000
L 1.35311585 3.69348287 1.35053307 3.69616634 1 P 0 ;0,1,2=100,3=90.000000
L 1.35053307 3.69616634 1.3495 3.69923307 1 P 0 ;0,1,2=100,3=90.000000
L 1.3495 3.69923307 1.35053307 3.7022998 1 P 0 ;0,1,2=100,3=90.000000
L 1.35053307 3.7022998 1.35363238 3.70498327 1 P 0 ;0,1,2=100,3=90.000000
L 1.35363238 3.70498327 1.35828327 3.7069002 1 P 0 ;0,1,2=100,3=90.000000
L 1.35828327 3.7069002 1.36293327 3.70766673 1 P 0 ;0,1,2=100,3=90.000000
L 1.36293327 3.70766673 1.36861634 3.70766673 1 P 0 ;0,1,2=100,3=90.000000
L 1.36861634 3.70766673 1.37326624 3.7069002 1 P 0 ;0,1,2=100,3=90.000000
L 1.37326624 3.7069002 1.3773997 3.70498327 1 P 0 ;0,1,2=100,3=90.000000
L 1.3773997 3.70498327 1.37946683 3.70268307 1 P 0 ;0,1,2=100,3=90.000000
L 1.37946683 3.70268307 1.3805 3.69999961 1 P 0 ;0,1,2=100,3=90.000000
L 1.3805 3.69999961 1.37946683 3.69693287 1 P 0 ;0,1,2=100,3=90.000000
L 1.37946683 3.69693287 1.3773997 3.69463337 1 P 0 ;0,1,2=100,3=90.000000
L 1.3773997 3.69463337 1.3743003 3.6930997 1 P 0 ;0,1,2=100,3=90.000000
L 1.3743003 3.6930997 1.37016594 3.69233317 1 P 0 ;0,1,2=100,3=90.000000
L 1.37016594 3.69233317 1.3665501 3.6930997 1 P 0 ;0,1,2=100,3=90.000000
L 1.3665501 3.6930997 1.36293327 3.69501663 1 P 0 ;0,1,2=100,3=90.000000
L 1.36293327 3.69501663 1.36086604 3.69731683 1 P 0 ;0,1,2=100,3=90.000000
L 1.36086604 3.69731683 1.36034951 3.69999961 1 P 0 ;0,1,2=100,3=90.000000
L 1.36034951 3.69999961 1.36138268 3.70306634 1 P 0 ;0,1,2=100,3=90.000000
L 1.36138268 3.70306634 1.36396634 3.70536654 1 P 0 ;0,1,2=100,3=90.000000
L 1.36396634 3.70536654 1.36861634 3.70766673 1 P 0 ;0,1,2=100,3=90.000000
L 1.3495 3.73099961 1.3805 3.73099961 1 P 0 ;0,1,2=100,3=90.000000
L 1.3805 3.73099961 1.3743003 3.7263999 1 P 0 ;0,1,2=100,3=90.000000
L 1.3495 3.7263999 1.3495 3.73559931 1 P 0 ;0,1,2=100,3=90.000000
L 1.063 3.63 1.107 3.63 1 P 0 
L 1.063 3.54 1.063 3.63 1 P 0 
L 1.107 3.63 1.107 3.54 1 P 0 
L 1.107 3.54 1.063 3.54 1 P 0 
L 1.10791624 3.67243327 1.10946683 3.67013307 1 P 0 ;0,1,2=101,3=90.000000
L 1.10946683 3.67013307 1.1105 3.6674503 1 P 0 ;0,1,2=101,3=90.000000
L 1.1105 3.6674503 1.1105 3.66438356 1 P 0 ;0,1,2=101,3=90.000000
L 1.1105 3.66438356 1.10894931 3.66093287 1 P 0 ;0,1,2=101,3=90.000000
L 1.10894931 3.66093287 1.10636654 3.6582501 1 P 0 ;0,1,2=101,3=90.000000
L 1.10636654 3.6582501 1.10326624 3.65633317 1 P 0 ;0,1,2=101,3=90.000000
L 1.10326624 3.65633317 1.0980998 3.65479951 1 P 0 ;0,1,2=101,3=90.000000
L 1.0980998 3.65479951 1.0934498 3.65441624 1 P 0 ;0,1,2=101,3=90.000000
L 1.0934498 3.65441624 1.0887999 3.65518337 1 P 0 ;0,1,2=101,3=90.000000
L 1.0887999 3.65518337 1.08569961 3.65633317 1 P 0 ;0,1,2=101,3=90.000000
L 1.08569961 3.65633317 1.08259931 3.65863337 1 P 0 ;0,1,2=101,3=90.000000
L 1.08259931 3.65863337 1.08053307 3.66131683 1 P 0 ;0,1,2=101,3=90.000000
L 1.08053307 3.66131683 1.0795 3.66399961 1 P 0 ;0,1,2=101,3=90.000000
L 1.0795 3.66399961 1.0795 3.66668307 1 P 0 ;0,1,2=101,3=90.000000
L 1.0795 3.66668307 1.08053307 3.66936654 1 P 0 ;0,1,2=101,3=90.000000
L 1.08053307 3.66936654 1.08208278 3.67166673 1 P 0 ;0,1,2=101,3=90.000000
L 1.08208278 3.67166673 1.08414892 3.67358366 1 P 0 ;0,1,2=101,3=90.000000
L 1.08311585 3.68848287 1.08053307 3.69116634 1 P 0 ;0,1,2=101,3=90.000000
L 1.08053307 3.69116634 1.0795 3.69423307 1 P 0 ;0,1,2=101,3=90.000000
L 1.0795 3.69423307 1.08053307 3.6972998 1 P 0 ;0,1,2=101,3=90.000000
L 1.08053307 3.6972998 1.08363238 3.69998327 1 P 0 ;0,1,2=101,3=90.000000
L 1.08363238 3.69998327 1.08828327 3.7019002 1 P 0 ;0,1,2=101,3=90.000000
L 1.08828327 3.7019002 1.09293327 3.70266673 1 P 0 ;0,1,2=101,3=90.000000
L 1.09293327 3.70266673 1.09861634 3.70266673 1 P 0 ;0,1,2=101,3=90.000000
L 1.09861634 3.70266673 1.10326624 3.7019002 1 P 0 ;0,1,2=101,3=90.000000
L 1.10326624 3.7019002 1.1073997 3.69998327 1 P 0 ;0,1,2=101,3=90.000000
L 1.1073997 3.69998327 1.10946683 3.69768307 1 P 0 ;0,1,2=101,3=90.000000
L 1.10946683 3.69768307 1.1105 3.69499961 1 P 0 ;0,1,2=101,3=90.000000
L 1.1105 3.69499961 1.10946683 3.69193287 1 P 0 ;0,1,2=101,3=90.000000
L 1.10946683 3.69193287 1.1073997 3.68963337 1 P 0 ;0,1,2=101,3=90.000000
L 1.1073997 3.68963337 1.1043003 3.6880997 1 P 0 ;0,1,2=101,3=90.000000
L 1.1043003 3.6880997 1.10016594 3.68733317 1 P 0 ;0,1,2=101,3=90.000000
L 1.10016594 3.68733317 1.0965501 3.6880997 1 P 0 ;0,1,2=101,3=90.000000
L 1.0965501 3.6880997 1.09293327 3.69001663 1 P 0 ;0,1,2=101,3=90.000000
L 1.09293327 3.69001663 1.09086604 3.69231683 1 P 0 ;0,1,2=101,3=90.000000
L 1.09086604 3.69231683 1.09034951 3.69499961 1 P 0 ;0,1,2=101,3=90.000000
L 1.09034951 3.69499961 1.09138268 3.69806634 1 P 0 ;0,1,2=101,3=90.000000
L 1.09138268 3.69806634 1.09396634 3.70036654 1 P 0 ;0,1,2=101,3=90.000000
L 1.09396634 3.70036654 1.09861634 3.70266673 1 P 0 ;0,1,2=101,3=90.000000
L 1.0795 3.72599961 1.08001654 3.72868307 1 P 0 ;0,1,2=101,3=90.000000
L 1.08001654 3.72868307 1.08156614 3.7317498 1 P 0 ;0,1,2=101,3=90.000000
L 1.08156614 3.7317498 1.08414892 3.73366673 1 P 0 ;0,1,2=101,3=90.000000
L 1.08414892 3.73366673 1.08776673 3.73443327 1 P 0 ;0,1,2=101,3=90.000000
L 1.08776673 3.73443327 1.09138268 3.73366673 1 P 0 ;0,1,2=101,3=90.000000
L 1.09138268 3.73366673 1.09448287 3.73136654 1 P 0 ;0,1,2=101,3=90.000000
L 1.09448287 3.73136654 1.09603356 3.72791654 1 P 0 ;0,1,2=101,3=90.000000
L 1.09603356 3.72791654 1.09603356 3.72408337 1 P 0 ;0,1,2=101,3=90.000000
L 1.09603356 3.72408337 1.09706663 3.72178317 1 P 0 ;0,1,2=101,3=90.000000
L 1.09706663 3.72178317 1.09964941 3.71986614 1 P 0 ;0,1,2=101,3=90.000000
L 1.09964941 3.71986614 1.10326624 3.7190997 1 P 0 ;0,1,2=101,3=90.000000
L 1.10326624 3.7190997 1.10688307 3.7202501 1 P 0 ;0,1,2=101,3=90.000000
L 1.10688307 3.7202501 1.10946683 3.72293287 1 P 0 ;0,1,2=101,3=90.000000
L 1.10946683 3.72293287 1.1105 3.72599961 1 P 0 ;0,1,2=101,3=90.000000
L 1.1105 3.72599961 1.10946683 3.72906634 1 P 0 ;0,1,2=101,3=90.000000
L 1.10946683 3.72906634 1.10688307 3.7317498 1 P 0 ;0,1,2=101,3=90.000000
L 1.10688307 3.7317498 1.10326624 3.7329002 1 P 0 ;0,1,2=101,3=90.000000
L 1.10326624 3.7329002 1.09964941 3.73213307 1 P 0 ;0,1,2=101,3=90.000000
L 1.09964941 3.73213307 1.09706663 3.73021673 1 P 0 ;0,1,2=101,3=90.000000
L 1.09706663 3.73021673 1.09603356 3.72791654 1 P 0 ;0,1,2=101,3=90.000000
L 1.09603356 3.72791654 1.09603356 3.72408337 1 P 0 ;0,1,2=101,3=90.000000
L 1.09603356 3.72408337 1.09448287 3.72063337 1 P 0 ;0,1,2=101,3=90.000000
L 1.09448287 3.72063337 1.09138268 3.71833317 1 P 0 ;0,1,2=101,3=90.000000
L 1.09138268 3.71833317 1.08776673 3.71756663 1 P 0 ;0,1,2=101,3=90.000000
L 1.08776673 3.71756663 1.08414892 3.71833317 1 P 0 ;0,1,2=101,3=90.000000
L 1.08414892 3.71833317 1.08156614 3.7202501 1 P 0 ;0,1,2=101,3=90.000000
L 1.08156614 3.7202501 1.08001654 3.72331683 1 P 0 ;0,1,2=101,3=90.000000
L 1.08001654 3.72331683 1.0795 3.72599961 1 P 0 ;0,1,2=101,3=90.000000
L 1.242 3.63 1.242 3.54 1 P 0 
L 1.198 3.63 1.242 3.63 1 P 0 
L 1.198 3.54 1.198 3.63 1 P 0 
L 1.242 3.54 1.198 3.54 1 P 0 
L 1.24291624 3.67243327 1.24446683 3.67013307 1 P 0 ;0,1,2=102,3=90.000000
L 1.24446683 3.67013307 1.2455 3.6674503 1 P 0 ;0,1,2=102,3=90.000000
L 1.2455 3.6674503 1.2455 3.66438356 1 P 0 ;0,1,2=102,3=90.000000
L 1.2455 3.66438356 1.24394931 3.66093287 1 P 0 ;0,1,2=102,3=90.000000
L 1.24394931 3.66093287 1.24136654 3.6582501 1 P 0 ;0,1,2=102,3=90.000000
L 1.24136654 3.6582501 1.23826624 3.65633317 1 P 0 ;0,1,2=102,3=90.000000
L 1.23826624 3.65633317 1.2330998 3.65479951 1 P 0 ;0,1,2=102,3=90.000000
L 1.2330998 3.65479951 1.2284498 3.65441624 1 P 0 ;0,1,2=102,3=90.000000
L 1.2284498 3.65441624 1.2237999 3.65518337 1 P 0 ;0,1,2=102,3=90.000000
L 1.2237999 3.65518337 1.22069961 3.65633317 1 P 0 ;0,1,2=102,3=90.000000
L 1.22069961 3.65633317 1.21759931 3.65863337 1 P 0 ;0,1,2=102,3=90.000000
L 1.21759931 3.65863337 1.21553307 3.66131683 1 P 0 ;0,1,2=102,3=90.000000
L 1.21553307 3.66131683 1.2145 3.66399961 1 P 0 ;0,1,2=102,3=90.000000
L 1.2145 3.66399961 1.2145 3.66668307 1 P 0 ;0,1,2=102,3=90.000000
L 1.2145 3.66668307 1.21553307 3.66936654 1 P 0 ;0,1,2=102,3=90.000000
L 1.21553307 3.66936654 1.21708278 3.67166673 1 P 0 ;0,1,2=102,3=90.000000
L 1.21708278 3.67166673 1.21914892 3.67358366 1 P 0 ;0,1,2=102,3=90.000000
L 1.21811585 3.68848287 1.21553307 3.69116634 1 P 0 ;0,1,2=102,3=90.000000
L 1.21553307 3.69116634 1.2145 3.69423307 1 P 0 ;0,1,2=102,3=90.000000
L 1.2145 3.69423307 1.21553307 3.6972998 1 P 0 ;0,1,2=102,3=90.000000
L 1.21553307 3.6972998 1.21863238 3.69998327 1 P 0 ;0,1,2=102,3=90.000000
L 1.21863238 3.69998327 1.22328327 3.7019002 1 P 0 ;0,1,2=102,3=90.000000
L 1.22328327 3.7019002 1.22793327 3.70266673 1 P 0 ;0,1,2=102,3=90.000000
L 1.22793327 3.70266673 1.23361634 3.70266673 1 P 0 ;0,1,2=102,3=90.000000
L 1.23361634 3.70266673 1.23826624 3.7019002 1 P 0 ;0,1,2=102,3=90.000000
L 1.23826624 3.7019002 1.2423997 3.69998327 1 P 0 ;0,1,2=102,3=90.000000
L 1.2423997 3.69998327 1.24446683 3.69768307 1 P 0 ;0,1,2=102,3=90.000000
L 1.24446683 3.69768307 1.2455 3.69499961 1 P 0 ;0,1,2=102,3=90.000000
L 1.2455 3.69499961 1.24446683 3.69193287 1 P 0 ;0,1,2=102,3=90.000000
L 1.24446683 3.69193287 1.2423997 3.68963337 1 P 0 ;0,1,2=102,3=90.000000
L 1.2423997 3.68963337 1.2393003 3.6880997 1 P 0 ;0,1,2=102,3=90.000000
L 1.2393003 3.6880997 1.23516594 3.68733317 1 P 0 ;0,1,2=102,3=90.000000
L 1.23516594 3.68733317 1.2315501 3.6880997 1 P 0 ;0,1,2=102,3=90.000000
L 1.2315501 3.6880997 1.22793327 3.69001663 1 P 0 ;0,1,2=102,3=90.000000
L 1.22793327 3.69001663 1.22586604 3.69231683 1 P 0 ;0,1,2=102,3=90.000000
L 1.22586604 3.69231683 1.22534951 3.69499961 1 P 0 ;0,1,2=102,3=90.000000
L 1.22534951 3.69499961 1.22638268 3.69806634 1 P 0 ;0,1,2=102,3=90.000000
L 1.22638268 3.69806634 1.22896634 3.70036654 1 P 0 ;0,1,2=102,3=90.000000
L 1.22896634 3.70036654 1.23361634 3.70266673 1 P 0 ;0,1,2=102,3=90.000000
L 1.21811585 3.71948287 1.21553307 3.72216634 1 P 0 ;0,1,2=102,3=90.000000
L 1.21553307 3.72216634 1.2145 3.72523307 1 P 0 ;0,1,2=102,3=90.000000
L 1.2145 3.72523307 1.21553307 3.7282998 1 P 0 ;0,1,2=102,3=90.000000
L 1.21553307 3.7282998 1.21863238 3.73098327 1 P 0 ;0,1,2=102,3=90.000000
L 1.21863238 3.73098327 1.22328327 3.7329002 1 P 0 ;0,1,2=102,3=90.000000
L 1.22328327 3.7329002 1.22793327 3.73366673 1 P 0 ;0,1,2=102,3=90.000000
L 1.22793327 3.73366673 1.23361634 3.73366673 1 P 0 ;0,1,2=102,3=90.000000
L 1.23361634 3.73366673 1.23826624 3.7329002 1 P 0 ;0,1,2=102,3=90.000000
L 1.23826624 3.7329002 1.2423997 3.73098327 1 P 0 ;0,1,2=102,3=90.000000
L 1.2423997 3.73098327 1.24446683 3.72868307 1 P 0 ;0,1,2=102,3=90.000000
L 1.24446683 3.72868307 1.2455 3.72599961 1 P 0 ;0,1,2=102,3=90.000000
L 1.2455 3.72599961 1.24446683 3.72293287 1 P 0 ;0,1,2=102,3=90.000000
L 1.24446683 3.72293287 1.2423997 3.72063337 1 P 0 ;0,1,2=102,3=90.000000
L 1.2423997 3.72063337 1.2393003 3.7190997 1 P 0 ;0,1,2=102,3=90.000000
L 1.2393003 3.7190997 1.23516594 3.71833317 1 P 0 ;0,1,2=102,3=90.000000
L 1.23516594 3.71833317 1.2315501 3.7190997 1 P 0 ;0,1,2=102,3=90.000000
L 1.2315501 3.7190997 1.22793327 3.72101663 1 P 0 ;0,1,2=102,3=90.000000
L 1.22793327 3.72101663 1.22586604 3.72331683 1 P 0 ;0,1,2=102,3=90.000000
L 1.22586604 3.72331683 1.22534951 3.72599961 1 P 0 ;0,1,2=102,3=90.000000
L 1.22534951 3.72599961 1.22638268 3.72906634 1 P 0 ;0,1,2=102,3=90.000000
L 1.22638268 3.72906634 1.22896634 3.73136654 1 P 0 ;0,1,2=102,3=90.000000
L 1.22896634 3.73136654 1.23361634 3.73366673 1 P 0 ;0,1,2=102,3=90.000000
L 4.09 2.237 4.09 2.193 1 P 0 
L 4.09 2.193 4 2.193 1 P 0 
L 4 2.193 4 2.237 1 P 0 
L 4 2.237 4.09 2.237 1 P 0 
L 4.17713337 2.22741634 4.17873356 2.22866683 1 P 0 ;0,1,2=103,3=0.000000
L 4.17873356 2.22866683 4.1805998 2.2295 1 P 0 ;0,1,2=103,3=0.000000
L 4.1805998 2.2295 4.18273317 2.2295 1 P 0 ;0,1,2=103,3=0.000000
L 4.18273317 2.2295 4.18513366 2.22824941 1 P 0 ;0,1,2=103,3=0.000000
L 4.18513366 2.22824941 4.1869999 2.22616654 1 P 0 ;0,1,2=103,3=0.000000
L 4.1869999 2.22616654 4.18833346 2.22366634 1 P 0 ;0,1,2=103,3=0.000000
L 4.18833346 2.22366634 4.18940039 2.2194998 1 P 0 ;0,1,2=103,3=0.000000
L 4.18940039 2.2194998 4.18966703 2.2157498 1 P 0 ;0,1,2=103,3=0.000000
L 4.18966703 2.2157498 4.18913327 2.2119999 1 P 0 ;0,1,2=103,3=0.000000
L 4.18913327 2.2119999 4.18833346 2.20949961 1 P 0 ;0,1,2=103,3=0.000000
L 4.18833346 2.20949961 4.18673337 2.20699941 1 P 0 ;0,1,2=103,3=0.000000
L 4.18673337 2.20699941 4.18486654 2.20533307 1 P 0 ;0,1,2=103,3=0.000000
L 4.18486654 2.20533307 4.1830003 2.2045 1 P 0 ;0,1,2=103,3=0.000000
L 4.1830003 2.2045 4.18113356 2.2045 1 P 0 ;0,1,2=103,3=0.000000
L 4.18113356 2.2045 4.17926673 2.20533307 1 P 0 ;0,1,2=103,3=0.000000
L 4.17926673 2.20533307 4.17766663 2.20658287 1 P 0 ;0,1,2=103,3=0.000000
L 4.17766663 2.20658287 4.17633307 2.20824911 1 P 0 ;0,1,2=103,3=0.000000
L 4.1610003 2.2045 4.1610003 2.2295 1 P 0 ;0,1,2=103,3=0.000000
L 4.1610003 2.2295 4.1642001 2.2245003 1 P 0 ;0,1,2=103,3=0.000000
L 4.1642001 2.2045 4.15780049 2.2045 1 P 0 ;0,1,2=103,3=0.000000
L 4.14486673 2.20824911 4.14326703 2.20616624 1 P 0 ;0,1,2=103,3=0.000000
L 4.14326703 2.20616624 4.1414003 2.20491654 1 P 0 ;0,1,2=103,3=0.000000
L 4.1414003 2.20491654 4.1390003 2.2045 1 P 0 ;0,1,2=103,3=0.000000
L 4.1390003 2.2045 4.1365998 2.20533307 1 P 0 ;0,1,2=103,3=0.000000
L 4.1365998 2.20533307 4.13473356 2.20699941 1 P 0 ;0,1,2=103,3=0.000000
L 4.13473356 2.20699941 4.1334 2.20991624 1 P 0 ;0,1,2=103,3=0.000000
L 4.1334 2.20991624 4.13313337 2.21324961 1 P 0 ;0,1,2=103,3=0.000000
L 4.13313337 2.21324961 4.13366663 2.21658297 1 P 0 ;0,1,2=103,3=0.000000
L 4.13366663 2.21658297 4.1350002 2.21866663 1 P 0 ;0,1,2=103,3=0.000000
L 4.1350002 2.21866663 4.13686693 2.22033297 1 P 0 ;0,1,2=103,3=0.000000
L 4.13686693 2.22033297 4.13873317 2.22074951 1 P 0 ;0,1,2=103,3=0.000000
L 4.13873317 2.22074951 4.1406 2.22033297 1 P 0 ;0,1,2=103,3=0.000000
L 4.1406 2.22033297 4.1429999 2.21866663 1 P 0 ;0,1,2=103,3=0.000000
L 4.1429999 2.21866663 4.1422001 2.2295 1 P 0 ;0,1,2=103,3=0.000000
L 4.1422001 2.2295 4.1350002 2.2295 1 P 0 ;0,1,2=103,3=0.000000
L 4.12153366 2.20741604 4.11966683 2.20533307 1 P 0 ;0,1,2=103,3=0.000000
L 4.11966683 2.20533307 4.11753346 2.2045 1 P 0 ;0,1,2=103,3=0.000000
L 4.11753346 2.2045 4.1154001 2.20533307 1 P 0 ;0,1,2=103,3=0.000000
L 4.1154001 2.20533307 4.11353337 2.20783258 1 P 0 ;0,1,2=103,3=0.000000
L 4.11353337 2.20783258 4.1121999 2.21158327 1 P 0 ;0,1,2=103,3=0.000000
L 4.1121999 2.21158327 4.11166663 2.21533327 1 P 0 ;0,1,2=103,3=0.000000
L 4.11166663 2.21533327 4.11166663 2.21991634 1 P 0 ;0,1,2=103,3=0.000000
L 4.11166663 2.21991634 4.1121999 2.22366634 1 P 0 ;0,1,2=103,3=0.000000
L 4.1121999 2.22366634 4.11353337 2.2269997 1 P 0 ;0,1,2=103,3=0.000000
L 4.11353337 2.2269997 4.11513356 2.22866683 1 P 0 ;0,1,2=103,3=0.000000
L 4.11513356 2.22866683 4.1170003 2.2295 1 P 0 ;0,1,2=103,3=0.000000
L 4.1170003 2.2295 4.11913366 2.22866683 1 P 0 ;0,1,2=103,3=0.000000
L 4.11913366 2.22866683 4.12073337 2.2269997 1 P 0 ;0,1,2=103,3=0.000000
L 4.12073337 2.2269997 4.1218002 2.2245003 1 P 0 ;0,1,2=103,3=0.000000
L 4.1218002 2.2245003 4.12233346 2.22116614 1 P 0 ;0,1,2=103,3=0.000000
L 4.12233346 2.22116614 4.1218002 2.2182501 1 P 0 ;0,1,2=103,3=0.000000
L 4.1218002 2.2182501 4.12046673 2.21533327 1 P 0 ;0,1,2=103,3=0.000000
L 4.12046673 2.21533327 4.11886654 2.21366614 1 P 0 ;0,1,2=103,3=0.000000
L 4.11886654 2.21366614 4.1170003 2.21324961 1 P 0 ;0,1,2=103,3=0.000000
L 4.1170003 2.21324961 4.11486693 2.21408278 1 P 0 ;0,1,2=103,3=0.000000
L 4.11486693 2.21408278 4.11326673 2.21616644 1 P 0 ;0,1,2=103,3=0.000000
L 4.11326673 2.21616644 4.11166663 2.21991634 1 P 0 ;0,1,2=103,3=0.000000
L 4.39911004 1.777 4.48911004 1.777 1 P 0 
L 4.48911004 1.777 4.48911004 1.733 1 P 0 
L 4.48911004 1.733 4.39911004 1.733 1 P 0 
L 4.39911004 1.733 4.39911004 1.777 1 P 0 
L 2.76623337 1.69241634 2.76783356 1.69366683 1 P 0 ;0,1,2=104,3=0.000000
L 2.76783356 1.69366683 2.7696998 1.6945 1 P 0 ;0,1,2=104,3=0.000000
L 2.7696998 1.6945 2.77183317 1.6945 1 P 0 ;0,1,2=104,3=0.000000
L 2.77183317 1.6945 2.77423366 1.69324941 1 P 0 ;0,1,2=104,3=0.000000
L 2.77423366 1.69324941 2.7760999 1.69116654 1 P 0 ;0,1,2=104,3=0.000000
L 2.7760999 1.69116654 2.77743346 1.68866634 1 P 0 ;0,1,2=104,3=0.000000
L 2.77743346 1.68866634 2.77850039 1.6844998 1 P 0 ;0,1,2=104,3=0.000000
L 2.77850039 1.6844998 2.77876703 1.6807498 1 P 0 ;0,1,2=104,3=0.000000
L 2.77876703 1.6807498 2.77823327 1.6769999 1 P 0 ;0,1,2=104,3=0.000000
L 2.77823327 1.6769999 2.77743346 1.67449961 1 P 0 ;0,1,2=104,3=0.000000
L 2.77743346 1.67449961 2.77583337 1.67199941 1 P 0 ;0,1,2=104,3=0.000000
L 2.77583337 1.67199941 2.77396654 1.67033307 1 P 0 ;0,1,2=104,3=0.000000
L 2.77396654 1.67033307 2.7721003 1.6695 1 P 0 ;0,1,2=104,3=0.000000
L 2.7721003 1.6695 2.77023356 1.6695 1 P 0 ;0,1,2=104,3=0.000000
L 2.77023356 1.6695 2.76836673 1.67033307 1 P 0 ;0,1,2=104,3=0.000000
L 2.76836673 1.67033307 2.76676663 1.67158287 1 P 0 ;0,1,2=104,3=0.000000
L 2.76676663 1.67158287 2.76543307 1.67324911 1 P 0 ;0,1,2=104,3=0.000000
L 2.7501003 1.6695 2.7501003 1.6945 1 P 0 ;0,1,2=104,3=0.000000
L 2.7501003 1.6945 2.7533001 1.6895003 1 P 0 ;0,1,2=104,3=0.000000
L 2.7533001 1.6695 2.74690049 1.6695 1 P 0 ;0,1,2=104,3=0.000000
L 2.73316683 1.69033337 2.73156673 1.69283287 1 P 0 ;0,1,2=104,3=0.000000
L 2.73156673 1.69283287 2.7297 1.69408337 1 P 0 ;0,1,2=104,3=0.000000
L 2.7297 1.69408337 2.72756663 1.6945 1 P 0 ;0,1,2=104,3=0.000000
L 2.72756663 1.6945 2.7249 1.69366683 1 P 0 ;0,1,2=104,3=0.000000
L 2.7249 1.69366683 2.72303327 1.69158317 1 P 0 ;0,1,2=104,3=0.000000
L 2.72303327 1.69158317 2.7225 1.68908366 1 P 0 ;0,1,2=104,3=0.000000
L 2.7225 1.68908366 2.72276663 1.68658268 1 P 0 ;0,1,2=104,3=0.000000
L 2.72276663 1.68658268 2.72383356 1.6844998 1 P 0 ;0,1,2=104,3=0.000000
L 2.72383356 1.6844998 2.72916673 1.68033327 1 P 0 ;0,1,2=104,3=0.000000
L 2.72916673 1.68033327 2.73156673 1.67741644 1 P 0 ;0,1,2=104,3=0.000000
L 2.73156673 1.67741644 2.73316683 1.67324911 1 P 0 ;0,1,2=104,3=0.000000
L 2.73316683 1.67324911 2.7337001 1.6695 1 P 0 ;0,1,2=104,3=0.000000
L 2.7337001 1.6695 2.7225 1.6695 1 P 0 ;0,1,2=104,3=0.000000
L 2.7061003 1.6695 2.70423356 1.66991654 1 P 0 ;0,1,2=104,3=0.000000
L 2.70423356 1.66991654 2.7021002 1.67116624 1 P 0 ;0,1,2=104,3=0.000000
L 2.7021002 1.67116624 2.70076663 1.67324911 1 P 0 ;0,1,2=104,3=0.000000
L 2.70076663 1.67324911 2.70023337 1.67616673 1 P 0 ;0,1,2=104,3=0.000000
L 2.70023337 1.67616673 2.70076663 1.67908278 1 P 0 ;0,1,2=104,3=0.000000
L 2.70076663 1.67908278 2.70236673 1.68158297 1 P 0 ;0,1,2=104,3=0.000000
L 2.70236673 1.68158297 2.70476673 1.68283346 1 P 0 ;0,1,2=104,3=0.000000
L 2.70476673 1.68283346 2.70743337 1.68283346 1 P 0 ;0,1,2=104,3=0.000000
L 2.70743337 1.68283346 2.70903346 1.68366663 1 P 0 ;0,1,2=104,3=0.000000
L 2.70903346 1.68366663 2.71036703 1.68574951 1 P 0 ;0,1,2=104,3=0.000000
L 2.71036703 1.68574951 2.7109002 1.68866634 1 P 0 ;0,1,2=104,3=0.000000
L 2.7109002 1.68866634 2.7100999 1.69158317 1 P 0 ;0,1,2=104,3=0.000000
L 2.7100999 1.69158317 2.70823366 1.69366683 1 P 0 ;0,1,2=104,3=0.000000
L 2.70823366 1.69366683 2.7061003 1.6945 1 P 0 ;0,1,2=104,3=0.000000
L 2.7061003 1.6945 2.70396693 1.69366683 1 P 0 ;0,1,2=104,3=0.000000
L 2.70396693 1.69366683 2.7021002 1.69158317 1 P 0 ;0,1,2=104,3=0.000000
L 2.7021002 1.69158317 2.7012999 1.68866634 1 P 0 ;0,1,2=104,3=0.000000
L 2.7012999 1.68866634 2.70183356 1.68574951 1 P 0 ;0,1,2=104,3=0.000000
L 2.70183356 1.68574951 2.70316663 1.68366663 1 P 0 ;0,1,2=104,3=0.000000
L 2.70316663 1.68366663 2.70476673 1.68283346 1 P 0 ;0,1,2=104,3=0.000000
L 2.70476673 1.68283346 2.70743337 1.68283346 1 P 0 ;0,1,2=104,3=0.000000
L 2.70743337 1.68283346 2.70983337 1.68158297 1 P 0 ;0,1,2=104,3=0.000000
L 2.70983337 1.68158297 2.71143346 1.67908278 1 P 0 ;0,1,2=104,3=0.000000
L 2.71143346 1.67908278 2.71196673 1.67616673 1 P 0 ;0,1,2=104,3=0.000000
L 2.71196673 1.67616673 2.71143346 1.67324911 1 P 0 ;0,1,2=104,3=0.000000
L 2.71143346 1.67324911 2.7100999 1.67116624 1 P 0 ;0,1,2=104,3=0.000000
L 2.7100999 1.67116624 2.70796654 1.66991654 1 P 0 ;0,1,2=104,3=0.000000
L 2.70796654 1.66991654 2.7061003 1.6695 1 P 0 ;0,1,2=104,3=0.000000
L 4.52085 2.198 4.43085 2.198 1 P 0 
L 4.43085 2.198 4.43085 2.242 1 P 0 
L 4.43085 2.242 4.52085 2.242 1 P 0 
L 4.52085 2.242 4.52085 2.198 1 P 0 
L 4.55041634 2.21786663 4.55166683 2.21626644 1 P 0 ;0,1,2=105,3=90.000000
L 4.55166683 2.21626644 4.5525 2.2144002 1 P 0 ;0,1,2=105,3=90.000000
L 4.5525 2.2144002 4.5525 2.21226683 1 P 0 ;0,1,2=105,3=90.000000
L 4.5525 2.21226683 4.55124941 2.20986634 1 P 0 ;0,1,2=105,3=90.000000
L 4.55124941 2.20986634 4.54916654 2.2080001 1 P 0 ;0,1,2=105,3=90.000000
L 4.54916654 2.2080001 4.54666634 2.20666654 1 P 0 ;0,1,2=105,3=90.000000
L 4.54666634 2.20666654 4.5424998 2.20559961 1 P 0 ;0,1,2=105,3=90.000000
L 4.5424998 2.20559961 4.5387498 2.20533297 1 P 0 ;0,1,2=105,3=90.000000
L 4.5387498 2.20533297 4.5349999 2.20586673 1 P 0 ;0,1,2=105,3=90.000000
L 4.5349999 2.20586673 4.53249961 2.20666654 1 P 0 ;0,1,2=105,3=90.000000
L 4.53249961 2.20666654 4.52999941 2.20826663 1 P 0 ;0,1,2=105,3=90.000000
L 4.52999941 2.20826663 4.52833307 2.21013346 1 P 0 ;0,1,2=105,3=90.000000
L 4.52833307 2.21013346 4.5275 2.2119997 1 P 0 ;0,1,2=105,3=90.000000
L 4.5275 2.2119997 4.5275 2.21386644 1 P 0 ;0,1,2=105,3=90.000000
L 4.5275 2.21386644 4.52833307 2.21573327 1 P 0 ;0,1,2=105,3=90.000000
L 4.52833307 2.21573327 4.52958287 2.21733337 1 P 0 ;0,1,2=105,3=90.000000
L 4.52958287 2.21733337 4.53124911 2.21866693 1 P 0 ;0,1,2=105,3=90.000000
L 4.5275 2.2339997 4.5525 2.2339997 1 P 0 ;0,1,2=105,3=90.000000
L 4.5525 2.2339997 4.5475003 2.2307999 1 P 0 ;0,1,2=105,3=90.000000
L 4.5275 2.2307999 4.5275 2.23719951 1 P 0 ;0,1,2=105,3=90.000000
L 4.53791594 2.25093317 4.54083346 2.2527999 1 P 0 ;0,1,2=105,3=90.000000
L 4.54083346 2.2527999 4.5424998 2.2544 1 P 0 ;0,1,2=105,3=90.000000
L 4.5424998 2.2544 4.54333297 2.25653337 1 P 0 ;0,1,2=105,3=90.000000
L 4.54333297 2.25653337 4.5424998 2.2584002 1 P 0 ;0,1,2=105,3=90.000000
L 4.5424998 2.2584002 4.54083346 2.25973327 1 P 0 ;0,1,2=105,3=90.000000
L 4.54083346 2.25973327 4.53833327 2.2608001 1 P 0 ;0,1,2=105,3=90.000000
L 4.53833327 2.2608001 4.53541644 2.26106673 1 P 0 ;0,1,2=105,3=90.000000
L 4.53541644 2.26106673 4.53291624 2.2608001 1 P 0 ;0,1,2=105,3=90.000000
L 4.53291624 2.2608001 4.53041604 2.25973327 1 P 0 ;0,1,2=105,3=90.000000
L 4.53041604 2.25973327 4.52833307 2.25813307 1 P 0 ;0,1,2=105,3=90.000000
L 4.52833307 2.25813307 4.5275 2.25626683 1 P 0 ;0,1,2=105,3=90.000000
L 4.5275 2.25626683 4.52833307 2.25413346 1 P 0 ;0,1,2=105,3=90.000000
L 4.52833307 2.25413346 4.53083258 2.25226663 1 P 0 ;0,1,2=105,3=90.000000
L 4.53083258 2.25226663 4.53458327 2.2511998 1 P 0 ;0,1,2=105,3=90.000000
L 4.53458327 2.2511998 4.5387498 2.25093317 1 P 0 ;0,1,2=105,3=90.000000
L 4.5387498 2.25093317 4.54416614 2.25146634 1 P 0 ;0,1,2=105,3=90.000000
L 4.54416614 2.25146634 4.54708366 2.25226663 1 P 0 ;0,1,2=105,3=90.000000
L 4.54708366 2.25226663 4.5499997 2.2535997 1 P 0 ;0,1,2=105,3=90.000000
L 4.5499997 2.2535997 4.55208337 2.25546654 1 P 0 ;0,1,2=105,3=90.000000
L 4.55208337 2.25546654 4.5525 2.25733327 1 P 0 ;0,1,2=105,3=90.000000
L 4.5525 2.25733327 4.55166683 2.2592 1 P 0 ;0,1,2=105,3=90.000000
L 4.55166683 2.2592 4.54958317 2.26053356 1 P 0 ;0,1,2=105,3=90.000000
L 4.53249961 2.27213327 4.52958287 2.27373297 1 P 0 ;0,1,2=105,3=90.000000
L 4.52958287 2.27373297 4.52791654 2.27586634 1 P 0 ;0,1,2=105,3=90.000000
L 4.52791654 2.27586634 4.5275 2.27826683 1 P 0 ;0,1,2=105,3=90.000000
L 4.5275 2.27826683 4.52791654 2.2804002 1 P 0 ;0,1,2=105,3=90.000000
L 4.52791654 2.2804002 4.52999941 2.28253356 1 P 0 ;0,1,2=105,3=90.000000
L 4.52999941 2.28253356 4.53249961 2.28386663 1 P 0 ;0,1,2=105,3=90.000000
L 4.53249961 2.28386663 4.5349999 2.28413317 1 P 0 ;0,1,2=105,3=90.000000
L 4.5349999 2.28413317 4.53791594 2.2836 1 P 0 ;0,1,2=105,3=90.000000
L 4.53791594 2.2836 4.53999961 2.28173327 1 P 0 ;0,1,2=105,3=90.000000
L 4.53999961 2.28173327 4.54083346 2.27986644 1 P 0 ;0,1,2=105,3=90.000000
L 4.54083346 2.27986644 4.54083346 2.27746654 1 P 0 ;0,1,2=105,3=90.000000
L 4.54083346 2.27986644 4.54208327 2.28146663 1 P 0 ;0,1,2=105,3=90.000000
L 4.54208327 2.28146663 4.54416614 2.2828001 1 P 0 ;0,1,2=105,3=90.000000
L 4.54416614 2.2828001 4.54666634 2.28333337 1 P 0 ;0,1,2=105,3=90.000000
L 4.54666634 2.28333337 4.54916654 2.2828001 1 P 0 ;0,1,2=105,3=90.000000
L 4.54916654 2.2828001 4.55124941 2.28146663 1 P 0 ;0,1,2=105,3=90.000000
L 4.55124941 2.28146663 4.5525 2.27906663 1 P 0 ;0,1,2=105,3=90.000000
L 4.5525 2.27906663 4.55208337 2.27666663 1 P 0 ;0,1,2=105,3=90.000000
L 4.55208337 2.27666663 4.55041634 2.27426663 1 P 0 ;0,1,2=105,3=90.000000
L 1.6730501 3.97463238 1.66998337 3.97204961 1 P 0 ;0,1,2=106,3=0.000000
L 1.66998337 3.97204961 1.66653337 3.9705 1 P 0 ;0,1,2=106,3=0.000000
L 1.66653337 3.9705 1.66346673 3.9705 1 P 0 ;0,1,2=106,3=0.000000
L 1.66346673 3.9705 1.6604 3.97204961 1 P 0 ;0,1,2=106,3=0.000000
L 1.6604 3.97204961 1.6580998 3.97463238 1 P 0 ;0,1,2=106,3=0.000000
L 1.6580998 3.97463238 1.65695 3.9782502 1 P 0 ;0,1,2=106,3=0.000000
L 1.65695 3.9782502 1.65771654 3.98186604 1 P 0 ;0,1,2=106,3=0.000000
L 1.65771654 3.98186604 1.65963346 3.98496634 1 P 0 ;0,1,2=106,3=0.000000
L 1.65963346 3.98496634 1.66308346 3.98703356 1 P 0 ;0,1,2=106,3=0.000000
L 1.66308346 3.98703356 1.66768317 3.98806663 1 P 0 ;0,1,2=106,3=0.000000
L 1.66768317 3.98806663 1.67036663 3.99013287 1 P 0 ;0,1,2=106,3=0.000000
L 1.67036663 3.99013287 1.67151713 3.9937497 1 P 0 ;0,1,2=106,3=0.000000
L 1.67151713 3.9937497 1.6707499 3.99736654 1 P 0 ;0,1,2=106,3=0.000000
L 1.6707499 3.99736654 1.66883366 3.99994931 1 P 0 ;0,1,2=106,3=0.000000
L 1.66883366 3.99994931 1.6661502 4.0015 1 P 0 ;0,1,2=106,3=0.000000
L 1.6661502 4.0015 1.66346673 4.0015 1 P 0 ;0,1,2=106,3=0.000000
L 1.66346673 4.0015 1.66078327 4.00046683 1 P 0 ;0,1,2=106,3=0.000000
L 1.66078327 4.00046683 1.65848297 3.99788307 1 P 0 ;0,1,2=106,3=0.000000
L 1.64166683 3.9705 1.64166683 4.0015 1 P 0 ;0,1,2=106,3=0.000000
L 1.64166683 4.0015 1.63246673 4.0015 1 P 0 ;0,1,2=106,3=0.000000
L 1.63246673 4.0015 1.6294 3.99994931 1 P 0 ;0,1,2=106,3=0.000000
L 1.6294 3.99994931 1.6270998 3.99633346 1 P 0 ;0,1,2=106,3=0.000000
L 1.6270998 3.99633346 1.62633327 3.9922 1 P 0 ;0,1,2=106,3=0.000000
L 1.62633327 3.9922 1.6270998 3.98806663 1 P 0 ;0,1,2=106,3=0.000000
L 1.6270998 3.98806663 1.62901673 3.98496634 1 P 0 ;0,1,2=106,3=0.000000
L 1.62901673 3.98496634 1.63246673 3.98341575 1 P 0 ;0,1,2=106,3=0.000000
L 1.63246673 3.98341575 1.64166683 3.98341575 1 P 0 ;0,1,2=106,3=0.000000
L 1.60300039 3.9705 1.60300039 4.0015 1 P 0 ;0,1,2=106,3=0.000000
L 1.60300039 4.0015 1.6076001 3.9953003 1 P 0 ;0,1,2=106,3=0.000000
L 1.6076001 3.9705 1.59840069 3.9705 1 P 0 ;0,1,2=106,3=0.000000
L 3.3740501 3.86863238 3.37098337 3.86604961 1 P 0 ;0,1,2=107,3=0.000000
L 3.37098337 3.86604961 3.36753337 3.8645 1 P 0 ;0,1,2=107,3=0.000000
L 3.36753337 3.8645 3.36446673 3.8645 1 P 0 ;0,1,2=107,3=0.000000
L 3.36446673 3.8645 3.3614 3.86604961 1 P 0 ;0,1,2=107,3=0.000000
L 3.3614 3.86604961 3.3590998 3.86863238 1 P 0 ;0,1,2=107,3=0.000000
L 3.3590998 3.86863238 3.35795 3.8722502 1 P 0 ;0,1,2=107,3=0.000000
L 3.35795 3.8722502 3.35871654 3.87586604 1 P 0 ;0,1,2=107,3=0.000000
L 3.35871654 3.87586604 3.36063346 3.87896634 1 P 0 ;0,1,2=107,3=0.000000
L 3.36063346 3.87896634 3.36408346 3.88103356 1 P 0 ;0,1,2=107,3=0.000000
L 3.36408346 3.88103356 3.36868317 3.88206663 1 P 0 ;0,1,2=107,3=0.000000
L 3.36868317 3.88206663 3.37136663 3.88413287 1 P 0 ;0,1,2=107,3=0.000000
L 3.37136663 3.88413287 3.37251713 3.8877497 1 P 0 ;0,1,2=107,3=0.000000
L 3.37251713 3.8877497 3.3717499 3.89136654 1 P 0 ;0,1,2=107,3=0.000000
L 3.3717499 3.89136654 3.36983366 3.89394931 1 P 0 ;0,1,2=107,3=0.000000
L 3.36983366 3.89394931 3.3671502 3.8955 1 P 0 ;0,1,2=107,3=0.000000
L 3.3671502 3.8955 3.36446673 3.8955 1 P 0 ;0,1,2=107,3=0.000000
L 3.36446673 3.8955 3.36178327 3.89446683 1 P 0 ;0,1,2=107,3=0.000000
L 3.36178327 3.89446683 3.35948297 3.89188307 1 P 0 ;0,1,2=107,3=0.000000
L 3.34266683 3.8645 3.34266683 3.8955 1 P 0 ;0,1,2=107,3=0.000000
L 3.34266683 3.8955 3.33346673 3.8955 1 P 0 ;0,1,2=107,3=0.000000
L 3.33346673 3.8955 3.3304 3.89394931 1 P 0 ;0,1,2=107,3=0.000000
L 3.3304 3.89394931 3.3280998 3.89033346 1 P 0 ;0,1,2=107,3=0.000000
L 3.3280998 3.89033346 3.32733327 3.8862 1 P 0 ;0,1,2=107,3=0.000000
L 3.32733327 3.8862 3.3280998 3.88206663 1 P 0 ;0,1,2=107,3=0.000000
L 3.3280998 3.88206663 3.33001673 3.87896634 1 P 0 ;0,1,2=107,3=0.000000
L 3.33001673 3.87896634 3.33346673 3.87741575 1 P 0 ;0,1,2=107,3=0.000000
L 3.33346673 3.87741575 3.34266683 3.87741575 1 P 0 ;0,1,2=107,3=0.000000
L 3.31128356 3.89033346 3.30898337 3.89343278 1 P 0 ;0,1,2=107,3=0.000000
L 3.30898337 3.89343278 3.3062999 3.89498337 1 P 0 ;0,1,2=107,3=0.000000
L 3.3062999 3.89498337 3.30323317 3.8955 1 P 0 ;0,1,2=107,3=0.000000
L 3.30323317 3.8955 3.2994 3.89446683 1 P 0 ;0,1,2=107,3=0.000000
L 3.2994 3.89446683 3.29671654 3.89188307 1 P 0 ;0,1,2=107,3=0.000000
L 3.29671654 3.89188307 3.29595 3.88878376 1 P 0 ;0,1,2=107,3=0.000000
L 3.29595 3.88878376 3.29633327 3.88568258 1 P 0 ;0,1,2=107,3=0.000000
L 3.29633327 3.88568258 3.29786693 3.8830998 1 P 0 ;0,1,2=107,3=0.000000
L 3.29786693 3.8830998 3.30553337 3.87793327 1 P 0 ;0,1,2=107,3=0.000000
L 3.30553337 3.87793327 3.30898337 3.87431644 1 P 0 ;0,1,2=107,3=0.000000
L 3.30898337 3.87431644 3.31128356 3.86914892 1 P 0 ;0,1,2=107,3=0.000000
L 3.31128356 3.86914892 3.3120501 3.8645 1 P 0 ;0,1,2=107,3=0.000000
L 3.3120501 3.8645 3.29595 3.8645 1 P 0 ;0,1,2=107,3=0.000000
L 5.6890501 2.08863238 5.68598337 2.08604961 1 P 0 ;0,1,2=108,3=0.000000
L 5.68598337 2.08604961 5.68253337 2.0845 1 P 0 ;0,1,2=108,3=0.000000
L 5.68253337 2.0845 5.67946673 2.0845 1 P 0 ;0,1,2=108,3=0.000000
L 5.67946673 2.0845 5.6764 2.08604961 1 P 0 ;0,1,2=108,3=0.000000
L 5.6764 2.08604961 5.6740998 2.08863238 1 P 0 ;0,1,2=108,3=0.000000
L 5.6740998 2.08863238 5.67295 2.0922502 1 P 0 ;0,1,2=108,3=0.000000
L 5.67295 2.0922502 5.67371654 2.09586604 1 P 0 ;0,1,2=108,3=0.000000
L 5.67371654 2.09586604 5.67563346 2.09896634 1 P 0 ;0,1,2=108,3=0.000000
L 5.67563346 2.09896634 5.67908346 2.10103356 1 P 0 ;0,1,2=108,3=0.000000
L 5.67908346 2.10103356 5.68368317 2.10206663 1 P 0 ;0,1,2=108,3=0.000000
L 5.68368317 2.10206663 5.68636663 2.10413287 1 P 0 ;0,1,2=108,3=0.000000
L 5.68636663 2.10413287 5.68751713 2.1077497 1 P 0 ;0,1,2=108,3=0.000000
L 5.68751713 2.1077497 5.6867499 2.11136654 1 P 0 ;0,1,2=108,3=0.000000
L 5.6867499 2.11136654 5.68483366 2.11394931 1 P 0 ;0,1,2=108,3=0.000000
L 5.68483366 2.11394931 5.6821502 2.1155 1 P 0 ;0,1,2=108,3=0.000000
L 5.6821502 2.1155 5.67946673 2.1155 1 P 0 ;0,1,2=108,3=0.000000
L 5.67946673 2.1155 5.67678327 2.11446683 1 P 0 ;0,1,2=108,3=0.000000
L 5.67678327 2.11446683 5.67448297 2.11188307 1 P 0 ;0,1,2=108,3=0.000000
L 5.65766683 2.0845 5.65766683 2.1155 1 P 0 ;0,1,2=108,3=0.000000
L 5.65766683 2.1155 5.64846673 2.1155 1 P 0 ;0,1,2=108,3=0.000000
L 5.64846673 2.1155 5.6454 2.11394931 1 P 0 ;0,1,2=108,3=0.000000
L 5.6454 2.11394931 5.6430998 2.11033346 1 P 0 ;0,1,2=108,3=0.000000
L 5.6430998 2.11033346 5.64233327 2.1062 1 P 0 ;0,1,2=108,3=0.000000
L 5.64233327 2.1062 5.6430998 2.10206663 1 P 0 ;0,1,2=108,3=0.000000
L 5.6430998 2.10206663 5.64501673 2.09896634 1 P 0 ;0,1,2=108,3=0.000000
L 5.64501673 2.09896634 5.64846673 2.09741575 1 P 0 ;0,1,2=108,3=0.000000
L 5.64846673 2.09741575 5.65766683 2.09741575 1 P 0 ;0,1,2=108,3=0.000000
L 5.62743337 2.09069961 5.62513386 2.08708278 1 P 0 ;0,1,2=108,3=0.000000
L 5.62513386 2.08708278 5.62206713 2.08501654 1 P 0 ;0,1,2=108,3=0.000000
L 5.62206713 2.08501654 5.61861644 2.0845 1 P 0 ;0,1,2=108,3=0.000000
L 5.61861644 2.0845 5.6155497 2.08501654 1 P 0 ;0,1,2=108,3=0.000000
L 5.6155497 2.08501654 5.61248297 2.08759931 1 P 0 ;0,1,2=108,3=0.000000
L 5.61248297 2.08759931 5.61056673 2.09069961 1 P 0 ;0,1,2=108,3=0.000000
L 5.61056673 2.09069961 5.61018346 2.0937999 1 P 0 ;0,1,2=108,3=0.000000
L 5.61018346 2.0937999 5.61095 2.09741575 1 P 0 ;0,1,2=108,3=0.000000
L 5.61095 2.09741575 5.61363346 2.09999951 1 P 0 ;0,1,2=108,3=0.000000
L 5.61363346 2.09999951 5.61631693 2.10103356 1 P 0 ;0,1,2=108,3=0.000000
L 5.61631693 2.10103356 5.61976693 2.10103356 1 P 0 ;0,1,2=108,3=0.000000
L 5.61631693 2.10103356 5.61401673 2.10258317 1 P 0 ;0,1,2=108,3=0.000000
L 5.61401673 2.10258317 5.6120998 2.10516594 1 P 0 ;0,1,2=108,3=0.000000
L 5.6120998 2.10516594 5.61133327 2.10826624 1 P 0 ;0,1,2=108,3=0.000000
L 5.61133327 2.10826624 5.6120998 2.11136654 1 P 0 ;0,1,2=108,3=0.000000
L 5.6120998 2.11136654 5.61401673 2.11394931 1 P 0 ;0,1,2=108,3=0.000000
L 5.61401673 2.11394931 5.61746673 2.1155 1 P 0 ;0,1,2=108,3=0.000000
L 5.61746673 2.1155 5.62091663 2.11498337 1 P 0 ;0,1,2=108,3=0.000000
L 5.62091663 2.11498337 5.62436663 2.11291624 1 P 0 ;0,1,2=108,3=0.000000
L 5.41041004 3.42996998 5.36041004 3.42996998 1 P 0 
L 5.38541004 3.45496998 5.38541004 3.40496998 1 P 0 
L 5.40376004 3.46748996 5.40376004 3.74651004 1 P 0 
L 5.40376004 3.74651004 5.22823996 3.74651004 1 P 0 
L 5.22823996 3.46748996 5.40376004 3.46748996 1 P 0 
L 5.22823996 3.74651004 5.22823996 3.46748996 1 P 0 
S P 0
OB 5.40376003937 3.76651003937 I
OS 5.40376003937 3.74651003937
OS 5.22823996063 3.74651003937
OS 5.22823996063 3.76651003937
OS 5.40376003937 3.76651003937
OE
SE
L 5.37156673 3.79791624 5.37386693 3.79946683 1 P 0 ;0,1,2=109,3=0.000000
L 5.37386693 3.79946683 5.3765497 3.8005 1 P 0 ;0,1,2=109,3=0.000000
L 5.3765497 3.8005 5.37961644 3.8005 1 P 0 ;0,1,2=109,3=0.000000
L 5.37961644 3.8005 5.38306713 3.79894931 1 P 0 ;0,1,2=109,3=0.000000
L 5.38306713 3.79894931 5.3857499 3.79636654 1 P 0 ;0,1,2=109,3=0.000000
L 5.3857499 3.79636654 5.38766683 3.79326624 1 P 0 ;0,1,2=109,3=0.000000
L 5.38766683 3.79326624 5.38920049 3.7880998 1 P 0 ;0,1,2=109,3=0.000000
L 5.38920049 3.7880998 5.38958376 3.7834498 1 P 0 ;0,1,2=109,3=0.000000
L 5.38958376 3.7834498 5.38881663 3.7787999 1 P 0 ;0,1,2=109,3=0.000000
L 5.38881663 3.7787999 5.38766683 3.77569961 1 P 0 ;0,1,2=109,3=0.000000
L 5.38766683 3.77569961 5.38536663 3.77259931 1 P 0 ;0,1,2=109,3=0.000000
L 5.38536663 3.77259931 5.38268317 3.77053307 1 P 0 ;0,1,2=109,3=0.000000
L 5.38268317 3.77053307 5.38000039 3.7695 1 P 0 ;0,1,2=109,3=0.000000
L 5.38000039 3.7695 5.37731693 3.7695 1 P 0 ;0,1,2=109,3=0.000000
L 5.37731693 3.7695 5.37463346 3.77053307 1 P 0 ;0,1,2=109,3=0.000000
L 5.37463346 3.77053307 5.37233327 3.77208278 1 P 0 ;0,1,2=109,3=0.000000
L 5.37233327 3.77208278 5.37041634 3.77414892 1 P 0 ;0,1,2=109,3=0.000000
L 5.30958376 3.4095 5.30000039 3.4405 1 P 0 ;0,1,2=0,3=0.000000
L 5.30000039 3.4405 5.29041634 3.4095 1 P 0 ;0,1,2=0,3=0.000000
L 5.29386693 3.42034951 5.30613386 3.42034951 1 P 0 ;0,1,2=0,3=0.000000
L 5.21291624 3.60343327 5.21446683 3.60113307 1 P 0 ;0,1,2=110,3=90.000000
L 5.21446683 3.60113307 5.2155 3.5984503 1 P 0 ;0,1,2=110,3=90.000000
L 5.2155 3.5984503 5.2155 3.59538356 1 P 0 ;0,1,2=110,3=90.000000
L 5.2155 3.59538356 5.21394931 3.59193287 1 P 0 ;0,1,2=110,3=90.000000
L 5.21394931 3.59193287 5.21136654 3.5892501 1 P 0 ;0,1,2=110,3=90.000000
L 5.21136654 3.5892501 5.20826624 3.58733317 1 P 0 ;0,1,2=110,3=90.000000
L 5.20826624 3.58733317 5.2030998 3.58579951 1 P 0 ;0,1,2=110,3=90.000000
L 5.2030998 3.58579951 5.1984498 3.58541624 1 P 0 ;0,1,2=110,3=90.000000
L 5.1984498 3.58541624 5.1937999 3.58618337 1 P 0 ;0,1,2=110,3=90.000000
L 5.1937999 3.58618337 5.19069961 3.58733317 1 P 0 ;0,1,2=110,3=90.000000
L 5.19069961 3.58733317 5.18759931 3.58963337 1 P 0 ;0,1,2=110,3=90.000000
L 5.18759931 3.58963337 5.18553307 3.59231683 1 P 0 ;0,1,2=110,3=90.000000
L 5.18553307 3.59231683 5.1845 3.59499961 1 P 0 ;0,1,2=110,3=90.000000
L 5.1845 3.59499961 5.1845 3.59768307 1 P 0 ;0,1,2=110,3=90.000000
L 5.1845 3.59768307 5.18553307 3.60036654 1 P 0 ;0,1,2=110,3=90.000000
L 5.18553307 3.60036654 5.18708278 3.60266673 1 P 0 ;0,1,2=110,3=90.000000
L 5.18708278 3.60266673 5.18914892 3.60458366 1 P 0 ;0,1,2=110,3=90.000000
L 5.1845 3.61833317 5.2155 3.61833317 1 P 0 ;0,1,2=110,3=90.000000
L 5.2155 3.61833317 5.2155 3.62791654 1 P 0 ;0,1,2=110,3=90.000000
L 5.2155 3.62791654 5.21394931 3.63098327 1 P 0 ;0,1,2=110,3=90.000000
L 5.21394931 3.63098327 5.21188307 3.6329002 1 P 0 ;0,1,2=110,3=90.000000
L 5.21188307 3.6329002 5.2077497 3.63366673 1 P 0 ;0,1,2=110,3=90.000000
L 5.2077497 3.63366673 5.20361634 3.6329002 1 P 0 ;0,1,2=110,3=90.000000
L 5.20361634 3.6329002 5.20103356 3.6306 1 P 0 ;0,1,2=110,3=90.000000
L 5.20103356 3.6306 5.19948287 3.62791654 1 P 0 ;0,1,2=110,3=90.000000
L 5.19948287 3.62791654 5.19948287 3.61833317 1 P 0 ;0,1,2=110,3=90.000000
L 5.19948287 3.62791654 5.1845 3.63366673 1 P 0 ;0,1,2=110,3=90.000000
L 5.19069961 3.64856663 5.18708278 3.65086614 1 P 0 ;0,1,2=110,3=90.000000
L 5.18708278 3.65086614 5.18501654 3.65393287 1 P 0 ;0,1,2=110,3=90.000000
L 5.18501654 3.65393287 5.1845 3.65738356 1 P 0 ;0,1,2=110,3=90.000000
L 5.1845 3.65738356 5.18501654 3.6604503 1 P 0 ;0,1,2=110,3=90.000000
L 5.18501654 3.6604503 5.18759931 3.66351703 1 P 0 ;0,1,2=110,3=90.000000
L 5.18759931 3.66351703 5.19069961 3.66543327 1 P 0 ;0,1,2=110,3=90.000000
L 5.19069961 3.66543327 5.1937999 3.66581654 1 P 0 ;0,1,2=110,3=90.000000
L 5.1937999 3.66581654 5.19741575 3.66505 1 P 0 ;0,1,2=110,3=90.000000
L 5.19741575 3.66505 5.19999951 3.66236654 1 P 0 ;0,1,2=110,3=90.000000
L 5.19999951 3.66236654 5.20103356 3.65968307 1 P 0 ;0,1,2=110,3=90.000000
L 5.20103356 3.65968307 5.20103356 3.65623307 1 P 0 ;0,1,2=110,3=90.000000
L 5.20103356 3.65968307 5.20258317 3.66198327 1 P 0 ;0,1,2=110,3=90.000000
L 5.20258317 3.66198327 5.20516594 3.6639002 1 P 0 ;0,1,2=110,3=90.000000
L 5.20516594 3.6639002 5.20826624 3.66466673 1 P 0 ;0,1,2=110,3=90.000000
L 5.20826624 3.66466673 5.21136654 3.6639002 1 P 0 ;0,1,2=110,3=90.000000
L 5.21136654 3.6639002 5.21394931 3.66198327 1 P 0 ;0,1,2=110,3=90.000000
L 5.21394931 3.66198327 5.2155 3.65853327 1 P 0 ;0,1,2=110,3=90.000000
L 5.2155 3.65853327 5.21498337 3.65508337 1 P 0 ;0,1,2=110,3=90.000000
L 5.21498337 3.65508337 5.21291624 3.65163337 1 P 0 ;0,1,2=110,3=90.000000
L 2.7474 2.34 2.7074 2.34 1 P 0 
L 2.6726 2.34 2.6326 2.34 1 P 0 
L 2.7074 2.34 2.7074 2.2915 1 P 0 
L 2.7074 2.2915 2.6726 2.2915 1 P 0 
L 2.6726 2.2915 2.6726 2.34 1 P 0 
L 2.6326 2.34 2.6326 2.2915 1 P 0 
L 2.6326 2.2915 2.62291004 2.2915 1 P 0 
L 2.62291004 2.2915 2.62291004 2.2085 1 P 0 
L 2.62291004 2.2085 2.6326 2.2085 1 P 0 
L 2.6326 2.2085 2.6326 2.16 1 P 0 
L 2.6326 2.16 2.7474 2.16 1 P 0 
L 2.7474 2.16 2.7474 2.2085 1 P 0 
L 2.7474 2.2085 2.75708996 2.2085 1 P 0 
L 2.75708996 2.2085 2.75708996 2.2915 1 P 0 
L 2.75708996 2.2915 2.7474 2.2915 1 P 0 
L 2.7474 2.2915 2.7474 2.34 1 P 0 
S P 0
OB 2.751 2.136 I
OC 2.751 2.136 2.736 2.136 Y
OE
SE
L 2.75586673 2.35624911 2.75426703 2.35416624 1 P 0 ;0,1,2=111,3=0.000000
L 2.75426703 2.35416624 2.7524003 2.35291654 1 P 0 ;0,1,2=111,3=0.000000
L 2.7524003 2.35291654 2.7500003 2.3525 1 P 0 ;0,1,2=111,3=0.000000
L 2.7500003 2.3525 2.7475998 2.35333307 1 P 0 ;0,1,2=111,3=0.000000
L 2.7475998 2.35333307 2.74573356 2.35499941 1 P 0 ;0,1,2=111,3=0.000000
L 2.74573356 2.35499941 2.7444 2.35791624 1 P 0 ;0,1,2=111,3=0.000000
L 2.7444 2.35791624 2.74413337 2.36124961 1 P 0 ;0,1,2=111,3=0.000000
L 2.74413337 2.36124961 2.74466663 2.36458297 1 P 0 ;0,1,2=111,3=0.000000
L 2.74466663 2.36458297 2.7460002 2.36666663 1 P 0 ;0,1,2=111,3=0.000000
L 2.7460002 2.36666663 2.74786693 2.36833297 1 P 0 ;0,1,2=111,3=0.000000
L 2.74786693 2.36833297 2.74973317 2.36874951 1 P 0 ;0,1,2=111,3=0.000000
L 2.74973317 2.36874951 2.7516 2.36833297 1 P 0 ;0,1,2=111,3=0.000000
L 2.7516 2.36833297 2.7539999 2.36666663 1 P 0 ;0,1,2=111,3=0.000000
L 2.7539999 2.36666663 2.7532001 2.3775 1 P 0 ;0,1,2=111,3=0.000000
L 2.7532001 2.3775 2.7460002 2.3775 1 P 0 ;0,1,2=111,3=0.000000
L 2.5825 2.3432 2.6075 2.3432 1 P 0 ;0,1,2=112,3=90.000000
L 2.6075 2.3432 2.58958327 2.33333297 1 P 0 ;0,1,2=112,3=90.000000
L 2.58958327 2.33333297 2.58958327 2.34666693 1 P 0 ;0,1,2=112,3=90.000000
L 2.63086673 2.10249961 2.62926703 2.09958287 1 P 0 ;0,1,2=113,3=0.000000
L 2.62926703 2.09958287 2.62713366 2.09791654 1 P 0 ;0,1,2=113,3=0.000000
L 2.62713366 2.09791654 2.62473317 2.0975 1 P 0 ;0,1,2=113,3=0.000000
L 2.62473317 2.0975 2.6225998 2.09791654 1 P 0 ;0,1,2=113,3=0.000000
L 2.6225998 2.09791654 2.62046644 2.09999941 1 P 0 ;0,1,2=113,3=0.000000
L 2.62046644 2.09999941 2.61913337 2.10249961 1 P 0 ;0,1,2=113,3=0.000000
L 2.61913337 2.10249961 2.61886683 2.1049999 1 P 0 ;0,1,2=113,3=0.000000
L 2.61886683 2.1049999 2.6194 2.10791594 1 P 0 ;0,1,2=113,3=0.000000
L 2.6194 2.10791594 2.62126673 2.10999961 1 P 0 ;0,1,2=113,3=0.000000
L 2.62126673 2.10999961 2.62313356 2.11083346 1 P 0 ;0,1,2=113,3=0.000000
L 2.62313356 2.11083346 2.62553346 2.11083346 1 P 0 ;0,1,2=113,3=0.000000
L 2.62313356 2.11083346 2.62153337 2.11208327 1 P 0 ;0,1,2=113,3=0.000000
L 2.62153337 2.11208327 2.6201999 2.11416614 1 P 0 ;0,1,2=113,3=0.000000
L 2.6201999 2.11416614 2.61966663 2.11666634 1 P 0 ;0,1,2=113,3=0.000000
L 2.61966663 2.11666634 2.6201999 2.11916654 1 P 0 ;0,1,2=113,3=0.000000
L 2.6201999 2.11916654 2.62153337 2.12124941 1 P 0 ;0,1,2=113,3=0.000000
L 2.62153337 2.12124941 2.62393337 2.1225 1 P 0 ;0,1,2=113,3=0.000000
L 2.62393337 2.1225 2.62633337 2.12208337 1 P 0 ;0,1,2=113,3=0.000000
L 2.62633337 2.12208337 2.62873337 2.12041634 1 P 0 ;0,1,2=113,3=0.000000
L 2.77443337 2.1105 2.77443337 2.08828327 1 P 0 ;0,1,2=114,3=0.000000
L 2.77443337 2.08828327 2.7729003 2.08363238 1 P 0 ;0,1,2=114,3=0.000000
L 2.7729003 2.08363238 2.76983366 2.08053307 1 P 0 ;0,1,2=114,3=0.000000
L 2.76983366 2.08053307 2.76600039 2.0795 1 P 0 ;0,1,2=114,3=0.000000
L 2.76600039 2.0795 2.76216644 2.08053307 1 P 0 ;0,1,2=114,3=0.000000
L 2.76216644 2.08053307 2.7590998 2.08363238 1 P 0 ;0,1,2=114,3=0.000000
L 2.7590998 2.08363238 2.75756673 2.08828327 1 P 0 ;0,1,2=114,3=0.000000
L 2.75756673 2.08828327 2.75756673 2.1105 1 P 0 ;0,1,2=114,3=0.000000
L 2.73500039 2.0795 2.73500039 2.1105 1 P 0 ;0,1,2=114,3=0.000000
L 2.73500039 2.1105 2.7396001 2.1043003 1 P 0 ;0,1,2=114,3=0.000000
L 2.7396001 2.0795 2.73040069 2.0795 1 P 0 ;0,1,2=114,3=0.000000
L 2.71128356 2.10533346 2.70898337 2.10843278 1 P 0 ;0,1,2=114,3=0.000000
L 2.70898337 2.10843278 2.7062999 2.10998337 1 P 0 ;0,1,2=114,3=0.000000
L 2.7062999 2.10998337 2.70323317 2.1105 1 P 0 ;0,1,2=114,3=0.000000
L 2.70323317 2.1105 2.6994 2.10946683 1 P 0 ;0,1,2=114,3=0.000000
L 2.6994 2.10946683 2.69671654 2.10688307 1 P 0 ;0,1,2=114,3=0.000000
L 2.69671654 2.10688307 2.69595 2.10378376 1 P 0 ;0,1,2=114,3=0.000000
L 2.69595 2.10378376 2.69633327 2.10068258 1 P 0 ;0,1,2=114,3=0.000000
L 2.69633327 2.10068258 2.69786693 2.0980998 1 P 0 ;0,1,2=114,3=0.000000
L 2.69786693 2.0980998 2.70553337 2.09293327 1 P 0 ;0,1,2=114,3=0.000000
L 2.70553337 2.09293327 2.70898337 2.08931644 1 P 0 ;0,1,2=114,3=0.000000
L 2.70898337 2.08931644 2.71128356 2.08414892 1 P 0 ;0,1,2=114,3=0.000000
L 2.71128356 2.08414892 2.7120501 2.0795 1 P 0 ;0,1,2=114,3=0.000000
L 2.7120501 2.0795 2.69595 2.0795 1 P 0 ;0,1,2=114,3=0.000000
L 2.012 3.558 1.946 3.558 1 P 0 
L 1.946 3.558 1.946 3.5695 1 P 0 
L 1.946 3.3565 1.946 3.368 1 P 0 
L 1.946 3.368 2.012 3.368 1 P 0 
L 2.012 3.368 2.012 3.558 1 P 0 
L 1.772 3.5695 1.772 3.558 1 P 0 
L 1.946 3.5695 1.772 3.5695 1 P 0 
L 1.772 3.368 1.772 3.3565 1 P 0 
L 1.772 3.3565 1.946 3.3565 1 P 0 
L 1.772 3.558 1.706 3.558 1 P 0 
L 1.706 3.558 1.706 3.368 1 P 0 
L 1.706 3.368 1.772 3.368 1 P 0 
S P 0
OB 2.055 3.58 I
OC 2.055 3.58 2.04 3.58 Y
OE
SE
L 2.0304 3.3395 2.0304 3.3705 1 P 0 ;0,1,2=112,3=0.000000
L 2.0304 3.3705 2.04458376 3.34828327 1 P 0 ;0,1,2=112,3=0.000000
L 2.04458376 3.34828327 2.02541634 3.34828327 1 P 0 ;0,1,2=112,3=0.000000
L 1.90943337 3.6255 1.90943337 3.60328327 1 P 0 ;0,1,2=115,3=0.000000
L 1.90943337 3.60328327 1.9079003 3.59863238 1 P 0 ;0,1,2=115,3=0.000000
L 1.9079003 3.59863238 1.90483366 3.59553307 1 P 0 ;0,1,2=115,3=0.000000
L 1.90483366 3.59553307 1.90100039 3.5945 1 P 0 ;0,1,2=115,3=0.000000
L 1.90100039 3.5945 1.89716644 3.59553307 1 P 0 ;0,1,2=115,3=0.000000
L 1.89716644 3.59553307 1.8940998 3.59863238 1 P 0 ;0,1,2=115,3=0.000000
L 1.8940998 3.59863238 1.89256673 3.60328327 1 P 0 ;0,1,2=115,3=0.000000
L 1.89256673 3.60328327 1.89256673 3.6255 1 P 0 ;0,1,2=115,3=0.000000
L 1.87843337 3.60069961 1.87613386 3.59708278 1 P 0 ;0,1,2=115,3=0.000000
L 1.87613386 3.59708278 1.87306713 3.59501654 1 P 0 ;0,1,2=115,3=0.000000
L 1.87306713 3.59501654 1.86961644 3.5945 1 P 0 ;0,1,2=115,3=0.000000
L 1.86961644 3.5945 1.8665497 3.59501654 1 P 0 ;0,1,2=115,3=0.000000
L 1.8665497 3.59501654 1.86348297 3.59759931 1 P 0 ;0,1,2=115,3=0.000000
L 1.86348297 3.59759931 1.86156673 3.60069961 1 P 0 ;0,1,2=115,3=0.000000
L 1.86156673 3.60069961 1.86118346 3.6037999 1 P 0 ;0,1,2=115,3=0.000000
L 1.86118346 3.6037999 1.86195 3.60741575 1 P 0 ;0,1,2=115,3=0.000000
L 1.86195 3.60741575 1.86463346 3.60999951 1 P 0 ;0,1,2=115,3=0.000000
L 1.86463346 3.60999951 1.86731693 3.61103356 1 P 0 ;0,1,2=115,3=0.000000
L 1.86731693 3.61103356 1.87076693 3.61103356 1 P 0 ;0,1,2=115,3=0.000000
L 1.86731693 3.61103356 1.86501673 3.61258317 1 P 0 ;0,1,2=115,3=0.000000
L 1.86501673 3.61258317 1.8630998 3.61516594 1 P 0 ;0,1,2=115,3=0.000000
L 1.8630998 3.61516594 1.86233327 3.61826624 1 P 0 ;0,1,2=115,3=0.000000
L 1.86233327 3.61826624 1.8630998 3.62136654 1 P 0 ;0,1,2=115,3=0.000000
L 1.8630998 3.62136654 1.86501673 3.62394931 1 P 0 ;0,1,2=115,3=0.000000
L 1.86501673 3.62394931 1.86846673 3.6255 1 P 0 ;0,1,2=115,3=0.000000
L 1.86846673 3.6255 1.87191663 3.62498337 1 P 0 ;0,1,2=115,3=0.000000
L 1.87191663 3.62498337 1.87536663 3.62291624 1 P 0 ;0,1,2=115,3=0.000000
L 1.83900039 3.5945 1.83900039 3.6255 1 P 0 ;0,1,2=115,3=0.000000
L 1.83900039 3.6255 1.8436001 3.6193003 1 P 0 ;0,1,2=115,3=0.000000
L 1.8436001 3.5945 1.83440069 3.5945 1 P 0 ;0,1,2=115,3=0.000000
L 1.68500039 3.5295 1.68231693 3.53001654 1 P 0 ;0,1,2=116,3=0.000000
L 1.68231693 3.53001654 1.6792502 3.53156614 1 P 0 ;0,1,2=116,3=0.000000
L 1.6792502 3.53156614 1.67733327 3.53414892 1 P 0 ;0,1,2=116,3=0.000000
L 1.67733327 3.53414892 1.67656673 3.53776673 1 P 0 ;0,1,2=116,3=0.000000
L 1.67656673 3.53776673 1.67733327 3.54138268 1 P 0 ;0,1,2=116,3=0.000000
L 1.67733327 3.54138268 1.67963346 3.54448287 1 P 0 ;0,1,2=116,3=0.000000
L 1.67963346 3.54448287 1.68308346 3.54603356 1 P 0 ;0,1,2=116,3=0.000000
L 1.68308346 3.54603356 1.68691663 3.54603356 1 P 0 ;0,1,2=116,3=0.000000
L 1.68691663 3.54603356 1.68921683 3.54706663 1 P 0 ;0,1,2=116,3=0.000000
L 1.68921683 3.54706663 1.69113386 3.54964941 1 P 0 ;0,1,2=116,3=0.000000
L 1.69113386 3.54964941 1.6919003 3.55326624 1 P 0 ;0,1,2=116,3=0.000000
L 1.6919003 3.55326624 1.6907499 3.55688307 1 P 0 ;0,1,2=116,3=0.000000
L 1.6907499 3.55688307 1.68806713 3.55946683 1 P 0 ;0,1,2=116,3=0.000000
L 1.68806713 3.55946683 1.68500039 3.5605 1 P 0 ;0,1,2=116,3=0.000000
L 1.68500039 3.5605 1.68193366 3.55946683 1 P 0 ;0,1,2=116,3=0.000000
L 1.68193366 3.55946683 1.6792502 3.55688307 1 P 0 ;0,1,2=116,3=0.000000
L 1.6792502 3.55688307 1.6780998 3.55326624 1 P 0 ;0,1,2=116,3=0.000000
L 1.6780998 3.55326624 1.67886693 3.54964941 1 P 0 ;0,1,2=116,3=0.000000
L 1.67886693 3.54964941 1.68078327 3.54706663 1 P 0 ;0,1,2=116,3=0.000000
L 1.68078327 3.54706663 1.68308346 3.54603356 1 P 0 ;0,1,2=116,3=0.000000
L 1.68308346 3.54603356 1.68691663 3.54603356 1 P 0 ;0,1,2=116,3=0.000000
L 1.68691663 3.54603356 1.69036663 3.54448287 1 P 0 ;0,1,2=116,3=0.000000
L 1.69036663 3.54448287 1.69266683 3.54138268 1 P 0 ;0,1,2=116,3=0.000000
L 1.69266683 3.54138268 1.69343337 3.53776673 1 P 0 ;0,1,2=116,3=0.000000
L 1.69343337 3.53776673 1.69266683 3.53414892 1 P 0 ;0,1,2=116,3=0.000000
L 1.69266683 3.53414892 1.6907499 3.53156614 1 P 0 ;0,1,2=116,3=0.000000
L 1.6907499 3.53156614 1.68768317 3.53001654 1 P 0 ;0,1,2=116,3=0.000000
L 1.68768317 3.53001654 1.68500039 3.5295 1 P 0 ;0,1,2=116,3=0.000000
L 1.69343337 3.33914892 1.69113386 3.33656614 1 P 0 ;0,1,2=111,3=0.000000
L 1.69113386 3.33656614 1.68845039 3.33501654 1 P 0 ;0,1,2=111,3=0.000000
L 1.68845039 3.33501654 1.68500039 3.3345 1 P 0 ;0,1,2=111,3=0.000000
L 1.68500039 3.3345 1.6815497 3.33553307 1 P 0 ;0,1,2=111,3=0.000000
L 1.6815497 3.33553307 1.67886693 3.33759931 1 P 0 ;0,1,2=111,3=0.000000
L 1.67886693 3.33759931 1.67695 3.34121614 1 P 0 ;0,1,2=111,3=0.000000
L 1.67695 3.34121614 1.67656673 3.34534951 1 P 0 ;0,1,2=111,3=0.000000
L 1.67656673 3.34534951 1.67733327 3.34948287 1 P 0 ;0,1,2=111,3=0.000000
L 1.67733327 3.34948287 1.6792502 3.35206663 1 P 0 ;0,1,2=111,3=0.000000
L 1.6792502 3.35206663 1.68193366 3.35413287 1 P 0 ;0,1,2=111,3=0.000000
L 1.68193366 3.35413287 1.68461644 3.35464941 1 P 0 ;0,1,2=111,3=0.000000
L 1.68461644 3.35464941 1.6872999 3.35413287 1 P 0 ;0,1,2=111,3=0.000000
L 1.6872999 3.35413287 1.6907499 3.35206663 1 P 0 ;0,1,2=111,3=0.000000
L 1.6907499 3.35206663 1.6896001 3.3655 1 P 0 ;0,1,2=111,3=0.000000
L 1.6896001 3.3655 1.6792502 3.3655 1 P 0 ;0,1,2=111,3=0.000000
L 0.53 3.06 0.53 3.0474 1 P 0 
L 0.53 3.0474 0.5905 3.0474 1 P 0 
L 0.5905 3.0474 0.5905 2.9326 1 P 0 
L 0.5905 2.9326 0.53 2.9326 1 P 0 
L 0.53 2.9326 0.53 2.92 1 P 0 
L 0.39 3.0474 0.39 3.06 1 P 0 
L 0.39 3.06 0.53 3.06 1 P 0 
L 0.3295 3.0474 0.39 3.0474 1 P 0 
L 0.53 2.92 0.39 2.92 1 P 0 
L 0.39 2.92 0.39 2.9326 1 P 0 
L 0.39 2.9326 0.3295 2.9326 1 P 0 
L 0.3295 2.9326 0.3295 3.0474 1 P 0 
S P 0
OB 0.6088 3.0748 I
OC 0.6088 3.0748 0.5938 3.0748 Y
OE
SE
L 0.6054 2.9445 0.6054 2.9755 1 P 0 ;0,1,2=112,3=0.000000
L 0.6054 2.9755 0.61958376 2.95328327 1 P 0 ;0,1,2=112,3=0.000000
L 0.61958376 2.95328327 0.60041634 2.95328327 1 P 0 ;0,1,2=112,3=0.000000
L 0.53393337 2.8955 0.53393337 2.87328327 1 P 0 ;0,1,2=117,3=0.000000
L 0.53393337 2.87328327 0.5324003 2.86863238 1 P 0 ;0,1,2=117,3=0.000000
L 0.5324003 2.86863238 0.52933366 2.86553307 1 P 0 ;0,1,2=117,3=0.000000
L 0.52933366 2.86553307 0.52550039 2.8645 1 P 0 ;0,1,2=117,3=0.000000
L 0.52550039 2.8645 0.52166644 2.86553307 1 P 0 ;0,1,2=117,3=0.000000
L 0.52166644 2.86553307 0.5185998 2.86863238 1 P 0 ;0,1,2=117,3=0.000000
L 0.5185998 2.86863238 0.51706673 2.87328327 1 P 0 ;0,1,2=117,3=0.000000
L 0.51706673 2.87328327 0.51706673 2.8955 1 P 0 ;0,1,2=117,3=0.000000
L 0.49450039 2.8645 0.49181693 2.86501654 1 P 0 ;0,1,2=117,3=0.000000
L 0.49181693 2.86501654 0.4887502 2.86656614 1 P 0 ;0,1,2=117,3=0.000000
L 0.4887502 2.86656614 0.48683327 2.86914892 1 P 0 ;0,1,2=117,3=0.000000
L 0.48683327 2.86914892 0.48606673 2.87276673 1 P 0 ;0,1,2=117,3=0.000000
L 0.48606673 2.87276673 0.48683327 2.87638268 1 P 0 ;0,1,2=117,3=0.000000
L 0.48683327 2.87638268 0.48913346 2.87948287 1 P 0 ;0,1,2=117,3=0.000000
L 0.48913346 2.87948287 0.49258346 2.88103356 1 P 0 ;0,1,2=117,3=0.000000
L 0.49258346 2.88103356 0.49641663 2.88103356 1 P 0 ;0,1,2=117,3=0.000000
L 0.49641663 2.88103356 0.49871683 2.88206663 1 P 0 ;0,1,2=117,3=0.000000
L 0.49871683 2.88206663 0.50063386 2.88464941 1 P 0 ;0,1,2=117,3=0.000000
L 0.50063386 2.88464941 0.5014003 2.88826624 1 P 0 ;0,1,2=117,3=0.000000
L 0.5014003 2.88826624 0.5002499 2.89188307 1 P 0 ;0,1,2=117,3=0.000000
L 0.5002499 2.89188307 0.49756713 2.89446683 1 P 0 ;0,1,2=117,3=0.000000
L 0.49756713 2.89446683 0.49450039 2.8955 1 P 0 ;0,1,2=117,3=0.000000
L 0.49450039 2.8955 0.49143366 2.89446683 1 P 0 ;0,1,2=117,3=0.000000
L 0.49143366 2.89446683 0.4887502 2.89188307 1 P 0 ;0,1,2=117,3=0.000000
L 0.4887502 2.89188307 0.4875998 2.88826624 1 P 0 ;0,1,2=117,3=0.000000
L 0.4875998 2.88826624 0.48836693 2.88464941 1 P 0 ;0,1,2=117,3=0.000000
L 0.48836693 2.88464941 0.49028327 2.88206663 1 P 0 ;0,1,2=117,3=0.000000
L 0.49028327 2.88206663 0.49258346 2.88103356 1 P 0 ;0,1,2=117,3=0.000000
L 0.49258346 2.88103356 0.49641663 2.88103356 1 P 0 ;0,1,2=117,3=0.000000
L 0.49641663 2.88103356 0.49986663 2.87948287 1 P 0 ;0,1,2=117,3=0.000000
L 0.49986663 2.87948287 0.50216683 2.87638268 1 P 0 ;0,1,2=117,3=0.000000
L 0.50216683 2.87638268 0.50293337 2.87276673 1 P 0 ;0,1,2=117,3=0.000000
L 0.50293337 2.87276673 0.50216683 2.86914892 1 P 0 ;0,1,2=117,3=0.000000
L 0.50216683 2.86914892 0.5002499 2.86656614 1 P 0 ;0,1,2=117,3=0.000000
L 0.5002499 2.86656614 0.49718317 2.86501654 1 P 0 ;0,1,2=117,3=0.000000
L 0.49718317 2.86501654 0.49450039 2.8645 1 P 0 ;0,1,2=117,3=0.000000
L 0.31000039 3.0295 0.30731693 3.03001654 1 P 0 ;0,1,2=116,3=0.000000
L 0.30731693 3.03001654 0.3042502 3.03156614 1 P 0 ;0,1,2=116,3=0.000000
L 0.3042502 3.03156614 0.30233327 3.03414892 1 P 0 ;0,1,2=116,3=0.000000
L 0.30233327 3.03414892 0.30156673 3.03776673 1 P 0 ;0,1,2=116,3=0.000000
L 0.30156673 3.03776673 0.30233327 3.04138268 1 P 0 ;0,1,2=116,3=0.000000
L 0.30233327 3.04138268 0.30463346 3.04448287 1 P 0 ;0,1,2=116,3=0.000000
L 0.30463346 3.04448287 0.30808346 3.04603356 1 P 0 ;0,1,2=116,3=0.000000
L 0.30808346 3.04603356 0.31191663 3.04603356 1 P 0 ;0,1,2=116,3=0.000000
L 0.31191663 3.04603356 0.31421683 3.04706663 1 P 0 ;0,1,2=116,3=0.000000
L 0.31421683 3.04706663 0.31613386 3.04964941 1 P 0 ;0,1,2=116,3=0.000000
L 0.31613386 3.04964941 0.3169003 3.05326624 1 P 0 ;0,1,2=116,3=0.000000
L 0.3169003 3.05326624 0.3157499 3.05688307 1 P 0 ;0,1,2=116,3=0.000000
L 0.3157499 3.05688307 0.31306713 3.05946683 1 P 0 ;0,1,2=116,3=0.000000
L 0.31306713 3.05946683 0.31000039 3.0605 1 P 0 ;0,1,2=116,3=0.000000
L 0.31000039 3.0605 0.30693366 3.05946683 1 P 0 ;0,1,2=116,3=0.000000
L 0.30693366 3.05946683 0.3042502 3.05688307 1 P 0 ;0,1,2=116,3=0.000000
L 0.3042502 3.05688307 0.3030998 3.05326624 1 P 0 ;0,1,2=116,3=0.000000
L 0.3030998 3.05326624 0.30386693 3.04964941 1 P 0 ;0,1,2=116,3=0.000000
L 0.30386693 3.04964941 0.30578327 3.04706663 1 P 0 ;0,1,2=116,3=0.000000
L 0.30578327 3.04706663 0.30808346 3.04603356 1 P 0 ;0,1,2=116,3=0.000000
L 0.30808346 3.04603356 0.31191663 3.04603356 1 P 0 ;0,1,2=116,3=0.000000
L 0.31191663 3.04603356 0.31536663 3.04448287 1 P 0 ;0,1,2=116,3=0.000000
L 0.31536663 3.04448287 0.31766683 3.04138268 1 P 0 ;0,1,2=116,3=0.000000
L 0.31766683 3.04138268 0.31843337 3.03776673 1 P 0 ;0,1,2=116,3=0.000000
L 0.31843337 3.03776673 0.31766683 3.03414892 1 P 0 ;0,1,2=116,3=0.000000
L 0.31766683 3.03414892 0.3157499 3.03156614 1 P 0 ;0,1,2=116,3=0.000000
L 0.3157499 3.03156614 0.31268317 3.03001654 1 P 0 ;0,1,2=116,3=0.000000
L 0.31268317 3.03001654 0.31000039 3.0295 1 P 0 ;0,1,2=116,3=0.000000
L 0.32343337 2.93914892 0.32113386 2.93656614 1 P 0 ;0,1,2=111,3=0.000000
L 0.32113386 2.93656614 0.31845039 2.93501654 1 P 0 ;0,1,2=111,3=0.000000
L 0.31845039 2.93501654 0.31500039 2.9345 1 P 0 ;0,1,2=111,3=0.000000
L 0.31500039 2.9345 0.3115497 2.93553307 1 P 0 ;0,1,2=111,3=0.000000
L 0.3115497 2.93553307 0.30886693 2.93759931 1 P 0 ;0,1,2=111,3=0.000000
L 0.30886693 2.93759931 0.30695 2.94121614 1 P 0 ;0,1,2=111,3=0.000000
L 0.30695 2.94121614 0.30656673 2.94534951 1 P 0 ;0,1,2=111,3=0.000000
L 0.30656673 2.94534951 0.30733327 2.94948287 1 P 0 ;0,1,2=111,3=0.000000
L 0.30733327 2.94948287 0.3092502 2.95206663 1 P 0 ;0,1,2=111,3=0.000000
L 0.3092502 2.95206663 0.31193366 2.95413287 1 P 0 ;0,1,2=111,3=0.000000
L 0.31193366 2.95413287 0.31461644 2.95464941 1 P 0 ;0,1,2=111,3=0.000000
L 0.31461644 2.95464941 0.3172999 2.95413287 1 P 0 ;0,1,2=111,3=0.000000
L 0.3172999 2.95413287 0.3207499 2.95206663 1 P 0 ;0,1,2=111,3=0.000000
L 0.3207499 2.95206663 0.3196001 2.9655 1 P 0 ;0,1,2=111,3=0.000000
L 0.3196001 2.9655 0.3092502 2.9655 1 P 0 ;0,1,2=111,3=0.000000
L 1.545 2.978 1.455 2.978 1 P 0 
L 1.455 2.978 1.455 3.022 1 P 0 
L 1.455 3.022 1.545 3.022 1 P 0 
L 1.545 3.022 1.545 2.978 1 P 0 
L 1.53416683 3.0295 1.53416683 3.0605 1 P 0 ;0,1,2=118,3=0.000000
L 1.53416683 3.0605 1.52458346 3.0605 1 P 0 ;0,1,2=118,3=0.000000
L 1.52458346 3.0605 1.52151673 3.05894931 1 P 0 ;0,1,2=118,3=0.000000
L 1.52151673 3.05894931 1.5195998 3.05688307 1 P 0 ;0,1,2=118,3=0.000000
L 1.5195998 3.05688307 1.51883327 3.0527497 1 P 0 ;0,1,2=118,3=0.000000
L 1.51883327 3.0527497 1.5195998 3.04861634 1 P 0 ;0,1,2=118,3=0.000000
L 1.5195998 3.04861634 1.5219 3.04603356 1 P 0 ;0,1,2=118,3=0.000000
L 1.5219 3.04603356 1.52458346 3.04448287 1 P 0 ;0,1,2=118,3=0.000000
L 1.52458346 3.04448287 1.53416683 3.04448287 1 P 0 ;0,1,2=118,3=0.000000
L 1.52458346 3.04448287 1.51883327 3.0295 1 P 0 ;0,1,2=118,3=0.000000
L 1.4909 3.0295 1.4909 3.0605 1 P 0 ;0,1,2=118,3=0.000000
L 1.4909 3.0605 1.50508376 3.03828327 1 P 0 ;0,1,2=118,3=0.000000
L 1.50508376 3.03828327 1.48591634 3.03828327 1 P 0 ;0,1,2=118,3=0.000000
L 1.47101713 3.03311585 1.46833366 3.03053307 1 P 0 ;0,1,2=118,3=0.000000
L 1.46833366 3.03053307 1.46526693 3.0295 1 P 0 ;0,1,2=118,3=0.000000
L 1.46526693 3.0295 1.4622002 3.03053307 1 P 0 ;0,1,2=118,3=0.000000
L 1.4622002 3.03053307 1.45951673 3.03363238 1 P 0 ;0,1,2=118,3=0.000000
L 1.45951673 3.03363238 1.4575998 3.03828327 1 P 0 ;0,1,2=118,3=0.000000
L 1.4575998 3.03828327 1.45683327 3.04293327 1 P 0 ;0,1,2=118,3=0.000000
L 1.45683327 3.04293327 1.45683327 3.04861634 1 P 0 ;0,1,2=118,3=0.000000
L 1.45683327 3.04861634 1.4575998 3.05326624 1 P 0 ;0,1,2=118,3=0.000000
L 1.4575998 3.05326624 1.45951673 3.0573997 1 P 0 ;0,1,2=118,3=0.000000
L 1.45951673 3.0573997 1.46181693 3.05946683 1 P 0 ;0,1,2=118,3=0.000000
L 1.46181693 3.05946683 1.46450039 3.0605 1 P 0 ;0,1,2=118,3=0.000000
L 1.46450039 3.0605 1.46756713 3.05946683 1 P 0 ;0,1,2=118,3=0.000000
L 1.46756713 3.05946683 1.46986663 3.0573997 1 P 0 ;0,1,2=118,3=0.000000
L 1.46986663 3.0573997 1.4714003 3.0543003 1 P 0 ;0,1,2=118,3=0.000000
L 1.4714003 3.0543003 1.47216683 3.05016594 1 P 0 ;0,1,2=118,3=0.000000
L 1.47216683 3.05016594 1.4714003 3.0465501 1 P 0 ;0,1,2=118,3=0.000000
L 1.4714003 3.0465501 1.46948337 3.04293327 1 P 0 ;0,1,2=118,3=0.000000
L 1.46948337 3.04293327 1.46718317 3.04086604 1 P 0 ;0,1,2=118,3=0.000000
L 1.46718317 3.04086604 1.46450039 3.04034951 1 P 0 ;0,1,2=118,3=0.000000
L 1.46450039 3.04034951 1.46143366 3.04138268 1 P 0 ;0,1,2=118,3=0.000000
L 1.46143366 3.04138268 1.45913346 3.04396634 1 P 0 ;0,1,2=118,3=0.000000
L 1.45913346 3.04396634 1.45683327 3.04861634 1 P 0 ;0,1,2=118,3=0.000000
L 1.43350039 3.0295 1.43350039 3.0605 1 P 0 ;0,1,2=118,3=0.000000
L 1.43350039 3.0605 1.4381001 3.0543003 1 P 0 ;0,1,2=118,3=0.000000
L 1.4381001 3.0295 1.42890069 3.0295 1 P 0 ;0,1,2=118,3=0.000000
L 1.501 4.12 1.411 4.12 1 P 0 
L 1.411 4.12 1.411 4.164 1 P 0 
L 1.411 4.164 1.501 4.164 1 P 0 
L 1.501 4.164 1.501 4.12 1 P 0 
L 1.38366683 4.155 1.38366683 4.186 1 P 0 ;0,1,2=119,3=0.000000
L 1.38366683 4.186 1.37408346 4.186 1 P 0 ;0,1,2=119,3=0.000000
L 1.37408346 4.186 1.37101673 4.18444931 1 P 0 ;0,1,2=119,3=0.000000
L 1.37101673 4.18444931 1.3690998 4.18238307 1 P 0 ;0,1,2=119,3=0.000000
L 1.3690998 4.18238307 1.36833327 4.1782497 1 P 0 ;0,1,2=119,3=0.000000
L 1.36833327 4.1782497 1.3690998 4.17411634 1 P 0 ;0,1,2=119,3=0.000000
L 1.3690998 4.17411634 1.3714 4.17153356 1 P 0 ;0,1,2=119,3=0.000000
L 1.3714 4.17153356 1.37408346 4.16998287 1 P 0 ;0,1,2=119,3=0.000000
L 1.37408346 4.16998287 1.38366683 4.16998287 1 P 0 ;0,1,2=119,3=0.000000
L 1.37408346 4.16998287 1.36833327 4.155 1 P 0 ;0,1,2=119,3=0.000000
L 1.35343337 4.16119961 1.35113386 4.15758278 1 P 0 ;0,1,2=119,3=0.000000
L 1.35113386 4.15758278 1.34806713 4.15551654 1 P 0 ;0,1,2=119,3=0.000000
L 1.34806713 4.15551654 1.34461644 4.155 1 P 0 ;0,1,2=119,3=0.000000
L 1.34461644 4.155 1.3415497 4.15551654 1 P 0 ;0,1,2=119,3=0.000000
L 1.3415497 4.15551654 1.33848297 4.15809931 1 P 0 ;0,1,2=119,3=0.000000
L 1.33848297 4.15809931 1.33656673 4.16119961 1 P 0 ;0,1,2=119,3=0.000000
L 1.33656673 4.16119961 1.33618346 4.1642999 1 P 0 ;0,1,2=119,3=0.000000
L 1.33618346 4.1642999 1.33695 4.16791575 1 P 0 ;0,1,2=119,3=0.000000
L 1.33695 4.16791575 1.33963346 4.17049951 1 P 0 ;0,1,2=119,3=0.000000
L 1.33963346 4.17049951 1.34231693 4.17153356 1 P 0 ;0,1,2=119,3=0.000000
L 1.34231693 4.17153356 1.34576693 4.17153356 1 P 0 ;0,1,2=119,3=0.000000
L 1.34231693 4.17153356 1.34001673 4.17308317 1 P 0 ;0,1,2=119,3=0.000000
L 1.34001673 4.17308317 1.3380998 4.17566594 1 P 0 ;0,1,2=119,3=0.000000
L 1.3380998 4.17566594 1.33733327 4.17876624 1 P 0 ;0,1,2=119,3=0.000000
L 1.33733327 4.17876624 1.3380998 4.18186654 1 P 0 ;0,1,2=119,3=0.000000
L 1.3380998 4.18186654 1.34001673 4.18444931 1 P 0 ;0,1,2=119,3=0.000000
L 1.34001673 4.18444931 1.34346673 4.186 1 P 0 ;0,1,2=119,3=0.000000
L 1.34346673 4.186 1.34691663 4.18548337 1 P 0 ;0,1,2=119,3=0.000000
L 1.34691663 4.18548337 1.35036663 4.18341624 1 P 0 ;0,1,2=119,3=0.000000
L 1.32128356 4.18083346 1.31898337 4.18393278 1 P 0 ;0,1,2=119,3=0.000000
L 1.31898337 4.18393278 1.3162999 4.18548337 1 P 0 ;0,1,2=119,3=0.000000
L 1.3162999 4.18548337 1.31323317 4.186 1 P 0 ;0,1,2=119,3=0.000000
L 1.31323317 4.186 1.3094 4.18496683 1 P 0 ;0,1,2=119,3=0.000000
L 1.3094 4.18496683 1.30671654 4.18238307 1 P 0 ;0,1,2=119,3=0.000000
L 1.30671654 4.18238307 1.30595 4.17928376 1 P 0 ;0,1,2=119,3=0.000000
L 1.30595 4.17928376 1.30633327 4.17618258 1 P 0 ;0,1,2=119,3=0.000000
L 1.30633327 4.17618258 1.30786693 4.1735998 1 P 0 ;0,1,2=119,3=0.000000
L 1.30786693 4.1735998 1.31553337 4.16843327 1 P 0 ;0,1,2=119,3=0.000000
L 1.31553337 4.16843327 1.31898337 4.16481644 1 P 0 ;0,1,2=119,3=0.000000
L 1.31898337 4.16481644 1.32128356 4.15964892 1 P 0 ;0,1,2=119,3=0.000000
L 1.32128356 4.15964892 1.3220501 4.155 1 P 0 ;0,1,2=119,3=0.000000
L 1.3220501 4.155 1.30595 4.155 1 P 0 ;0,1,2=119,3=0.000000
L 5.256 2.677 5.3 2.677 1 P 0 
L 5.256 2.587 5.256 2.677 1 P 0 
L 5.3 2.677 5.3 2.587 1 P 0 
L 5.3 2.587 5.256 2.587 1 P 0 
L 5.1895 2.57583317 5.2205 2.57583317 1 P 0 ;0,1,2=120,3=90.000000
L 5.2205 2.57583317 5.2205 2.58541654 1 P 0 ;0,1,2=120,3=90.000000
L 5.2205 2.58541654 5.21894931 2.58848327 1 P 0 ;0,1,2=120,3=90.000000
L 5.21894931 2.58848327 5.21688307 2.5904002 1 P 0 ;0,1,2=120,3=90.000000
L 5.21688307 2.5904002 5.2127497 2.59116673 1 P 0 ;0,1,2=120,3=90.000000
L 5.2127497 2.59116673 5.20861634 2.5904002 1 P 0 ;0,1,2=120,3=90.000000
L 5.20861634 2.5904002 5.20603356 2.5881 1 P 0 ;0,1,2=120,3=90.000000
L 5.20603356 2.5881 5.20448287 2.58541654 1 P 0 ;0,1,2=120,3=90.000000
L 5.20448287 2.58541654 5.20448287 2.57583317 1 P 0 ;0,1,2=120,3=90.000000
L 5.20448287 2.58541654 5.1895 2.59116673 1 P 0 ;0,1,2=120,3=90.000000
L 5.1895 2.61449961 5.2205 2.61449961 1 P 0 ;0,1,2=120,3=90.000000
L 5.2205 2.61449961 5.2143003 2.6098999 1 P 0 ;0,1,2=120,3=90.000000
L 5.1895 2.6098999 5.1895 2.61909931 1 P 0 ;0,1,2=120,3=90.000000
L 5.1895 2.64549961 5.19001654 2.64818307 1 P 0 ;0,1,2=120,3=90.000000
L 5.19001654 2.64818307 5.19156614 2.6512498 1 P 0 ;0,1,2=120,3=90.000000
L 5.19156614 2.6512498 5.19414892 2.65316673 1 P 0 ;0,1,2=120,3=90.000000
L 5.19414892 2.65316673 5.19776673 2.65393327 1 P 0 ;0,1,2=120,3=90.000000
L 5.19776673 2.65393327 5.20138268 2.65316673 1 P 0 ;0,1,2=120,3=90.000000
L 5.20138268 2.65316673 5.20448287 2.65086654 1 P 0 ;0,1,2=120,3=90.000000
L 5.20448287 2.65086654 5.20603356 2.64741654 1 P 0 ;0,1,2=120,3=90.000000
L 5.20603356 2.64741654 5.20603356 2.64358337 1 P 0 ;0,1,2=120,3=90.000000
L 5.20603356 2.64358337 5.20706663 2.64128317 1 P 0 ;0,1,2=120,3=90.000000
L 5.20706663 2.64128317 5.20964941 2.63936614 1 P 0 ;0,1,2=120,3=90.000000
L 5.20964941 2.63936614 5.21326624 2.6385997 1 P 0 ;0,1,2=120,3=90.000000
L 5.21326624 2.6385997 5.21688307 2.6397501 1 P 0 ;0,1,2=120,3=90.000000
L 5.21688307 2.6397501 5.21946683 2.64243287 1 P 0 ;0,1,2=120,3=90.000000
L 5.21946683 2.64243287 5.2205 2.64549961 1 P 0 ;0,1,2=120,3=90.000000
L 5.2205 2.64549961 5.21946683 2.64856634 1 P 0 ;0,1,2=120,3=90.000000
L 5.21946683 2.64856634 5.21688307 2.6512498 1 P 0 ;0,1,2=120,3=90.000000
L 5.21688307 2.6512498 5.21326624 2.6524002 1 P 0 ;0,1,2=120,3=90.000000
L 5.21326624 2.6524002 5.20964941 2.65163307 1 P 0 ;0,1,2=120,3=90.000000
L 5.20964941 2.65163307 5.20706663 2.64971673 1 P 0 ;0,1,2=120,3=90.000000
L 5.20706663 2.64971673 5.20603356 2.64741654 1 P 0 ;0,1,2=120,3=90.000000
L 5.20603356 2.64741654 5.20603356 2.64358337 1 P 0 ;0,1,2=120,3=90.000000
L 5.20603356 2.64358337 5.20448287 2.64013337 1 P 0 ;0,1,2=120,3=90.000000
L 5.20448287 2.64013337 5.20138268 2.63783317 1 P 0 ;0,1,2=120,3=90.000000
L 5.20138268 2.63783317 5.19776673 2.63706663 1 P 0 ;0,1,2=120,3=90.000000
L 5.19776673 2.63706663 5.19414892 2.63783317 1 P 0 ;0,1,2=120,3=90.000000
L 5.19414892 2.63783317 5.19156614 2.6397501 1 P 0 ;0,1,2=120,3=90.000000
L 5.19156614 2.6397501 5.19001654 2.64281683 1 P 0 ;0,1,2=120,3=90.000000
L 5.19001654 2.64281683 5.1895 2.64549961 1 P 0 ;0,1,2=120,3=90.000000
L 5.1895 2.67649961 5.19001654 2.67918307 1 P 0 ;0,1,2=120,3=90.000000
L 5.19001654 2.67918307 5.19156614 2.6822498 1 P 0 ;0,1,2=120,3=90.000000
L 5.19156614 2.6822498 5.19414892 2.68416673 1 P 0 ;0,1,2=120,3=90.000000
L 5.19414892 2.68416673 5.19776673 2.68493327 1 P 0 ;0,1,2=120,3=90.000000
L 5.19776673 2.68493327 5.20138268 2.68416673 1 P 0 ;0,1,2=120,3=90.000000
L 5.20138268 2.68416673 5.20448287 2.68186654 1 P 0 ;0,1,2=120,3=90.000000
L 5.20448287 2.68186654 5.20603356 2.67841654 1 P 0 ;0,1,2=120,3=90.000000
L 5.20603356 2.67841654 5.20603356 2.67458337 1 P 0 ;0,1,2=120,3=90.000000
L 5.20603356 2.67458337 5.20706663 2.67228317 1 P 0 ;0,1,2=120,3=90.000000
L 5.20706663 2.67228317 5.20964941 2.67036614 1 P 0 ;0,1,2=120,3=90.000000
L 5.20964941 2.67036614 5.21326624 2.6695997 1 P 0 ;0,1,2=120,3=90.000000
L 5.21326624 2.6695997 5.21688307 2.6707501 1 P 0 ;0,1,2=120,3=90.000000
L 5.21688307 2.6707501 5.21946683 2.67343287 1 P 0 ;0,1,2=120,3=90.000000
L 5.21946683 2.67343287 5.2205 2.67649961 1 P 0 ;0,1,2=120,3=90.000000
L 5.2205 2.67649961 5.21946683 2.67956634 1 P 0 ;0,1,2=120,3=90.000000
L 5.21946683 2.67956634 5.21688307 2.6822498 1 P 0 ;0,1,2=120,3=90.000000
L 5.21688307 2.6822498 5.21326624 2.6834002 1 P 0 ;0,1,2=120,3=90.000000
L 5.21326624 2.6834002 5.20964941 2.68263307 1 P 0 ;0,1,2=120,3=90.000000
L 5.20964941 2.68263307 5.20706663 2.68071673 1 P 0 ;0,1,2=120,3=90.000000
L 5.20706663 2.68071673 5.20603356 2.67841654 1 P 0 ;0,1,2=120,3=90.000000
L 5.20603356 2.67841654 5.20603356 2.67458337 1 P 0 ;0,1,2=120,3=90.000000
L 5.20603356 2.67458337 5.20448287 2.67113337 1 P 0 ;0,1,2=120,3=90.000000
L 5.20448287 2.67113337 5.20138268 2.66883317 1 P 0 ;0,1,2=120,3=90.000000
L 5.20138268 2.66883317 5.19776673 2.66806663 1 P 0 ;0,1,2=120,3=90.000000
L 5.19776673 2.66806663 5.19414892 2.66883317 1 P 0 ;0,1,2=120,3=90.000000
L 5.19414892 2.66883317 5.19156614 2.6707501 1 P 0 ;0,1,2=120,3=90.000000
L 5.19156614 2.6707501 5.19001654 2.67381683 1 P 0 ;0,1,2=120,3=90.000000
L 5.19001654 2.67381683 5.1895 2.67649961 1 P 0 ;0,1,2=120,3=90.000000
L 1.497 4.118 1.393 4.118 1 P 0 
L 1.393 4.062 1.497 4.062 1 P 0 
L 1.497 4.062 1.497 4.118 1 P 0 
L 1.393 4.118 1.393 4.062 1 P 0 
L 1.32366683 4.0695 1.32366683 4.1005 1 P 0 ;0,1,2=121,3=0.000000
L 1.32366683 4.1005 1.31408346 4.1005 1 P 0 ;0,1,2=121,3=0.000000
L 1.31408346 4.1005 1.31101673 4.09894931 1 P 0 ;0,1,2=121,3=0.000000
L 1.31101673 4.09894931 1.3090998 4.09688307 1 P 0 ;0,1,2=121,3=0.000000
L 1.3090998 4.09688307 1.30833327 4.0927497 1 P 0 ;0,1,2=121,3=0.000000
L 1.30833327 4.0927497 1.3090998 4.08861634 1 P 0 ;0,1,2=121,3=0.000000
L 1.3090998 4.08861634 1.3114 4.08603356 1 P 0 ;0,1,2=121,3=0.000000
L 1.3114 4.08603356 1.31408346 4.08448287 1 P 0 ;0,1,2=121,3=0.000000
L 1.31408346 4.08448287 1.32366683 4.08448287 1 P 0 ;0,1,2=121,3=0.000000
L 1.31408346 4.08448287 1.30833327 4.0695 1 P 0 ;0,1,2=121,3=0.000000
L 1.29343337 4.07414892 1.29113386 4.07156614 1 P 0 ;0,1,2=121,3=0.000000
L 1.29113386 4.07156614 1.28845039 4.07001654 1 P 0 ;0,1,2=121,3=0.000000
L 1.28845039 4.07001654 1.28500039 4.0695 1 P 0 ;0,1,2=121,3=0.000000
L 1.28500039 4.0695 1.2815497 4.07053307 1 P 0 ;0,1,2=121,3=0.000000
L 1.2815497 4.07053307 1.27886693 4.07259931 1 P 0 ;0,1,2=121,3=0.000000
L 1.27886693 4.07259931 1.27695 4.07621614 1 P 0 ;0,1,2=121,3=0.000000
L 1.27695 4.07621614 1.27656673 4.08034951 1 P 0 ;0,1,2=121,3=0.000000
L 1.27656673 4.08034951 1.27733327 4.08448287 1 P 0 ;0,1,2=121,3=0.000000
L 1.27733327 4.08448287 1.2792502 4.08706663 1 P 0 ;0,1,2=121,3=0.000000
L 1.2792502 4.08706663 1.28193366 4.08913287 1 P 0 ;0,1,2=121,3=0.000000
L 1.28193366 4.08913287 1.28461644 4.08964941 1 P 0 ;0,1,2=121,3=0.000000
L 1.28461644 4.08964941 1.2872999 4.08913287 1 P 0 ;0,1,2=121,3=0.000000
L 1.2872999 4.08913287 1.2907499 4.08706663 1 P 0 ;0,1,2=121,3=0.000000
L 1.2907499 4.08706663 1.2896001 4.1005 1 P 0 ;0,1,2=121,3=0.000000
L 1.2896001 4.1005 1.2792502 4.1005 1 P 0 ;0,1,2=121,3=0.000000
L 1.25400039 4.1005 1.25706713 4.09946683 1 P 0 ;0,1,2=121,3=0.000000
L 1.25706713 4.09946683 1.25936663 4.09688307 1 P 0 ;0,1,2=121,3=0.000000
L 1.25936663 4.09688307 1.2609003 4.09378376 1 P 0 ;0,1,2=121,3=0.000000
L 1.2609003 4.09378376 1.2620501 4.08964941 1 P 0 ;0,1,2=121,3=0.000000
L 1.2620501 4.08964941 1.26243337 4.08499951 1 P 0 ;0,1,2=121,3=0.000000
L 1.26243337 4.08499951 1.2620501 4.08034951 1 P 0 ;0,1,2=121,3=0.000000
L 1.2620501 4.08034951 1.2609003 4.07621614 1 P 0 ;0,1,2=121,3=0.000000
L 1.2609003 4.07621614 1.25936663 4.07311585 1 P 0 ;0,1,2=121,3=0.000000
L 1.25936663 4.07311585 1.25706713 4.07053307 1 P 0 ;0,1,2=121,3=0.000000
L 1.25706713 4.07053307 1.25400039 4.0695 1 P 0 ;0,1,2=121,3=0.000000
L 1.25400039 4.0695 1.25093366 4.07053307 1 P 0 ;0,1,2=121,3=0.000000
L 1.25093366 4.07053307 1.24863346 4.07311585 1 P 0 ;0,1,2=121,3=0.000000
L 1.24863346 4.07311585 1.2470998 4.07621614 1 P 0 ;0,1,2=121,3=0.000000
L 1.2470998 4.07621614 1.24595 4.08034951 1 P 0 ;0,1,2=121,3=0.000000
L 1.24595 4.08034951 1.24556673 4.08499951 1 P 0 ;0,1,2=121,3=0.000000
L 1.24556673 4.08499951 1.24595 4.08964941 1 P 0 ;0,1,2=121,3=0.000000
L 1.24595 4.08964941 1.2470998 4.09378376 1 P 0 ;0,1,2=121,3=0.000000
L 1.2470998 4.09378376 1.24863346 4.09688307 1 P 0 ;0,1,2=121,3=0.000000
L 1.24863346 4.09688307 1.25093366 4.09946683 1 P 0 ;0,1,2=121,3=0.000000
L 1.25093366 4.09946683 1.25400039 4.1005 1 P 0 ;0,1,2=121,3=0.000000
L 2.873 2.247 2.817 2.247 1 P 0 
L 2.817 2.247 2.817 2.143 1 P 0 
L 2.817 2.143 2.873 2.143 1 P 0 
L 2.873 2.143 2.873 2.247 1 P 0 
L 2.8345 2.06171644 2.8655 2.06171644 1 P 0 ;0,1,2=122,3=90.000000
L 2.8655 2.06171644 2.8655 2.07628346 1 P 0 ;0,1,2=122,3=90.000000
L 2.85051703 2.07091654 2.85051703 2.06171644 1 P 0 ;0,1,2=122,3=90.000000
L 2.8655 2.09156663 2.84328327 2.09156663 1 P 0 ;0,1,2=122,3=90.000000
L 2.84328327 2.09156663 2.83863238 2.0930997 1 P 0 ;0,1,2=122,3=90.000000
L 2.83863238 2.0930997 2.83553307 2.09616634 1 P 0 ;0,1,2=122,3=90.000000
L 2.83553307 2.09616634 2.8345 2.09999961 1 P 0 ;0,1,2=122,3=90.000000
L 2.8345 2.09999961 2.83553307 2.10383356 1 P 0 ;0,1,2=122,3=90.000000
L 2.83553307 2.10383356 2.83863238 2.1069002 1 P 0 ;0,1,2=122,3=90.000000
L 2.83863238 2.1069002 2.84328327 2.10843327 1 P 0 ;0,1,2=122,3=90.000000
L 2.84328327 2.10843327 2.8655 2.10843327 1 P 0 ;0,1,2=122,3=90.000000
L 2.84069961 2.12256663 2.83708278 2.12486614 1 P 0 ;0,1,2=122,3=90.000000
L 2.83708278 2.12486614 2.83501654 2.12793287 1 P 0 ;0,1,2=122,3=90.000000
L 2.83501654 2.12793287 2.8345 2.13138356 1 P 0 ;0,1,2=122,3=90.000000
L 2.8345 2.13138356 2.83501654 2.1344503 1 P 0 ;0,1,2=122,3=90.000000
L 2.83501654 2.1344503 2.83759931 2.13751703 1 P 0 ;0,1,2=122,3=90.000000
L 2.83759931 2.13751703 2.84069961 2.13943327 1 P 0 ;0,1,2=122,3=90.000000
L 2.84069961 2.13943327 2.8437999 2.13981654 1 P 0 ;0,1,2=122,3=90.000000
L 2.8437999 2.13981654 2.84741575 2.13905 1 P 0 ;0,1,2=122,3=90.000000
L 2.84741575 2.13905 2.84999951 2.13636654 1 P 0 ;0,1,2=122,3=90.000000
L 2.84999951 2.13636654 2.85103356 2.13368307 1 P 0 ;0,1,2=122,3=90.000000
L 2.85103356 2.13368307 2.85103356 2.13023307 1 P 0 ;0,1,2=122,3=90.000000
L 2.85103356 2.13368307 2.85258317 2.13598327 1 P 0 ;0,1,2=122,3=90.000000
L 2.85258317 2.13598327 2.85516594 2.1379002 1 P 0 ;0,1,2=122,3=90.000000
L 2.85516594 2.1379002 2.85826624 2.13866673 1 P 0 ;0,1,2=122,3=90.000000
L 2.85826624 2.13866673 2.86136654 2.1379002 1 P 0 ;0,1,2=122,3=90.000000
L 2.86136654 2.1379002 2.86394931 2.13598327 1 P 0 ;0,1,2=122,3=90.000000
L 2.86394931 2.13598327 2.8655 2.13253327 1 P 0 ;0,1,2=122,3=90.000000
L 2.8655 2.13253327 2.86498337 2.12908337 1 P 0 ;0,1,2=122,3=90.000000
L 2.86498337 2.12908337 2.86291624 2.12563337 1 P 0 ;0,1,2=122,3=90.000000
L 3.595 3.915 3.491 3.915 1 P 0 
L 3.491 3.915 3.491 3.859 1 P 0 
L 3.491 3.859 3.595 3.859 1 P 0 
L 3.595 3.859 3.595 3.915 1 P 0 
L 3.72666683 3.8715 3.72666683 3.9025 1 P 0 ;0,1,2=123,3=0.000000
L 3.72666683 3.9025 3.71708346 3.9025 1 P 0 ;0,1,2=123,3=0.000000
L 3.71708346 3.9025 3.71401673 3.90094931 1 P 0 ;0,1,2=123,3=0.000000
L 3.71401673 3.90094931 3.7120998 3.89888307 1 P 0 ;0,1,2=123,3=0.000000
L 3.7120998 3.89888307 3.71133327 3.8947497 1 P 0 ;0,1,2=123,3=0.000000
L 3.71133327 3.8947497 3.7120998 3.89061634 1 P 0 ;0,1,2=123,3=0.000000
L 3.7120998 3.89061634 3.7144 3.88803356 1 P 0 ;0,1,2=123,3=0.000000
L 3.7144 3.88803356 3.71708346 3.88648287 1 P 0 ;0,1,2=123,3=0.000000
L 3.71708346 3.88648287 3.72666683 3.88648287 1 P 0 ;0,1,2=123,3=0.000000
L 3.71708346 3.88648287 3.71133327 3.8715 1 P 0 ;0,1,2=123,3=0.000000
L 3.69643337 3.87614892 3.69413386 3.87356614 1 P 0 ;0,1,2=123,3=0.000000
L 3.69413386 3.87356614 3.69145039 3.87201654 1 P 0 ;0,1,2=123,3=0.000000
L 3.69145039 3.87201654 3.68800039 3.8715 1 P 0 ;0,1,2=123,3=0.000000
L 3.68800039 3.8715 3.6845497 3.87253307 1 P 0 ;0,1,2=123,3=0.000000
L 3.6845497 3.87253307 3.68186693 3.87459931 1 P 0 ;0,1,2=123,3=0.000000
L 3.68186693 3.87459931 3.67995 3.87821614 1 P 0 ;0,1,2=123,3=0.000000
L 3.67995 3.87821614 3.67956673 3.88234951 1 P 0 ;0,1,2=123,3=0.000000
L 3.67956673 3.88234951 3.68033327 3.88648287 1 P 0 ;0,1,2=123,3=0.000000
L 3.68033327 3.88648287 3.6822502 3.88906663 1 P 0 ;0,1,2=123,3=0.000000
L 3.6822502 3.88906663 3.68493366 3.89113287 1 P 0 ;0,1,2=123,3=0.000000
L 3.68493366 3.89113287 3.68761644 3.89164941 1 P 0 ;0,1,2=123,3=0.000000
L 3.68761644 3.89164941 3.6902999 3.89113287 1 P 0 ;0,1,2=123,3=0.000000
L 3.6902999 3.89113287 3.6937499 3.88906663 1 P 0 ;0,1,2=123,3=0.000000
L 3.6937499 3.88906663 3.6926001 3.9025 1 P 0 ;0,1,2=123,3=0.000000
L 3.6926001 3.9025 3.6822502 3.9025 1 P 0 ;0,1,2=123,3=0.000000
L 3.6524 3.8715 3.6524 3.9025 1 P 0 ;0,1,2=123,3=0.000000
L 3.6524 3.9025 3.66658376 3.88028327 1 P 0 ;0,1,2=123,3=0.000000
L 3.66658376 3.88028327 3.64741634 3.88028327 1 P 0 ;0,1,2=123,3=0.000000
L 5.728 2.397 5.672 2.397 1 P 0 
L 5.672 2.397 5.672 2.293 1 P 0 
L 5.672 2.293 5.728 2.293 1 P 0 
L 5.728 2.293 5.728 2.397 1 P 0 
L 5.8095 2.32583317 5.8405 2.32583317 1 P 0 ;0,1,2=124,3=90.000000
L 5.8405 2.32583317 5.8405 2.33541654 1 P 0 ;0,1,2=124,3=90.000000
L 5.8405 2.33541654 5.83894931 2.33848327 1 P 0 ;0,1,2=124,3=90.000000
L 5.83894931 2.33848327 5.83688307 2.3404002 1 P 0 ;0,1,2=124,3=90.000000
L 5.83688307 2.3404002 5.8327497 2.34116673 1 P 0 ;0,1,2=124,3=90.000000
L 5.8327497 2.34116673 5.82861634 2.3404002 1 P 0 ;0,1,2=124,3=90.000000
L 5.82861634 2.3404002 5.82603356 2.3381 1 P 0 ;0,1,2=124,3=90.000000
L 5.82603356 2.3381 5.82448287 2.33541654 1 P 0 ;0,1,2=124,3=90.000000
L 5.82448287 2.33541654 5.82448287 2.32583317 1 P 0 ;0,1,2=124,3=90.000000
L 5.82448287 2.33541654 5.8095 2.34116673 1 P 0 ;0,1,2=124,3=90.000000
L 5.83533346 2.35721644 5.83843278 2.35951663 1 P 0 ;0,1,2=124,3=90.000000
L 5.83843278 2.35951663 5.83998337 2.3622001 1 P 0 ;0,1,2=124,3=90.000000
L 5.83998337 2.3622001 5.8405 2.36526683 1 P 0 ;0,1,2=124,3=90.000000
L 5.8405 2.36526683 5.83946683 2.3691 1 P 0 ;0,1,2=124,3=90.000000
L 5.83946683 2.3691 5.83688307 2.37178346 1 P 0 ;0,1,2=124,3=90.000000
L 5.83688307 2.37178346 5.83378376 2.37255 1 P 0 ;0,1,2=124,3=90.000000
L 5.83378376 2.37255 5.83068258 2.37216673 1 P 0 ;0,1,2=124,3=90.000000
L 5.83068258 2.37216673 5.8280998 2.37063307 1 P 0 ;0,1,2=124,3=90.000000
L 5.8280998 2.37063307 5.82293327 2.36296663 1 P 0 ;0,1,2=124,3=90.000000
L 5.82293327 2.36296663 5.81931644 2.35951663 1 P 0 ;0,1,2=124,3=90.000000
L 5.81931644 2.35951663 5.81414892 2.35721644 1 P 0 ;0,1,2=124,3=90.000000
L 5.81414892 2.35721644 5.8095 2.3564499 1 P 0 ;0,1,2=124,3=90.000000
L 5.8095 2.3564499 5.8095 2.37255 1 P 0 ;0,1,2=124,3=90.000000
L 5.81414892 2.38706663 5.81156614 2.38936614 1 P 0 ;0,1,2=124,3=90.000000
L 5.81156614 2.38936614 5.81001654 2.39204961 1 P 0 ;0,1,2=124,3=90.000000
L 5.81001654 2.39204961 5.8095 2.39549961 1 P 0 ;0,1,2=124,3=90.000000
L 5.8095 2.39549961 5.81053307 2.3989503 1 P 0 ;0,1,2=124,3=90.000000
L 5.81053307 2.3989503 5.81259931 2.40163307 1 P 0 ;0,1,2=124,3=90.000000
L 5.81259931 2.40163307 5.81621614 2.40355 1 P 0 ;0,1,2=124,3=90.000000
L 5.81621614 2.40355 5.82034951 2.40393327 1 P 0 ;0,1,2=124,3=90.000000
L 5.82034951 2.40393327 5.82448287 2.40316673 1 P 0 ;0,1,2=124,3=90.000000
L 5.82448287 2.40316673 5.82706663 2.4012498 1 P 0 ;0,1,2=124,3=90.000000
L 5.82706663 2.4012498 5.82913287 2.39856634 1 P 0 ;0,1,2=124,3=90.000000
L 5.82913287 2.39856634 5.82964941 2.39588356 1 P 0 ;0,1,2=124,3=90.000000
L 5.82964941 2.39588356 5.82913287 2.3932001 1 P 0 ;0,1,2=124,3=90.000000
L 5.82913287 2.3932001 5.82706663 2.3897501 1 P 0 ;0,1,2=124,3=90.000000
L 5.82706663 2.3897501 5.8405 2.3908999 1 P 0 ;0,1,2=124,3=90.000000
L 5.8405 2.3908999 5.8405 2.4012498 1 P 0 ;0,1,2=124,3=90.000000
L 5.83533346 2.41921644 5.83843278 2.42151663 1 P 0 ;0,1,2=124,3=90.000000
L 5.83843278 2.42151663 5.83998337 2.4242001 1 P 0 ;0,1,2=124,3=90.000000
L 5.83998337 2.4242001 5.8405 2.42726683 1 P 0 ;0,1,2=124,3=90.000000
L 5.8405 2.42726683 5.83946683 2.4311 1 P 0 ;0,1,2=124,3=90.000000
L 5.83946683 2.4311 5.83688307 2.43378346 1 P 0 ;0,1,2=124,3=90.000000
L 5.83688307 2.43378346 5.83378376 2.43455 1 P 0 ;0,1,2=124,3=90.000000
L 5.83378376 2.43455 5.83068258 2.43416673 1 P 0 ;0,1,2=124,3=90.000000
L 5.83068258 2.43416673 5.8280998 2.43263307 1 P 0 ;0,1,2=124,3=90.000000
L 5.8280998 2.43263307 5.82293327 2.42496663 1 P 0 ;0,1,2=124,3=90.000000
L 5.82293327 2.42496663 5.81931644 2.42151663 1 P 0 ;0,1,2=124,3=90.000000
L 5.81931644 2.42151663 5.81414892 2.41921644 1 P 0 ;0,1,2=124,3=90.000000
L 5.81414892 2.41921644 5.8095 2.4184499 1 P 0 ;0,1,2=124,3=90.000000
L 5.8095 2.4184499 5.8095 2.43455 1 P 0 ;0,1,2=124,3=90.000000
L 1.902 4.167 1.902 4.093 1 P 0 
L 1.778 4.167 1.902 4.167 1 P 0 
L 1.902 4.093 1.778 4.093 1 P 0 
L 1.778 4.093 1.778 4.167 1 P 0 
L 1.87166683 4.1795 1.87166683 4.2105 1 P 0 ;0,1,2=125,3=0.000000
L 1.87166683 4.2105 1.86208346 4.2105 1 P 0 ;0,1,2=125,3=0.000000
L 1.86208346 4.2105 1.85901673 4.20894931 1 P 0 ;0,1,2=125,3=0.000000
L 1.85901673 4.20894931 1.8570998 4.20688307 1 P 0 ;0,1,2=125,3=0.000000
L 1.8570998 4.20688307 1.85633327 4.2027497 1 P 0 ;0,1,2=125,3=0.000000
L 1.85633327 4.2027497 1.8570998 4.19861634 1 P 0 ;0,1,2=125,3=0.000000
L 1.8570998 4.19861634 1.8594 4.19603356 1 P 0 ;0,1,2=125,3=0.000000
L 1.8594 4.19603356 1.86208346 4.19448287 1 P 0 ;0,1,2=125,3=0.000000
L 1.86208346 4.19448287 1.87166683 4.19448287 1 P 0 ;0,1,2=125,3=0.000000
L 1.86208346 4.19448287 1.85633327 4.1795 1 P 0 ;0,1,2=125,3=0.000000
L 1.84143337 4.18569961 1.83913386 4.18208278 1 P 0 ;0,1,2=125,3=0.000000
L 1.83913386 4.18208278 1.83606713 4.18001654 1 P 0 ;0,1,2=125,3=0.000000
L 1.83606713 4.18001654 1.83261644 4.1795 1 P 0 ;0,1,2=125,3=0.000000
L 1.83261644 4.1795 1.8295497 4.18001654 1 P 0 ;0,1,2=125,3=0.000000
L 1.8295497 4.18001654 1.82648297 4.18259931 1 P 0 ;0,1,2=125,3=0.000000
L 1.82648297 4.18259931 1.82456673 4.18569961 1 P 0 ;0,1,2=125,3=0.000000
L 1.82456673 4.18569961 1.82418346 4.1887999 1 P 0 ;0,1,2=125,3=0.000000
L 1.82418346 4.1887999 1.82495 4.19241575 1 P 0 ;0,1,2=125,3=0.000000
L 1.82495 4.19241575 1.82763346 4.19499951 1 P 0 ;0,1,2=125,3=0.000000
L 1.82763346 4.19499951 1.83031693 4.19603356 1 P 0 ;0,1,2=125,3=0.000000
L 1.83031693 4.19603356 1.83376693 4.19603356 1 P 0 ;0,1,2=125,3=0.000000
L 1.83031693 4.19603356 1.82801673 4.19758317 1 P 0 ;0,1,2=125,3=0.000000
L 1.82801673 4.19758317 1.8260998 4.20016594 1 P 0 ;0,1,2=125,3=0.000000
L 1.8260998 4.20016594 1.82533327 4.20326624 1 P 0 ;0,1,2=125,3=0.000000
L 1.82533327 4.20326624 1.8260998 4.20636654 1 P 0 ;0,1,2=125,3=0.000000
L 1.8260998 4.20636654 1.82801673 4.20894931 1 P 0 ;0,1,2=125,3=0.000000
L 1.82801673 4.20894931 1.83146673 4.2105 1 P 0 ;0,1,2=125,3=0.000000
L 1.83146673 4.2105 1.83491663 4.20998337 1 P 0 ;0,1,2=125,3=0.000000
L 1.83491663 4.20998337 1.83836663 4.20791624 1 P 0 ;0,1,2=125,3=0.000000
L 1.81043337 4.18569961 1.80813386 4.18208278 1 P 0 ;0,1,2=125,3=0.000000
L 1.80813386 4.18208278 1.80506713 4.18001654 1 P 0 ;0,1,2=125,3=0.000000
L 1.80506713 4.18001654 1.80161644 4.1795 1 P 0 ;0,1,2=125,3=0.000000
L 1.80161644 4.1795 1.7985497 4.18001654 1 P 0 ;0,1,2=125,3=0.000000
L 1.7985497 4.18001654 1.79548297 4.18259931 1 P 0 ;0,1,2=125,3=0.000000
L 1.79548297 4.18259931 1.79356673 4.18569961 1 P 0 ;0,1,2=125,3=0.000000
L 1.79356673 4.18569961 1.79318346 4.1887999 1 P 0 ;0,1,2=125,3=0.000000
L 1.79318346 4.1887999 1.79395 4.19241575 1 P 0 ;0,1,2=125,3=0.000000
L 1.79395 4.19241575 1.79663346 4.19499951 1 P 0 ;0,1,2=125,3=0.000000
L 1.79663346 4.19499951 1.79931693 4.19603356 1 P 0 ;0,1,2=125,3=0.000000
L 1.79931693 4.19603356 1.80276693 4.19603356 1 P 0 ;0,1,2=125,3=0.000000
L 1.79931693 4.19603356 1.79701673 4.19758317 1 P 0 ;0,1,2=125,3=0.000000
L 1.79701673 4.19758317 1.7950998 4.20016594 1 P 0 ;0,1,2=125,3=0.000000
L 1.7950998 4.20016594 1.79433327 4.20326624 1 P 0 ;0,1,2=125,3=0.000000
L 1.79433327 4.20326624 1.7950998 4.20636654 1 P 0 ;0,1,2=125,3=0.000000
L 1.7950998 4.20636654 1.79701673 4.20894931 1 P 0 ;0,1,2=125,3=0.000000
L 1.79701673 4.20894931 1.80046673 4.2105 1 P 0 ;0,1,2=125,3=0.000000
L 1.80046673 4.2105 1.80391663 4.20998337 1 P 0 ;0,1,2=125,3=0.000000
L 1.80391663 4.20998337 1.80736663 4.20791624 1 P 0 ;0,1,2=125,3=0.000000
L 2.813 2.372 2.887 2.372 1 P 0 
L 2.887 2.372 2.887 2.248 1 P 0 
L 2.887 2.248 2.813 2.248 1 P 0 
L 2.813 2.248 2.813 2.372 1 P 0 
L 3.1245 2.38083317 3.1555 2.38083317 1 P 0 ;0,1,2=126,3=90.000000
L 3.1555 2.38083317 3.1555 2.39041654 1 P 0 ;0,1,2=126,3=90.000000
L 3.1555 2.39041654 3.15394931 2.39348327 1 P 0 ;0,1,2=126,3=90.000000
L 3.15394931 2.39348327 3.15188307 2.3954002 1 P 0 ;0,1,2=126,3=90.000000
L 3.15188307 2.3954002 3.1477497 2.39616673 1 P 0 ;0,1,2=126,3=90.000000
L 3.1477497 2.39616673 3.14361634 2.3954002 1 P 0 ;0,1,2=126,3=90.000000
L 3.14361634 2.3954002 3.14103356 2.3931 1 P 0 ;0,1,2=126,3=90.000000
L 3.14103356 2.3931 3.13948287 2.39041654 1 P 0 ;0,1,2=126,3=90.000000
L 3.13948287 2.39041654 3.13948287 2.38083317 1 P 0 ;0,1,2=126,3=90.000000
L 3.13948287 2.39041654 3.1245 2.39616673 1 P 0 ;0,1,2=126,3=90.000000
L 3.13069961 2.41106663 3.12708278 2.41336614 1 P 0 ;0,1,2=126,3=90.000000
L 3.12708278 2.41336614 3.12501654 2.41643287 1 P 0 ;0,1,2=126,3=90.000000
L 3.12501654 2.41643287 3.1245 2.41988356 1 P 0 ;0,1,2=126,3=90.000000
L 3.1245 2.41988356 3.12501654 2.4229503 1 P 0 ;0,1,2=126,3=90.000000
L 3.12501654 2.4229503 3.12759931 2.42601703 1 P 0 ;0,1,2=126,3=90.000000
L 3.12759931 2.42601703 3.13069961 2.42793327 1 P 0 ;0,1,2=126,3=90.000000
L 3.13069961 2.42793327 3.1337999 2.42831654 1 P 0 ;0,1,2=126,3=90.000000
L 3.1337999 2.42831654 3.13741575 2.42755 1 P 0 ;0,1,2=126,3=90.000000
L 3.13741575 2.42755 3.13999951 2.42486654 1 P 0 ;0,1,2=126,3=90.000000
L 3.13999951 2.42486654 3.14103356 2.42218307 1 P 0 ;0,1,2=126,3=90.000000
L 3.14103356 2.42218307 3.14103356 2.41873307 1 P 0 ;0,1,2=126,3=90.000000
L 3.14103356 2.42218307 3.14258317 2.42448327 1 P 0 ;0,1,2=126,3=90.000000
L 3.14258317 2.42448327 3.14516594 2.4264002 1 P 0 ;0,1,2=126,3=90.000000
L 3.14516594 2.4264002 3.14826624 2.42716673 1 P 0 ;0,1,2=126,3=90.000000
L 3.14826624 2.42716673 3.15136654 2.4264002 1 P 0 ;0,1,2=126,3=90.000000
L 3.15136654 2.4264002 3.15394931 2.42448327 1 P 0 ;0,1,2=126,3=90.000000
L 3.15394931 2.42448327 3.1555 2.42103327 1 P 0 ;0,1,2=126,3=90.000000
L 3.1555 2.42103327 3.15498337 2.41758337 1 P 0 ;0,1,2=126,3=90.000000
L 3.15498337 2.41758337 3.15291624 2.41413337 1 P 0 ;0,1,2=126,3=90.000000
L 3.12914892 2.44206663 3.12656614 2.44436614 1 P 0 ;0,1,2=126,3=90.000000
L 3.12656614 2.44436614 3.12501654 2.44704961 1 P 0 ;0,1,2=126,3=90.000000
L 3.12501654 2.44704961 3.1245 2.45049961 1 P 0 ;0,1,2=126,3=90.000000
L 3.1245 2.45049961 3.12553307 2.4539503 1 P 0 ;0,1,2=126,3=90.000000
L 3.12553307 2.4539503 3.12759931 2.45663307 1 P 0 ;0,1,2=126,3=90.000000
L 3.12759931 2.45663307 3.13121614 2.45855 1 P 0 ;0,1,2=126,3=90.000000
L 3.13121614 2.45855 3.13534951 2.45893327 1 P 0 ;0,1,2=126,3=90.000000
L 3.13534951 2.45893327 3.13948287 2.45816673 1 P 0 ;0,1,2=126,3=90.000000
L 3.13948287 2.45816673 3.14206663 2.4562498 1 P 0 ;0,1,2=126,3=90.000000
L 3.14206663 2.4562498 3.14413287 2.45356634 1 P 0 ;0,1,2=126,3=90.000000
L 3.14413287 2.45356634 3.14464941 2.45088356 1 P 0 ;0,1,2=126,3=90.000000
L 3.14464941 2.45088356 3.14413287 2.4482001 1 P 0 ;0,1,2=126,3=90.000000
L 3.14413287 2.4482001 3.14206663 2.4447501 1 P 0 ;0,1,2=126,3=90.000000
L 3.14206663 2.4447501 3.1555 2.4458999 1 P 0 ;0,1,2=126,3=90.000000
L 3.1555 2.4458999 3.1555 2.4562498 1 P 0 ;0,1,2=126,3=90.000000
L 3.1245 2.48073307 3.13121614 2.48149961 1 P 0 ;0,1,2=126,3=90.000000
L 3.13121614 2.48149961 3.13689921 2.4826501 1 P 0 ;0,1,2=126,3=90.000000
L 3.13689921 2.4826501 3.14206663 2.48418307 1 P 0 ;0,1,2=126,3=90.000000
L 3.14206663 2.48418307 3.1477497 2.4861 1 P 0 ;0,1,2=126,3=90.000000
L 3.1477497 2.4861 3.1555 2.48916673 1 P 0 ;0,1,2=126,3=90.000000
L 3.1555 2.48916673 3.1555 2.47383317 1 P 0 ;0,1,2=126,3=90.000000
L 3.148 3.852 3.222 3.852 1 P 0 
L 3.222 3.852 3.222 3.728 1 P 0 
L 3.222 3.728 3.148 3.728 1 P 0 
L 3.148 3.728 3.148 3.852 1 P 0 
L 3.1045 3.74633317 3.1355 3.74633317 1 P 0 ;0,1,2=127,3=90.000000
L 3.1355 3.74633317 3.1355 3.75591654 1 P 0 ;0,1,2=127,3=90.000000
L 3.1355 3.75591654 3.13394931 3.75898327 1 P 0 ;0,1,2=127,3=90.000000
L 3.13394931 3.75898327 3.13188307 3.7609002 1 P 0 ;0,1,2=127,3=90.000000
L 3.13188307 3.7609002 3.1277497 3.76166673 1 P 0 ;0,1,2=127,3=90.000000
L 3.1277497 3.76166673 3.12361634 3.7609002 1 P 0 ;0,1,2=127,3=90.000000
L 3.12361634 3.7609002 3.12103356 3.7586 1 P 0 ;0,1,2=127,3=90.000000
L 3.12103356 3.7586 3.11948287 3.75591654 1 P 0 ;0,1,2=127,3=90.000000
L 3.11948287 3.75591654 3.11948287 3.74633317 1 P 0 ;0,1,2=127,3=90.000000
L 3.11948287 3.75591654 3.1045 3.76166673 1 P 0 ;0,1,2=127,3=90.000000
L 3.11069961 3.77656663 3.10708278 3.77886614 1 P 0 ;0,1,2=127,3=90.000000
L 3.10708278 3.77886614 3.10501654 3.78193287 1 P 0 ;0,1,2=127,3=90.000000
L 3.10501654 3.78193287 3.1045 3.78538356 1 P 0 ;0,1,2=127,3=90.000000
L 3.1045 3.78538356 3.10501654 3.7884503 1 P 0 ;0,1,2=127,3=90.000000
L 3.10501654 3.7884503 3.10759931 3.79151703 1 P 0 ;0,1,2=127,3=90.000000
L 3.10759931 3.79151703 3.11069961 3.79343327 1 P 0 ;0,1,2=127,3=90.000000
L 3.11069961 3.79343327 3.1137999 3.79381654 1 P 0 ;0,1,2=127,3=90.000000
L 3.1137999 3.79381654 3.11741575 3.79305 1 P 0 ;0,1,2=127,3=90.000000
L 3.11741575 3.79305 3.11999951 3.79036654 1 P 0 ;0,1,2=127,3=90.000000
L 3.11999951 3.79036654 3.12103356 3.78768307 1 P 0 ;0,1,2=127,3=90.000000
L 3.12103356 3.78768307 3.12103356 3.78423307 1 P 0 ;0,1,2=127,3=90.000000
L 3.12103356 3.78768307 3.12258317 3.78998327 1 P 0 ;0,1,2=127,3=90.000000
L 3.12258317 3.78998327 3.12516594 3.7919002 1 P 0 ;0,1,2=127,3=90.000000
L 3.12516594 3.7919002 3.12826624 3.79266673 1 P 0 ;0,1,2=127,3=90.000000
L 3.12826624 3.79266673 3.13136654 3.7919002 1 P 0 ;0,1,2=127,3=90.000000
L 3.13136654 3.7919002 3.13394931 3.78998327 1 P 0 ;0,1,2=127,3=90.000000
L 3.13394931 3.78998327 3.1355 3.78653327 1 P 0 ;0,1,2=127,3=90.000000
L 3.1355 3.78653327 3.13498337 3.78308337 1 P 0 ;0,1,2=127,3=90.000000
L 3.13498337 3.78308337 3.13291624 3.77963337 1 P 0 ;0,1,2=127,3=90.000000
L 3.10811585 3.80948287 3.10553307 3.81216634 1 P 0 ;0,1,2=127,3=90.000000
L 3.10553307 3.81216634 3.1045 3.81523307 1 P 0 ;0,1,2=127,3=90.000000
L 3.1045 3.81523307 3.10553307 3.8182998 1 P 0 ;0,1,2=127,3=90.000000
L 3.10553307 3.8182998 3.10863238 3.82098327 1 P 0 ;0,1,2=127,3=90.000000
L 3.10863238 3.82098327 3.11328327 3.8229002 1 P 0 ;0,1,2=127,3=90.000000
L 3.11328327 3.8229002 3.11793327 3.82366673 1 P 0 ;0,1,2=127,3=90.000000
L 3.11793327 3.82366673 3.12361634 3.82366673 1 P 0 ;0,1,2=127,3=90.000000
L 3.12361634 3.82366673 3.12826624 3.8229002 1 P 0 ;0,1,2=127,3=90.000000
L 3.12826624 3.8229002 3.1323997 3.82098327 1 P 0 ;0,1,2=127,3=90.000000
L 3.1323997 3.82098327 3.13446683 3.81868307 1 P 0 ;0,1,2=127,3=90.000000
L 3.13446683 3.81868307 3.1355 3.81599961 1 P 0 ;0,1,2=127,3=90.000000
L 3.1355 3.81599961 3.13446683 3.81293287 1 P 0 ;0,1,2=127,3=90.000000
L 3.13446683 3.81293287 3.1323997 3.81063337 1 P 0 ;0,1,2=127,3=90.000000
L 3.1323997 3.81063337 3.1293003 3.8090997 1 P 0 ;0,1,2=127,3=90.000000
L 3.1293003 3.8090997 3.12516594 3.80833317 1 P 0 ;0,1,2=127,3=90.000000
L 3.12516594 3.80833317 3.1215501 3.8090997 1 P 0 ;0,1,2=127,3=90.000000
L 3.1215501 3.8090997 3.11793327 3.81101663 1 P 0 ;0,1,2=127,3=90.000000
L 3.11793327 3.81101663 3.11586604 3.81331683 1 P 0 ;0,1,2=127,3=90.000000
L 3.11586604 3.81331683 3.11534951 3.81599961 1 P 0 ;0,1,2=127,3=90.000000
L 3.11534951 3.81599961 3.11638268 3.81906634 1 P 0 ;0,1,2=127,3=90.000000
L 3.11638268 3.81906634 3.11896634 3.82136654 1 P 0 ;0,1,2=127,3=90.000000
L 3.11896634 3.82136654 3.12361634 3.82366673 1 P 0 ;0,1,2=127,3=90.000000
L 5.782 2.027 5.782 1.953 1 P 0 
L 5.658 2.027 5.782 2.027 1 P 0 
L 5.782 1.953 5.658 1.953 1 P 0 
L 5.658 1.953 5.658 2.027 1 P 0 
L 5.78416683 1.9045 5.78416683 1.9355 1 P 0 ;0,1,2=128,3=0.000000
L 5.78416683 1.9355 5.77458346 1.9355 1 P 0 ;0,1,2=128,3=0.000000
L 5.77458346 1.9355 5.77151673 1.93394931 1 P 0 ;0,1,2=128,3=0.000000
L 5.77151673 1.93394931 5.7695998 1.93188307 1 P 0 ;0,1,2=128,3=0.000000
L 5.7695998 1.93188307 5.76883327 1.9277497 1 P 0 ;0,1,2=128,3=0.000000
L 5.76883327 1.9277497 5.7695998 1.92361634 1 P 0 ;0,1,2=128,3=0.000000
L 5.7695998 1.92361634 5.7719 1.92103356 1 P 0 ;0,1,2=128,3=0.000000
L 5.7719 1.92103356 5.77458346 1.91948287 1 P 0 ;0,1,2=128,3=0.000000
L 5.77458346 1.91948287 5.78416683 1.91948287 1 P 0 ;0,1,2=128,3=0.000000
L 5.77458346 1.91948287 5.76883327 1.9045 1 P 0 ;0,1,2=128,3=0.000000
L 5.75278356 1.93033346 5.75048337 1.93343278 1 P 0 ;0,1,2=128,3=0.000000
L 5.75048337 1.93343278 5.7477999 1.93498337 1 P 0 ;0,1,2=128,3=0.000000
L 5.7477999 1.93498337 5.74473317 1.9355 1 P 0 ;0,1,2=128,3=0.000000
L 5.74473317 1.9355 5.7409 1.93446683 1 P 0 ;0,1,2=128,3=0.000000
L 5.7409 1.93446683 5.73821654 1.93188307 1 P 0 ;0,1,2=128,3=0.000000
L 5.73821654 1.93188307 5.73745 1.92878376 1 P 0 ;0,1,2=128,3=0.000000
L 5.73745 1.92878376 5.73783327 1.92568258 1 P 0 ;0,1,2=128,3=0.000000
L 5.73783327 1.92568258 5.73936693 1.9230998 1 P 0 ;0,1,2=128,3=0.000000
L 5.73936693 1.9230998 5.74703337 1.91793327 1 P 0 ;0,1,2=128,3=0.000000
L 5.74703337 1.91793327 5.75048337 1.91431644 1 P 0 ;0,1,2=128,3=0.000000
L 5.75048337 1.91431644 5.75278356 1.90914892 1 P 0 ;0,1,2=128,3=0.000000
L 5.75278356 1.90914892 5.7535501 1.9045 1 P 0 ;0,1,2=128,3=0.000000
L 5.7535501 1.9045 5.73745 1.9045 1 P 0 ;0,1,2=128,3=0.000000
L 5.72293337 1.90914892 5.72063386 1.90656614 1 P 0 ;0,1,2=128,3=0.000000
L 5.72063386 1.90656614 5.71795039 1.90501654 1 P 0 ;0,1,2=128,3=0.000000
L 5.71795039 1.90501654 5.71450039 1.9045 1 P 0 ;0,1,2=128,3=0.000000
L 5.71450039 1.9045 5.7110497 1.90553307 1 P 0 ;0,1,2=128,3=0.000000
L 5.7110497 1.90553307 5.70836693 1.90759931 1 P 0 ;0,1,2=128,3=0.000000
L 5.70836693 1.90759931 5.70645 1.91121614 1 P 0 ;0,1,2=128,3=0.000000
L 5.70645 1.91121614 5.70606673 1.91534951 1 P 0 ;0,1,2=128,3=0.000000
L 5.70606673 1.91534951 5.70683327 1.91948287 1 P 0 ;0,1,2=128,3=0.000000
L 5.70683327 1.91948287 5.7087502 1.92206663 1 P 0 ;0,1,2=128,3=0.000000
L 5.7087502 1.92206663 5.71143366 1.92413287 1 P 0 ;0,1,2=128,3=0.000000
L 5.71143366 1.92413287 5.71411644 1.92464941 1 P 0 ;0,1,2=128,3=0.000000
L 5.71411644 1.92464941 5.7167999 1.92413287 1 P 0 ;0,1,2=128,3=0.000000
L 5.7167999 1.92413287 5.7202499 1.92206663 1 P 0 ;0,1,2=128,3=0.000000
L 5.7202499 1.92206663 5.7191001 1.9355 1 P 0 ;0,1,2=128,3=0.000000
L 5.7191001 1.9355 5.7087502 1.9355 1 P 0 ;0,1,2=128,3=0.000000
L 5.69193337 1.91069961 5.68963386 1.90708278 1 P 0 ;0,1,2=128,3=0.000000
L 5.68963386 1.90708278 5.68656713 1.90501654 1 P 0 ;0,1,2=128,3=0.000000
L 5.68656713 1.90501654 5.68311644 1.9045 1 P 0 ;0,1,2=128,3=0.000000
L 5.68311644 1.9045 5.6800497 1.90501654 1 P 0 ;0,1,2=128,3=0.000000
L 5.6800497 1.90501654 5.67698297 1.90759931 1 P 0 ;0,1,2=128,3=0.000000
L 5.67698297 1.90759931 5.67506673 1.91069961 1 P 0 ;0,1,2=128,3=0.000000
L 5.67506673 1.91069961 5.67468346 1.9137999 1 P 0 ;0,1,2=128,3=0.000000
L 5.67468346 1.9137999 5.67545 1.91741575 1 P 0 ;0,1,2=128,3=0.000000
L 5.67545 1.91741575 5.67813346 1.91999951 1 P 0 ;0,1,2=128,3=0.000000
L 5.67813346 1.91999951 5.68081693 1.92103356 1 P 0 ;0,1,2=128,3=0.000000
L 5.68081693 1.92103356 5.68426693 1.92103356 1 P 0 ;0,1,2=128,3=0.000000
L 5.68081693 1.92103356 5.67851673 1.92258317 1 P 0 ;0,1,2=128,3=0.000000
L 5.67851673 1.92258317 5.6765998 1.92516594 1 P 0 ;0,1,2=128,3=0.000000
L 5.6765998 1.92516594 5.67583327 1.92826624 1 P 0 ;0,1,2=128,3=0.000000
L 5.67583327 1.92826624 5.6765998 1.93136654 1 P 0 ;0,1,2=128,3=0.000000
L 5.6765998 1.93136654 5.67851673 1.93394931 1 P 0 ;0,1,2=128,3=0.000000
L 5.67851673 1.93394931 5.68196673 1.9355 1 P 0 ;0,1,2=128,3=0.000000
L 5.68196673 1.9355 5.68541663 1.93498337 1 P 0 ;0,1,2=128,3=0.000000
L 5.68541663 1.93498337 5.68886663 1.93291624 1 P 0 ;0,1,2=128,3=0.000000
L 1.8866 0.5782 1.8426 0.5782 1 P 0 
L 1.8866 0.6682 1.8866 0.5782 1 P 0 
L 1.8426 0.6682 1.8866 0.6682 1 P 0 
L 1.8426 0.5782 1.8426 0.6682 1 P 0 
L 1.8495 0.68133317 1.8805 0.68133317 1 P 0 ;0,1,2=129,3=90.000000
L 1.8805 0.68133317 1.8805 0.69091654 1 P 0 ;0,1,2=129,3=90.000000
L 1.8805 0.69091654 1.87894931 0.69398327 1 P 0 ;0,1,2=129,3=90.000000
L 1.87894931 0.69398327 1.87688307 0.6959002 1 P 0 ;0,1,2=129,3=90.000000
L 1.87688307 0.6959002 1.8727497 0.69666673 1 P 0 ;0,1,2=129,3=90.000000
L 1.8727497 0.69666673 1.86861634 0.6959002 1 P 0 ;0,1,2=129,3=90.000000
L 1.86861634 0.6959002 1.86603356 0.6936 1 P 0 ;0,1,2=129,3=90.000000
L 1.86603356 0.6936 1.86448287 0.69091654 1 P 0 ;0,1,2=129,3=90.000000
L 1.86448287 0.69091654 1.86448287 0.68133317 1 P 0 ;0,1,2=129,3=90.000000
L 1.86448287 0.69091654 1.8495 0.69666673 1 P 0 ;0,1,2=129,3=90.000000
L 1.87533346 0.71271644 1.87843278 0.71501663 1 P 0 ;0,1,2=129,3=90.000000
L 1.87843278 0.71501663 1.87998337 0.7177001 1 P 0 ;0,1,2=129,3=90.000000
L 1.87998337 0.7177001 1.8805 0.72076683 1 P 0 ;0,1,2=129,3=90.000000
L 1.8805 0.72076683 1.87946683 0.7246 1 P 0 ;0,1,2=129,3=90.000000
L 1.87946683 0.7246 1.87688307 0.72728346 1 P 0 ;0,1,2=129,3=90.000000
L 1.87688307 0.72728346 1.87378376 0.72805 1 P 0 ;0,1,2=129,3=90.000000
L 1.87378376 0.72805 1.87068258 0.72766673 1 P 0 ;0,1,2=129,3=90.000000
L 1.87068258 0.72766673 1.8680998 0.72613307 1 P 0 ;0,1,2=129,3=90.000000
L 1.8680998 0.72613307 1.86293327 0.71846663 1 P 0 ;0,1,2=129,3=90.000000
L 1.86293327 0.71846663 1.85931644 0.71501663 1 P 0 ;0,1,2=129,3=90.000000
L 1.85931644 0.71501663 1.85414892 0.71271644 1 P 0 ;0,1,2=129,3=90.000000
L 1.85414892 0.71271644 1.8495 0.7119499 1 P 0 ;0,1,2=129,3=90.000000
L 1.8495 0.7119499 1.8495 0.72805 1 P 0 ;0,1,2=129,3=90.000000
L 1.85569961 0.74256663 1.85208278 0.74486614 1 P 0 ;0,1,2=129,3=90.000000
L 1.85208278 0.74486614 1.85001654 0.74793287 1 P 0 ;0,1,2=129,3=90.000000
L 1.85001654 0.74793287 1.8495 0.75138356 1 P 0 ;0,1,2=129,3=90.000000
L 1.8495 0.75138356 1.85001654 0.7544503 1 P 0 ;0,1,2=129,3=90.000000
L 1.85001654 0.7544503 1.85259931 0.75751703 1 P 0 ;0,1,2=129,3=90.000000
L 1.85259931 0.75751703 1.85569961 0.75943327 1 P 0 ;0,1,2=129,3=90.000000
L 1.85569961 0.75943327 1.8587999 0.75981654 1 P 0 ;0,1,2=129,3=90.000000
L 1.8587999 0.75981654 1.86241575 0.75905 1 P 0 ;0,1,2=129,3=90.000000
L 1.86241575 0.75905 1.86499951 0.75636654 1 P 0 ;0,1,2=129,3=90.000000
L 1.86499951 0.75636654 1.86603356 0.75368307 1 P 0 ;0,1,2=129,3=90.000000
L 1.86603356 0.75368307 1.86603356 0.75023307 1 P 0 ;0,1,2=129,3=90.000000
L 1.86603356 0.75368307 1.86758317 0.75598327 1 P 0 ;0,1,2=129,3=90.000000
L 1.86758317 0.75598327 1.87016594 0.7579002 1 P 0 ;0,1,2=129,3=90.000000
L 1.87016594 0.7579002 1.87326624 0.75866673 1 P 0 ;0,1,2=129,3=90.000000
L 1.87326624 0.75866673 1.87636654 0.7579002 1 P 0 ;0,1,2=129,3=90.000000
L 1.87636654 0.7579002 1.87894931 0.75598327 1 P 0 ;0,1,2=129,3=90.000000
L 1.87894931 0.75598327 1.8805 0.75253327 1 P 0 ;0,1,2=129,3=90.000000
L 1.8805 0.75253327 1.87998337 0.74908337 1 P 0 ;0,1,2=129,3=90.000000
L 1.87998337 0.74908337 1.87791624 0.74563337 1 P 0 ;0,1,2=129,3=90.000000
L 3.509 1.86448996 3.509 1.90848996 1 P 0 
L 3.599 1.86448996 3.509 1.86448996 1 P 0 
L 3.599 1.90848996 3.599 1.86448996 1 P 0 
L 3.509 1.90848996 3.599 1.90848996 1 P 0 
L 3.63816683 1.971 3.63816683 2.002 1 P 0 ;0,1,2=130,3=0.000000
L 3.63816683 2.002 3.62858346 2.002 1 P 0 ;0,1,2=130,3=0.000000
L 3.62858346 2.002 3.62551673 2.00044931 1 P 0 ;0,1,2=130,3=0.000000
L 3.62551673 2.00044931 3.6235998 1.99838307 1 P 0 ;0,1,2=130,3=0.000000
L 3.6235998 1.99838307 3.62283327 1.9942497 1 P 0 ;0,1,2=130,3=0.000000
L 3.62283327 1.9942497 3.6235998 1.99011634 1 P 0 ;0,1,2=130,3=0.000000
L 3.6235998 1.99011634 3.6259 1.98753356 1 P 0 ;0,1,2=130,3=0.000000
L 3.6259 1.98753356 3.62858346 1.98598287 1 P 0 ;0,1,2=130,3=0.000000
L 3.62858346 1.98598287 3.63816683 1.98598287 1 P 0 ;0,1,2=130,3=0.000000
L 3.62858346 1.98598287 3.62283327 1.971 1 P 0 ;0,1,2=130,3=0.000000
L 3.59950039 1.971 3.59950039 2.002 1 P 0 ;0,1,2=130,3=0.000000
L 3.59950039 2.002 3.6041001 1.9958003 1 P 0 ;0,1,2=130,3=0.000000
L 3.6041001 1.971 3.59490069 1.971 1 P 0 ;0,1,2=130,3=0.000000
L 3.56850039 2.002 3.57156713 2.00096683 1 P 0 ;0,1,2=130,3=0.000000
L 3.57156713 2.00096683 3.57386663 1.99838307 1 P 0 ;0,1,2=130,3=0.000000
L 3.57386663 1.99838307 3.5754003 1.99528376 1 P 0 ;0,1,2=130,3=0.000000
L 3.5754003 1.99528376 3.5765501 1.99114941 1 P 0 ;0,1,2=130,3=0.000000
L 3.5765501 1.99114941 3.57693337 1.98649951 1 P 0 ;0,1,2=130,3=0.000000
L 3.57693337 1.98649951 3.5765501 1.98184951 1 P 0 ;0,1,2=130,3=0.000000
L 3.5765501 1.98184951 3.5754003 1.97771614 1 P 0 ;0,1,2=130,3=0.000000
L 3.5754003 1.97771614 3.57386663 1.97461585 1 P 0 ;0,1,2=130,3=0.000000
L 3.57386663 1.97461585 3.57156713 1.97203307 1 P 0 ;0,1,2=130,3=0.000000
L 3.57156713 1.97203307 3.56850039 1.971 1 P 0 ;0,1,2=130,3=0.000000
L 3.56850039 1.971 3.56543366 1.97203307 1 P 0 ;0,1,2=130,3=0.000000
L 3.56543366 1.97203307 3.56313346 1.97461585 1 P 0 ;0,1,2=130,3=0.000000
L 3.56313346 1.97461585 3.5615998 1.97771614 1 P 0 ;0,1,2=130,3=0.000000
L 3.5615998 1.97771614 3.56045 1.98184951 1 P 0 ;0,1,2=130,3=0.000000
L 3.56045 1.98184951 3.56006673 1.98649951 1 P 0 ;0,1,2=130,3=0.000000
L 3.56006673 1.98649951 3.56045 1.99114941 1 P 0 ;0,1,2=130,3=0.000000
L 3.56045 1.99114941 3.5615998 1.99528376 1 P 0 ;0,1,2=130,3=0.000000
L 3.5615998 1.99528376 3.56313346 1.99838307 1 P 0 ;0,1,2=130,3=0.000000
L 3.56313346 1.99838307 3.56543366 2.00096683 1 P 0 ;0,1,2=130,3=0.000000
L 3.56543366 2.00096683 3.56850039 2.002 1 P 0 ;0,1,2=130,3=0.000000
L 3.54478356 1.98391575 3.5421001 1.98753356 1 P 0 ;0,1,2=130,3=0.000000
L 3.5421001 1.98753356 3.5397999 1.9895998 1 P 0 ;0,1,2=130,3=0.000000
L 3.5397999 1.9895998 3.53673317 1.99063287 1 P 0 ;0,1,2=130,3=0.000000
L 3.53673317 1.99063287 3.5340497 1.9895998 1 P 0 ;0,1,2=130,3=0.000000
L 3.5340497 1.9895998 3.53213346 1.98753356 1 P 0 ;0,1,2=130,3=0.000000
L 3.53213346 1.98753356 3.5305998 1.98443327 1 P 0 ;0,1,2=130,3=0.000000
L 3.5305998 1.98443327 3.53021654 1.98081644 1 P 0 ;0,1,2=130,3=0.000000
L 3.53021654 1.98081644 3.5305998 1.97771614 1 P 0 ;0,1,2=130,3=0.000000
L 3.5305998 1.97771614 3.53213346 1.97461585 1 P 0 ;0,1,2=130,3=0.000000
L 3.53213346 1.97461585 3.53443366 1.97203307 1 P 0 ;0,1,2=130,3=0.000000
L 3.53443366 1.97203307 3.53711644 1.971 1 P 0 ;0,1,2=130,3=0.000000
L 3.53711644 1.971 3.54018317 1.97203307 1 P 0 ;0,1,2=130,3=0.000000
L 3.54018317 1.97203307 3.54286663 1.97513238 1 P 0 ;0,1,2=130,3=0.000000
L 3.54286663 1.97513238 3.5444003 1.97978327 1 P 0 ;0,1,2=130,3=0.000000
L 3.5444003 1.97978327 3.54478356 1.9849498 1 P 0 ;0,1,2=130,3=0.000000
L 3.54478356 1.9849498 3.54401713 1.99166594 1 P 0 ;0,1,2=130,3=0.000000
L 3.54401713 1.99166594 3.54286663 1.99528376 1 P 0 ;0,1,2=130,3=0.000000
L 3.54286663 1.99528376 3.54095039 1.9988997 1 P 0 ;0,1,2=130,3=0.000000
L 3.54095039 1.9988997 3.53826693 2.00148337 1 P 0 ;0,1,2=130,3=0.000000
L 3.53826693 2.00148337 3.53558346 2.002 1 P 0 ;0,1,2=130,3=0.000000
L 3.53558346 2.002 3.5329 2.00096683 1 P 0 ;0,1,2=130,3=0.000000
L 3.5329 2.00096683 3.53098297 1.99838307 1 P 0 ;0,1,2=130,3=0.000000
L 2.817 1.814 2.773 1.814 1 P 0 
L 2.773 1.904 2.817 1.904 1 P 0 
L 2.773 1.814 2.773 1.904 1 P 0 
L 2.817 1.904 2.817 1.814 1 P 0 
L 2.7395 1.82133317 2.7705 1.82133317 1 P 0 ;0,1,2=131,3=90.000000
L 2.7705 1.82133317 2.7705 1.83091654 1 P 0 ;0,1,2=131,3=90.000000
L 2.7705 1.83091654 2.76894931 1.83398327 1 P 0 ;0,1,2=131,3=90.000000
L 2.76894931 1.83398327 2.76688307 1.8359002 1 P 0 ;0,1,2=131,3=90.000000
L 2.76688307 1.8359002 2.7627497 1.83666673 1 P 0 ;0,1,2=131,3=90.000000
L 2.7627497 1.83666673 2.75861634 1.8359002 1 P 0 ;0,1,2=131,3=90.000000
L 2.75861634 1.8359002 2.75603356 1.8336 1 P 0 ;0,1,2=131,3=90.000000
L 2.75603356 1.8336 2.75448287 1.83091654 1 P 0 ;0,1,2=131,3=90.000000
L 2.75448287 1.83091654 2.75448287 1.82133317 1 P 0 ;0,1,2=131,3=90.000000
L 2.75448287 1.83091654 2.7395 1.83666673 1 P 0 ;0,1,2=131,3=90.000000
L 2.74311585 1.85348287 2.74053307 1.85616634 1 P 0 ;0,1,2=131,3=90.000000
L 2.74053307 1.85616634 2.7395 1.85923307 1 P 0 ;0,1,2=131,3=90.000000
L 2.7395 1.85923307 2.74053307 1.8622998 1 P 0 ;0,1,2=131,3=90.000000
L 2.74053307 1.8622998 2.74363238 1.86498327 1 P 0 ;0,1,2=131,3=90.000000
L 2.74363238 1.86498327 2.74828327 1.8669002 1 P 0 ;0,1,2=131,3=90.000000
L 2.74828327 1.8669002 2.75293327 1.86766673 1 P 0 ;0,1,2=131,3=90.000000
L 2.75293327 1.86766673 2.75861634 1.86766673 1 P 0 ;0,1,2=131,3=90.000000
L 2.75861634 1.86766673 2.76326624 1.8669002 1 P 0 ;0,1,2=131,3=90.000000
L 2.76326624 1.8669002 2.7673997 1.86498327 1 P 0 ;0,1,2=131,3=90.000000
L 2.7673997 1.86498327 2.76946683 1.86268307 1 P 0 ;0,1,2=131,3=90.000000
L 2.76946683 1.86268307 2.7705 1.85999961 1 P 0 ;0,1,2=131,3=90.000000
L 2.7705 1.85999961 2.76946683 1.85693287 1 P 0 ;0,1,2=131,3=90.000000
L 2.76946683 1.85693287 2.7673997 1.85463337 1 P 0 ;0,1,2=131,3=90.000000
L 2.7673997 1.85463337 2.7643003 1.8530997 1 P 0 ;0,1,2=131,3=90.000000
L 2.7643003 1.8530997 2.76016594 1.85233317 1 P 0 ;0,1,2=131,3=90.000000
L 2.76016594 1.85233317 2.7565501 1.8530997 1 P 0 ;0,1,2=131,3=90.000000
L 2.7565501 1.8530997 2.75293327 1.85501663 1 P 0 ;0,1,2=131,3=90.000000
L 2.75293327 1.85501663 2.75086604 1.85731683 1 P 0 ;0,1,2=131,3=90.000000
L 2.75086604 1.85731683 2.75034951 1.85999961 1 P 0 ;0,1,2=131,3=90.000000
L 2.75034951 1.85999961 2.75138268 1.86306634 1 P 0 ;0,1,2=131,3=90.000000
L 2.75138268 1.86306634 2.75396634 1.86536654 1 P 0 ;0,1,2=131,3=90.000000
L 2.75396634 1.86536654 2.75861634 1.86766673 1 P 0 ;0,1,2=131,3=90.000000
L 2.7705 1.89099961 2.76946683 1.88793287 1 P 0 ;0,1,2=131,3=90.000000
L 2.76946683 1.88793287 2.76688307 1.88563337 1 P 0 ;0,1,2=131,3=90.000000
L 2.76688307 1.88563337 2.76378376 1.8840997 1 P 0 ;0,1,2=131,3=90.000000
L 2.76378376 1.8840997 2.75964941 1.8829499 1 P 0 ;0,1,2=131,3=90.000000
L 2.75964941 1.8829499 2.75499951 1.88256663 1 P 0 ;0,1,2=131,3=90.000000
L 2.75499951 1.88256663 2.75034951 1.8829499 1 P 0 ;0,1,2=131,3=90.000000
L 2.75034951 1.8829499 2.74621614 1.8840997 1 P 0 ;0,1,2=131,3=90.000000
L 2.74621614 1.8840997 2.74311585 1.88563337 1 P 0 ;0,1,2=131,3=90.000000
L 2.74311585 1.88563337 2.74053307 1.88793287 1 P 0 ;0,1,2=131,3=90.000000
L 2.74053307 1.88793287 2.7395 1.89099961 1 P 0 ;0,1,2=131,3=90.000000
L 2.7395 1.89099961 2.74053307 1.89406634 1 P 0 ;0,1,2=131,3=90.000000
L 2.74053307 1.89406634 2.74311585 1.89636654 1 P 0 ;0,1,2=131,3=90.000000
L 2.74311585 1.89636654 2.74621614 1.8979002 1 P 0 ;0,1,2=131,3=90.000000
L 2.74621614 1.8979002 2.75034951 1.89905 1 P 0 ;0,1,2=131,3=90.000000
L 2.75034951 1.89905 2.75499951 1.89943327 1 P 0 ;0,1,2=131,3=90.000000
L 2.75499951 1.89943327 2.75964941 1.89905 1 P 0 ;0,1,2=131,3=90.000000
L 2.75964941 1.89905 2.76378376 1.8979002 1 P 0 ;0,1,2=131,3=90.000000
L 2.76378376 1.8979002 2.76688307 1.89636654 1 P 0 ;0,1,2=131,3=90.000000
L 2.76688307 1.89636654 2.76946683 1.89406634 1 P 0 ;0,1,2=131,3=90.000000
L 2.76946683 1.89406634 2.7705 1.89099961 1 P 0 ;0,1,2=131,3=90.000000
L 3.68 1.698 3.68 1.742 1 P 0 
L 3.77 1.698 3.68 1.698 1 P 0 
L 3.77 1.742 3.77 1.698 1 P 0 
L 3.68 1.742 3.77 1.742 1 P 0 
L 3.63916683 1.7095 3.63916683 1.7405 1 P 0 ;0,1,2=132,3=0.000000
L 3.63916683 1.7405 3.62958346 1.7405 1 P 0 ;0,1,2=132,3=0.000000
L 3.62958346 1.7405 3.62651673 1.73894931 1 P 0 ;0,1,2=132,3=0.000000
L 3.62651673 1.73894931 3.6245998 1.73688307 1 P 0 ;0,1,2=132,3=0.000000
L 3.6245998 1.73688307 3.62383327 1.7327497 1 P 0 ;0,1,2=132,3=0.000000
L 3.62383327 1.7327497 3.6245998 1.72861634 1 P 0 ;0,1,2=132,3=0.000000
L 3.6245998 1.72861634 3.6269 1.72603356 1 P 0 ;0,1,2=132,3=0.000000
L 3.6269 1.72603356 3.62958346 1.72448287 1 P 0 ;0,1,2=132,3=0.000000
L 3.62958346 1.72448287 3.63916683 1.72448287 1 P 0 ;0,1,2=132,3=0.000000
L 3.62958346 1.72448287 3.62383327 1.7095 1 P 0 ;0,1,2=132,3=0.000000
L 3.60050039 1.7095 3.60050039 1.7405 1 P 0 ;0,1,2=132,3=0.000000
L 3.60050039 1.7405 3.6051001 1.7343003 1 P 0 ;0,1,2=132,3=0.000000
L 3.6051001 1.7095 3.59590069 1.7095 1 P 0 ;0,1,2=132,3=0.000000
L 3.57601713 1.71311585 3.57333366 1.71053307 1 P 0 ;0,1,2=132,3=0.000000
L 3.57333366 1.71053307 3.57026693 1.7095 1 P 0 ;0,1,2=132,3=0.000000
L 3.57026693 1.7095 3.5672002 1.71053307 1 P 0 ;0,1,2=132,3=0.000000
L 3.5672002 1.71053307 3.56451673 1.71363238 1 P 0 ;0,1,2=132,3=0.000000
L 3.56451673 1.71363238 3.5625998 1.71828327 1 P 0 ;0,1,2=132,3=0.000000
L 3.5625998 1.71828327 3.56183327 1.72293327 1 P 0 ;0,1,2=132,3=0.000000
L 3.56183327 1.72293327 3.56183327 1.72861634 1 P 0 ;0,1,2=132,3=0.000000
L 3.56183327 1.72861634 3.5625998 1.73326624 1 P 0 ;0,1,2=132,3=0.000000
L 3.5625998 1.73326624 3.56451673 1.7373997 1 P 0 ;0,1,2=132,3=0.000000
L 3.56451673 1.7373997 3.56681693 1.73946683 1 P 0 ;0,1,2=132,3=0.000000
L 3.56681693 1.73946683 3.56950039 1.7405 1 P 0 ;0,1,2=132,3=0.000000
L 3.56950039 1.7405 3.57256713 1.73946683 1 P 0 ;0,1,2=132,3=0.000000
L 3.57256713 1.73946683 3.57486663 1.7373997 1 P 0 ;0,1,2=132,3=0.000000
L 3.57486663 1.7373997 3.5764003 1.7343003 1 P 0 ;0,1,2=132,3=0.000000
L 3.5764003 1.7343003 3.57716683 1.73016594 1 P 0 ;0,1,2=132,3=0.000000
L 3.57716683 1.73016594 3.5764003 1.7265501 1 P 0 ;0,1,2=132,3=0.000000
L 3.5764003 1.7265501 3.57448337 1.72293327 1 P 0 ;0,1,2=132,3=0.000000
L 3.57448337 1.72293327 3.57218317 1.72086604 1 P 0 ;0,1,2=132,3=0.000000
L 3.57218317 1.72086604 3.56950039 1.72034951 1 P 0 ;0,1,2=132,3=0.000000
L 3.56950039 1.72034951 3.56643366 1.72138268 1 P 0 ;0,1,2=132,3=0.000000
L 3.56643366 1.72138268 3.56413346 1.72396634 1 P 0 ;0,1,2=132,3=0.000000
L 3.56413346 1.72396634 3.56183327 1.72861634 1 P 0 ;0,1,2=132,3=0.000000
L 3.54578356 1.72241575 3.5431001 1.72603356 1 P 0 ;0,1,2=132,3=0.000000
L 3.5431001 1.72603356 3.5407999 1.7280998 1 P 0 ;0,1,2=132,3=0.000000
L 3.5407999 1.7280998 3.53773317 1.72913287 1 P 0 ;0,1,2=132,3=0.000000
L 3.53773317 1.72913287 3.5350497 1.7280998 1 P 0 ;0,1,2=132,3=0.000000
L 3.5350497 1.7280998 3.53313346 1.72603356 1 P 0 ;0,1,2=132,3=0.000000
L 3.53313346 1.72603356 3.5315998 1.72293327 1 P 0 ;0,1,2=132,3=0.000000
L 3.5315998 1.72293327 3.53121654 1.71931644 1 P 0 ;0,1,2=132,3=0.000000
L 3.53121654 1.71931644 3.5315998 1.71621614 1 P 0 ;0,1,2=132,3=0.000000
L 3.5315998 1.71621614 3.53313346 1.71311585 1 P 0 ;0,1,2=132,3=0.000000
L 3.53313346 1.71311585 3.53543366 1.71053307 1 P 0 ;0,1,2=132,3=0.000000
L 3.53543366 1.71053307 3.53811644 1.7095 1 P 0 ;0,1,2=132,3=0.000000
L 3.53811644 1.7095 3.54118317 1.71053307 1 P 0 ;0,1,2=132,3=0.000000
L 3.54118317 1.71053307 3.54386663 1.71363238 1 P 0 ;0,1,2=132,3=0.000000
L 3.54386663 1.71363238 3.5454003 1.71828327 1 P 0 ;0,1,2=132,3=0.000000
L 3.5454003 1.71828327 3.54578356 1.7234498 1 P 0 ;0,1,2=132,3=0.000000
L 3.54578356 1.7234498 3.54501713 1.73016594 1 P 0 ;0,1,2=132,3=0.000000
L 3.54501713 1.73016594 3.54386663 1.73378376 1 P 0 ;0,1,2=132,3=0.000000
L 3.54386663 1.73378376 3.54195039 1.7373997 1 P 0 ;0,1,2=132,3=0.000000
L 3.54195039 1.7373997 3.53926693 1.73998337 1 P 0 ;0,1,2=132,3=0.000000
L 3.53926693 1.73998337 3.53658346 1.7405 1 P 0 ;0,1,2=132,3=0.000000
L 3.53658346 1.7405 3.5339 1.73946683 1 P 0 ;0,1,2=132,3=0.000000
L 3.5339 1.73946683 3.53198297 1.73688307 1 P 0 ;0,1,2=132,3=0.000000
L 0.508 1.51 0.552 1.51 1 P 0 
L 0.552 1.51 0.552 1.42 1 P 0 
L 0.552 1.42 0.508 1.42 1 P 0 
L 0.508 1.42 0.508 1.51 1 P 0 
L 0.5845 1.35083317 0.6155 1.35083317 1 P 0 ;0,1,2=133,3=90.000000
L 0.6155 1.35083317 0.6155 1.36041654 1 P 0 ;0,1,2=133,3=90.000000
L 0.6155 1.36041654 0.61394931 1.36348327 1 P 0 ;0,1,2=133,3=90.000000
L 0.61394931 1.36348327 0.61188307 1.3654002 1 P 0 ;0,1,2=133,3=90.000000
L 0.61188307 1.3654002 0.6077497 1.36616673 1 P 0 ;0,1,2=133,3=90.000000
L 0.6077497 1.36616673 0.60361634 1.3654002 1 P 0 ;0,1,2=133,3=90.000000
L 0.60361634 1.3654002 0.60103356 1.3631 1 P 0 ;0,1,2=133,3=90.000000
L 0.60103356 1.3631 0.59948287 1.36041654 1 P 0 ;0,1,2=133,3=90.000000
L 0.59948287 1.36041654 0.59948287 1.35083317 1 P 0 ;0,1,2=133,3=90.000000
L 0.59948287 1.36041654 0.5845 1.36616673 1 P 0 ;0,1,2=133,3=90.000000
L 0.5845 1.3941 0.6155 1.3941 1 P 0 ;0,1,2=133,3=90.000000
L 0.6155 1.3941 0.59328327 1.37991624 1 P 0 ;0,1,2=133,3=90.000000
L 0.59328327 1.37991624 0.59328327 1.39908366 1 P 0 ;0,1,2=133,3=90.000000
L 0.58811585 1.41398287 0.58553307 1.41666634 1 P 0 ;0,1,2=133,3=90.000000
L 0.58553307 1.41666634 0.5845 1.41973307 1 P 0 ;0,1,2=133,3=90.000000
L 0.5845 1.41973307 0.58553307 1.4227998 1 P 0 ;0,1,2=133,3=90.000000
L 0.58553307 1.4227998 0.58863238 1.42548327 1 P 0 ;0,1,2=133,3=90.000000
L 0.58863238 1.42548327 0.59328327 1.4274002 1 P 0 ;0,1,2=133,3=90.000000
L 0.59328327 1.4274002 0.59793327 1.42816673 1 P 0 ;0,1,2=133,3=90.000000
L 0.59793327 1.42816673 0.60361634 1.42816673 1 P 0 ;0,1,2=133,3=90.000000
L 0.60361634 1.42816673 0.60826624 1.4274002 1 P 0 ;0,1,2=133,3=90.000000
L 0.60826624 1.4274002 0.6123997 1.42548327 1 P 0 ;0,1,2=133,3=90.000000
L 0.6123997 1.42548327 0.61446683 1.42318307 1 P 0 ;0,1,2=133,3=90.000000
L 0.61446683 1.42318307 0.6155 1.42049961 1 P 0 ;0,1,2=133,3=90.000000
L 0.6155 1.42049961 0.61446683 1.41743287 1 P 0 ;0,1,2=133,3=90.000000
L 0.61446683 1.41743287 0.6123997 1.41513337 1 P 0 ;0,1,2=133,3=90.000000
L 0.6123997 1.41513337 0.6093003 1.4135997 1 P 0 ;0,1,2=133,3=90.000000
L 0.6093003 1.4135997 0.60516594 1.41283317 1 P 0 ;0,1,2=133,3=90.000000
L 0.60516594 1.41283317 0.6015501 1.4135997 1 P 0 ;0,1,2=133,3=90.000000
L 0.6015501 1.4135997 0.59793327 1.41551663 1 P 0 ;0,1,2=133,3=90.000000
L 0.59793327 1.41551663 0.59586604 1.41781683 1 P 0 ;0,1,2=133,3=90.000000
L 0.59586604 1.41781683 0.59534951 1.42049961 1 P 0 ;0,1,2=133,3=90.000000
L 0.59534951 1.42049961 0.59638268 1.42356634 1 P 0 ;0,1,2=133,3=90.000000
L 0.59638268 1.42356634 0.59896634 1.42586654 1 P 0 ;0,1,2=133,3=90.000000
L 0.59896634 1.42586654 0.60361634 1.42816673 1 P 0 ;0,1,2=133,3=90.000000
L 0.61033346 1.44421644 0.61343278 1.44651663 1 P 0 ;0,1,2=133,3=90.000000
L 0.61343278 1.44651663 0.61498337 1.4492001 1 P 0 ;0,1,2=133,3=90.000000
L 0.61498337 1.4492001 0.6155 1.45226683 1 P 0 ;0,1,2=133,3=90.000000
L 0.6155 1.45226683 0.61446683 1.4561 1 P 0 ;0,1,2=133,3=90.000000
L 0.61446683 1.4561 0.61188307 1.45878346 1 P 0 ;0,1,2=133,3=90.000000
L 0.61188307 1.45878346 0.60878376 1.45955 1 P 0 ;0,1,2=133,3=90.000000
L 0.60878376 1.45955 0.60568258 1.45916673 1 P 0 ;0,1,2=133,3=90.000000
L 0.60568258 1.45916673 0.6030998 1.45763307 1 P 0 ;0,1,2=133,3=90.000000
L 0.6030998 1.45763307 0.59793327 1.44996663 1 P 0 ;0,1,2=133,3=90.000000
L 0.59793327 1.44996663 0.59431644 1.44651663 1 P 0 ;0,1,2=133,3=90.000000
L 0.59431644 1.44651663 0.58914892 1.44421644 1 P 0 ;0,1,2=133,3=90.000000
L 0.58914892 1.44421644 0.5845 1.4434499 1 P 0 ;0,1,2=133,3=90.000000
L 0.5845 1.4434499 0.5845 1.45955 1 P 0 ;0,1,2=133,3=90.000000
L 0.513 0.95 0.557 0.95 1 P 0 
L 0.557 0.95 0.557 0.86 1 P 0 
L 0.557 0.86 0.513 0.86 1 P 0 
L 0.513 0.86 0.513 0.95 1 P 0 
L 0.5625 0.86666654 0.5875 0.86666654 1 P 0 ;0,1,2=134,3=90.000000
L 0.5875 0.86666654 0.5875 0.87333327 1 P 0 ;0,1,2=134,3=90.000000
L 0.5875 0.87333327 0.58624941 0.87546663 1 P 0 ;0,1,2=134,3=90.000000
L 0.58624941 0.87546663 0.58458317 0.8768001 1 P 0 ;0,1,2=134,3=90.000000
L 0.58458317 0.8768001 0.5812498 0.87733337 1 P 0 ;0,1,2=134,3=90.000000
L 0.5812498 0.87733337 0.57791634 0.8768001 1 P 0 ;0,1,2=134,3=90.000000
L 0.57791634 0.8768001 0.57583346 0.8752 1 P 0 ;0,1,2=134,3=90.000000
L 0.57583346 0.8752 0.57458297 0.87333327 1 P 0 ;0,1,2=134,3=90.000000
L 0.57458297 0.87333327 0.57458297 0.86666654 1 P 0 ;0,1,2=134,3=90.000000
L 0.57458297 0.87333327 0.5625 0.87733337 1 P 0 ;0,1,2=134,3=90.000000
L 0.5625 0.8972 0.5875 0.8972 1 P 0 ;0,1,2=134,3=90.000000
L 0.5875 0.8972 0.56958327 0.88733297 1 P 0 ;0,1,2=134,3=90.000000
L 0.56958327 0.88733297 0.56958327 0.90066693 1 P 0 ;0,1,2=134,3=90.000000
L 0.56541604 0.91146634 0.56333307 0.91333317 1 P 0 ;0,1,2=134,3=90.000000
L 0.56333307 0.91333317 0.5625 0.91546654 1 P 0 ;0,1,2=134,3=90.000000
L 0.5625 0.91546654 0.56333307 0.9175999 1 P 0 ;0,1,2=134,3=90.000000
L 0.56333307 0.9175999 0.56583258 0.91946663 1 P 0 ;0,1,2=134,3=90.000000
L 0.56583258 0.91946663 0.56958327 0.9208001 1 P 0 ;0,1,2=134,3=90.000000
L 0.56958327 0.9208001 0.57333327 0.92133337 1 P 0 ;0,1,2=134,3=90.000000
L 0.57333327 0.92133337 0.57791634 0.92133337 1 P 0 ;0,1,2=134,3=90.000000
L 0.57791634 0.92133337 0.58166634 0.9208001 1 P 0 ;0,1,2=134,3=90.000000
L 0.58166634 0.9208001 0.5849997 0.91946663 1 P 0 ;0,1,2=134,3=90.000000
L 0.5849997 0.91946663 0.58666683 0.91786644 1 P 0 ;0,1,2=134,3=90.000000
L 0.58666683 0.91786644 0.5875 0.9159997 1 P 0 ;0,1,2=134,3=90.000000
L 0.5875 0.9159997 0.58666683 0.91386634 1 P 0 ;0,1,2=134,3=90.000000
L 0.58666683 0.91386634 0.5849997 0.91226663 1 P 0 ;0,1,2=134,3=90.000000
L 0.5849997 0.91226663 0.5825003 0.9111998 1 P 0 ;0,1,2=134,3=90.000000
L 0.5825003 0.9111998 0.57916614 0.91066654 1 P 0 ;0,1,2=134,3=90.000000
L 0.57916614 0.91066654 0.5762501 0.9111998 1 P 0 ;0,1,2=134,3=90.000000
L 0.5762501 0.9111998 0.57333327 0.91253327 1 P 0 ;0,1,2=134,3=90.000000
L 0.57333327 0.91253327 0.57166614 0.91413346 1 P 0 ;0,1,2=134,3=90.000000
L 0.57166614 0.91413346 0.57124961 0.9159997 1 P 0 ;0,1,2=134,3=90.000000
L 0.57124961 0.9159997 0.57208278 0.91813307 1 P 0 ;0,1,2=134,3=90.000000
L 0.57208278 0.91813307 0.57416644 0.91973327 1 P 0 ;0,1,2=134,3=90.000000
L 0.57416644 0.91973327 0.57791634 0.92133337 1 P 0 ;0,1,2=134,3=90.000000
L 0.56749961 0.93213327 0.56458287 0.93373297 1 P 0 ;0,1,2=134,3=90.000000
L 0.56458287 0.93373297 0.56291654 0.93586634 1 P 0 ;0,1,2=134,3=90.000000
L 0.56291654 0.93586634 0.5625 0.93826683 1 P 0 ;0,1,2=134,3=90.000000
L 0.5625 0.93826683 0.56291654 0.9404002 1 P 0 ;0,1,2=134,3=90.000000
L 0.56291654 0.9404002 0.56499941 0.94253356 1 P 0 ;0,1,2=134,3=90.000000
L 0.56499941 0.94253356 0.56749961 0.94386663 1 P 0 ;0,1,2=134,3=90.000000
L 0.56749961 0.94386663 0.5699999 0.94413317 1 P 0 ;0,1,2=134,3=90.000000
L 0.5699999 0.94413317 0.57291594 0.9436 1 P 0 ;0,1,2=134,3=90.000000
L 0.57291594 0.9436 0.57499961 0.94173327 1 P 0 ;0,1,2=134,3=90.000000
L 0.57499961 0.94173327 0.57583346 0.93986644 1 P 0 ;0,1,2=134,3=90.000000
L 0.57583346 0.93986644 0.57583346 0.93746654 1 P 0 ;0,1,2=134,3=90.000000
L 0.57583346 0.93986644 0.57708327 0.94146663 1 P 0 ;0,1,2=134,3=90.000000
L 0.57708327 0.94146663 0.57916614 0.9428001 1 P 0 ;0,1,2=134,3=90.000000
L 0.57916614 0.9428001 0.58166634 0.94333337 1 P 0 ;0,1,2=134,3=90.000000
L 0.58166634 0.94333337 0.58416654 0.9428001 1 P 0 ;0,1,2=134,3=90.000000
L 0.58416654 0.9428001 0.58624941 0.94146663 1 P 0 ;0,1,2=134,3=90.000000
L 0.58624941 0.94146663 0.5875 0.93906663 1 P 0 ;0,1,2=134,3=90.000000
L 0.5875 0.93906663 0.58708337 0.93666663 1 P 0 ;0,1,2=134,3=90.000000
L 0.58708337 0.93666663 0.58541634 0.93426663 1 P 0 ;0,1,2=134,3=90.000000
L 0.552 2.65 0.552 2.56 1 P 0 
L 0.552 2.56 0.508 2.56 1 P 0 
L 0.508 2.56 0.508 2.65 1 P 0 
L 0.508 2.65 0.552 2.65 1 P 0 
L 0.5645 2.55083317 0.5955 2.55083317 1 P 0 ;0,1,2=135,3=90.000000
L 0.5955 2.55083317 0.5955 2.56041654 1 P 0 ;0,1,2=135,3=90.000000
L 0.5955 2.56041654 0.59394931 2.56348327 1 P 0 ;0,1,2=135,3=90.000000
L 0.59394931 2.56348327 0.59188307 2.5654002 1 P 0 ;0,1,2=135,3=90.000000
L 0.59188307 2.5654002 0.5877497 2.56616673 1 P 0 ;0,1,2=135,3=90.000000
L 0.5877497 2.56616673 0.58361634 2.5654002 1 P 0 ;0,1,2=135,3=90.000000
L 0.58361634 2.5654002 0.58103356 2.5631 1 P 0 ;0,1,2=135,3=90.000000
L 0.58103356 2.5631 0.57948287 2.56041654 1 P 0 ;0,1,2=135,3=90.000000
L 0.57948287 2.56041654 0.57948287 2.55083317 1 P 0 ;0,1,2=135,3=90.000000
L 0.57948287 2.56041654 0.5645 2.56616673 1 P 0 ;0,1,2=135,3=90.000000
L 0.5645 2.5941 0.5955 2.5941 1 P 0 ;0,1,2=135,3=90.000000
L 0.5955 2.5941 0.57328327 2.57991624 1 P 0 ;0,1,2=135,3=90.000000
L 0.57328327 2.57991624 0.57328327 2.59908366 1 P 0 ;0,1,2=135,3=90.000000
L 0.56811585 2.61398287 0.56553307 2.61666634 1 P 0 ;0,1,2=135,3=90.000000
L 0.56553307 2.61666634 0.5645 2.61973307 1 P 0 ;0,1,2=135,3=90.000000
L 0.5645 2.61973307 0.56553307 2.6227998 1 P 0 ;0,1,2=135,3=90.000000
L 0.56553307 2.6227998 0.56863238 2.62548327 1 P 0 ;0,1,2=135,3=90.000000
L 0.56863238 2.62548327 0.57328327 2.6274002 1 P 0 ;0,1,2=135,3=90.000000
L 0.57328327 2.6274002 0.57793327 2.62816673 1 P 0 ;0,1,2=135,3=90.000000
L 0.57793327 2.62816673 0.58361634 2.62816673 1 P 0 ;0,1,2=135,3=90.000000
L 0.58361634 2.62816673 0.58826624 2.6274002 1 P 0 ;0,1,2=135,3=90.000000
L 0.58826624 2.6274002 0.5923997 2.62548327 1 P 0 ;0,1,2=135,3=90.000000
L 0.5923997 2.62548327 0.59446683 2.62318307 1 P 0 ;0,1,2=135,3=90.000000
L 0.59446683 2.62318307 0.5955 2.62049961 1 P 0 ;0,1,2=135,3=90.000000
L 0.5955 2.62049961 0.59446683 2.61743287 1 P 0 ;0,1,2=135,3=90.000000
L 0.59446683 2.61743287 0.5923997 2.61513337 1 P 0 ;0,1,2=135,3=90.000000
L 0.5923997 2.61513337 0.5893003 2.6135997 1 P 0 ;0,1,2=135,3=90.000000
L 0.5893003 2.6135997 0.58516594 2.61283317 1 P 0 ;0,1,2=135,3=90.000000
L 0.58516594 2.61283317 0.5815501 2.6135997 1 P 0 ;0,1,2=135,3=90.000000
L 0.5815501 2.6135997 0.57793327 2.61551663 1 P 0 ;0,1,2=135,3=90.000000
L 0.57793327 2.61551663 0.57586604 2.61781683 1 P 0 ;0,1,2=135,3=90.000000
L 0.57586604 2.61781683 0.57534951 2.62049961 1 P 0 ;0,1,2=135,3=90.000000
L 0.57534951 2.62049961 0.57638268 2.62356634 1 P 0 ;0,1,2=135,3=90.000000
L 0.57638268 2.62356634 0.57896634 2.62586654 1 P 0 ;0,1,2=135,3=90.000000
L 0.57896634 2.62586654 0.58361634 2.62816673 1 P 0 ;0,1,2=135,3=90.000000
L 0.5645 2.6561 0.5955 2.6561 1 P 0 ;0,1,2=135,3=90.000000
L 0.5955 2.6561 0.57328327 2.64191624 1 P 0 ;0,1,2=135,3=90.000000
L 0.57328327 2.64191624 0.57328327 2.66108366 1 P 0 ;0,1,2=135,3=90.000000
L 0.552 2.115 0.552 2.025 1 P 0 
L 0.552 2.025 0.508 2.025 1 P 0 
L 0.508 2.025 0.508 2.115 1 P 0 
L 0.508 2.115 0.552 2.115 1 P 0 
L 0.5595 2.01583317 0.5905 2.01583317 1 P 0 ;0,1,2=136,3=90.000000
L 0.5905 2.01583317 0.5905 2.02541654 1 P 0 ;0,1,2=136,3=90.000000
L 0.5905 2.02541654 0.58894931 2.02848327 1 P 0 ;0,1,2=136,3=90.000000
L 0.58894931 2.02848327 0.58688307 2.0304002 1 P 0 ;0,1,2=136,3=90.000000
L 0.58688307 2.0304002 0.5827497 2.03116673 1 P 0 ;0,1,2=136,3=90.000000
L 0.5827497 2.03116673 0.57861634 2.0304002 1 P 0 ;0,1,2=136,3=90.000000
L 0.57861634 2.0304002 0.57603356 2.0281 1 P 0 ;0,1,2=136,3=90.000000
L 0.57603356 2.0281 0.57448287 2.02541654 1 P 0 ;0,1,2=136,3=90.000000
L 0.57448287 2.02541654 0.57448287 2.01583317 1 P 0 ;0,1,2=136,3=90.000000
L 0.57448287 2.02541654 0.5595 2.03116673 1 P 0 ;0,1,2=136,3=90.000000
L 0.5595 2.0591 0.5905 2.0591 1 P 0 ;0,1,2=136,3=90.000000
L 0.5905 2.0591 0.56828327 2.04491624 1 P 0 ;0,1,2=136,3=90.000000
L 0.56828327 2.04491624 0.56828327 2.06408366 1 P 0 ;0,1,2=136,3=90.000000
L 0.56311585 2.07898287 0.56053307 2.08166634 1 P 0 ;0,1,2=136,3=90.000000
L 0.56053307 2.08166634 0.5595 2.08473307 1 P 0 ;0,1,2=136,3=90.000000
L 0.5595 2.08473307 0.56053307 2.0877998 1 P 0 ;0,1,2=136,3=90.000000
L 0.56053307 2.0877998 0.56363238 2.09048327 1 P 0 ;0,1,2=136,3=90.000000
L 0.56363238 2.09048327 0.56828327 2.0924002 1 P 0 ;0,1,2=136,3=90.000000
L 0.56828327 2.0924002 0.57293327 2.09316673 1 P 0 ;0,1,2=136,3=90.000000
L 0.57293327 2.09316673 0.57861634 2.09316673 1 P 0 ;0,1,2=136,3=90.000000
L 0.57861634 2.09316673 0.58326624 2.0924002 1 P 0 ;0,1,2=136,3=90.000000
L 0.58326624 2.0924002 0.5873997 2.09048327 1 P 0 ;0,1,2=136,3=90.000000
L 0.5873997 2.09048327 0.58946683 2.08818307 1 P 0 ;0,1,2=136,3=90.000000
L 0.58946683 2.08818307 0.5905 2.08549961 1 P 0 ;0,1,2=136,3=90.000000
L 0.5905 2.08549961 0.58946683 2.08243287 1 P 0 ;0,1,2=136,3=90.000000
L 0.58946683 2.08243287 0.5873997 2.08013337 1 P 0 ;0,1,2=136,3=90.000000
L 0.5873997 2.08013337 0.5843003 2.0785997 1 P 0 ;0,1,2=136,3=90.000000
L 0.5843003 2.0785997 0.58016594 2.07783317 1 P 0 ;0,1,2=136,3=90.000000
L 0.58016594 2.07783317 0.5765501 2.0785997 1 P 0 ;0,1,2=136,3=90.000000
L 0.5765501 2.0785997 0.57293327 2.08051663 1 P 0 ;0,1,2=136,3=90.000000
L 0.57293327 2.08051663 0.57086604 2.08281683 1 P 0 ;0,1,2=136,3=90.000000
L 0.57086604 2.08281683 0.57034951 2.08549961 1 P 0 ;0,1,2=136,3=90.000000
L 0.57034951 2.08549961 0.57138268 2.08856634 1 P 0 ;0,1,2=136,3=90.000000
L 0.57138268 2.08856634 0.57396634 2.09086654 1 P 0 ;0,1,2=136,3=90.000000
L 0.57396634 2.09086654 0.57861634 2.09316673 1 P 0 ;0,1,2=136,3=90.000000
L 0.56414892 2.10806663 0.56156614 2.11036614 1 P 0 ;0,1,2=136,3=90.000000
L 0.56156614 2.11036614 0.56001654 2.11304961 1 P 0 ;0,1,2=136,3=90.000000
L 0.56001654 2.11304961 0.5595 2.11649961 1 P 0 ;0,1,2=136,3=90.000000
L 0.5595 2.11649961 0.56053307 2.1199503 1 P 0 ;0,1,2=136,3=90.000000
L 0.56053307 2.1199503 0.56259931 2.12263307 1 P 0 ;0,1,2=136,3=90.000000
L 0.56259931 2.12263307 0.56621614 2.12455 1 P 0 ;0,1,2=136,3=90.000000
L 0.56621614 2.12455 0.57034951 2.12493327 1 P 0 ;0,1,2=136,3=90.000000
L 0.57034951 2.12493327 0.57448287 2.12416673 1 P 0 ;0,1,2=136,3=90.000000
L 0.57448287 2.12416673 0.57706663 2.1222498 1 P 0 ;0,1,2=136,3=90.000000
L 0.57706663 2.1222498 0.57913287 2.11956634 1 P 0 ;0,1,2=136,3=90.000000
L 0.57913287 2.11956634 0.57964941 2.11688356 1 P 0 ;0,1,2=136,3=90.000000
L 0.57964941 2.11688356 0.57913287 2.1142001 1 P 0 ;0,1,2=136,3=90.000000
L 0.57913287 2.1142001 0.57706663 2.1107501 1 P 0 ;0,1,2=136,3=90.000000
L 0.57706663 2.1107501 0.5905 2.1118999 1 P 0 ;0,1,2=136,3=90.000000
L 0.5905 2.1118999 0.5905 2.1222498 1 P 0 ;0,1,2=136,3=90.000000
L 4.705 1.777 4.705 1.733 1 P 0 
L 4.705 1.733 4.615 1.733 1 P 0 
L 4.615 1.733 4.615 1.777 1 P 0 
L 4.615 1.777 4.705 1.777 1 P 0 
L 4.78833346 1.7075 4.78833346 1.7325 1 P 0 ;0,1,2=137,3=0.000000
L 4.78833346 1.7325 4.78166673 1.7325 1 P 0 ;0,1,2=137,3=0.000000
L 4.78166673 1.7325 4.77953337 1.73124941 1 P 0 ;0,1,2=137,3=0.000000
L 4.77953337 1.73124941 4.7781999 1.72958317 1 P 0 ;0,1,2=137,3=0.000000
L 4.7781999 1.72958317 4.77766663 1.7262498 1 P 0 ;0,1,2=137,3=0.000000
L 4.77766663 1.7262498 4.7781999 1.72291634 1 P 0 ;0,1,2=137,3=0.000000
L 4.7781999 1.72291634 4.7798 1.72083346 1 P 0 ;0,1,2=137,3=0.000000
L 4.7798 1.72083346 4.78166673 1.71958297 1 P 0 ;0,1,2=137,3=0.000000
L 4.78166673 1.71958297 4.78833346 1.71958297 1 P 0 ;0,1,2=137,3=0.000000
L 4.78166673 1.71958297 4.77766663 1.7075 1 P 0 ;0,1,2=137,3=0.000000
L 4.76686673 1.71124911 4.76526703 1.70916624 1 P 0 ;0,1,2=137,3=0.000000
L 4.76526703 1.70916624 4.7634003 1.70791654 1 P 0 ;0,1,2=137,3=0.000000
L 4.7634003 1.70791654 4.7610003 1.7075 1 P 0 ;0,1,2=137,3=0.000000
L 4.7610003 1.7075 4.7585998 1.70833307 1 P 0 ;0,1,2=137,3=0.000000
L 4.7585998 1.70833307 4.75673356 1.70999941 1 P 0 ;0,1,2=137,3=0.000000
L 4.75673356 1.70999941 4.7554 1.71291624 1 P 0 ;0,1,2=137,3=0.000000
L 4.7554 1.71291624 4.75513337 1.71624961 1 P 0 ;0,1,2=137,3=0.000000
L 4.75513337 1.71624961 4.75566663 1.71958297 1 P 0 ;0,1,2=137,3=0.000000
L 4.75566663 1.71958297 4.7570002 1.72166663 1 P 0 ;0,1,2=137,3=0.000000
L 4.7570002 1.72166663 4.75886693 1.72333297 1 P 0 ;0,1,2=137,3=0.000000
L 4.75886693 1.72333297 4.76073317 1.72374951 1 P 0 ;0,1,2=137,3=0.000000
L 4.76073317 1.72374951 4.7626 1.72333297 1 P 0 ;0,1,2=137,3=0.000000
L 4.7626 1.72333297 4.7649999 1.72166663 1 P 0 ;0,1,2=137,3=0.000000
L 4.7649999 1.72166663 4.7642001 1.7325 1 P 0 ;0,1,2=137,3=0.000000
L 4.7642001 1.7325 4.7570002 1.7325 1 P 0 ;0,1,2=137,3=0.000000
L 4.7390003 1.7325 4.74113366 1.73166683 1 P 0 ;0,1,2=137,3=0.000000
L 4.74113366 1.73166683 4.74273337 1.72958317 1 P 0 ;0,1,2=137,3=0.000000
L 4.74273337 1.72958317 4.7438002 1.72708366 1 P 0 ;0,1,2=137,3=0.000000
L 4.7438002 1.72708366 4.7446001 1.72374951 1 P 0 ;0,1,2=137,3=0.000000
L 4.7446001 1.72374951 4.74486673 1.71999961 1 P 0 ;0,1,2=137,3=0.000000
L 4.74486673 1.71999961 4.7446001 1.71624961 1 P 0 ;0,1,2=137,3=0.000000
L 4.7446001 1.71624961 4.7438002 1.71291624 1 P 0 ;0,1,2=137,3=0.000000
L 4.7438002 1.71291624 4.74273337 1.71041604 1 P 0 ;0,1,2=137,3=0.000000
L 4.74273337 1.71041604 4.74113366 1.70833307 1 P 0 ;0,1,2=137,3=0.000000
L 4.74113366 1.70833307 4.7390003 1.7075 1 P 0 ;0,1,2=137,3=0.000000
L 4.7390003 1.7075 4.73686693 1.70833307 1 P 0 ;0,1,2=137,3=0.000000
L 4.73686693 1.70833307 4.73526673 1.71041604 1 P 0 ;0,1,2=137,3=0.000000
L 4.73526673 1.71041604 4.7341999 1.71291624 1 P 0 ;0,1,2=137,3=0.000000
L 4.7341999 1.71291624 4.7334 1.71624961 1 P 0 ;0,1,2=137,3=0.000000
L 4.7334 1.71624961 4.73313337 1.71999961 1 P 0 ;0,1,2=137,3=0.000000
L 4.73313337 1.71999961 4.7334 1.72374951 1 P 0 ;0,1,2=137,3=0.000000
L 4.7334 1.72374951 4.7341999 1.72708366 1 P 0 ;0,1,2=137,3=0.000000
L 4.7341999 1.72708366 4.73526673 1.72958317 1 P 0 ;0,1,2=137,3=0.000000
L 4.73526673 1.72958317 4.73686693 1.73166683 1 P 0 ;0,1,2=137,3=0.000000
L 4.73686693 1.73166683 4.7390003 1.7325 1 P 0 ;0,1,2=137,3=0.000000
L 4.7170003 1.7075 4.7170003 1.7325 1 P 0 ;0,1,2=137,3=0.000000
L 4.7170003 1.7325 4.7202001 1.7275003 1 P 0 ;0,1,2=137,3=0.000000
L 4.7202001 1.7075 4.71380049 1.7075 1 P 0 ;0,1,2=137,3=0.000000
L 4.76 0.987 4.76 0.943 1 P 0 
L 4.67 0.987 4.76 0.987 1 P 0 
L 4.76 0.943 4.67 0.943 1 P 0 
L 4.67 0.943 4.67 0.987 1 P 0 
L 4.76916683 0.9995 4.76916683 1.0305 1 P 0 ;0,1,2=138,3=0.000000
L 4.76916683 1.0305 4.75958346 1.0305 1 P 0 ;0,1,2=138,3=0.000000
L 4.75958346 1.0305 4.75651673 1.02894931 1 P 0 ;0,1,2=138,3=0.000000
L 4.75651673 1.02894931 4.7545998 1.02688307 1 P 0 ;0,1,2=138,3=0.000000
L 4.7545998 1.02688307 4.75383327 1.0227497 1 P 0 ;0,1,2=138,3=0.000000
L 4.75383327 1.0227497 4.7545998 1.01861634 1 P 0 ;0,1,2=138,3=0.000000
L 4.7545998 1.01861634 4.7569 1.01603356 1 P 0 ;0,1,2=138,3=0.000000
L 4.7569 1.01603356 4.75958346 1.01448287 1 P 0 ;0,1,2=138,3=0.000000
L 4.75958346 1.01448287 4.76916683 1.01448287 1 P 0 ;0,1,2=138,3=0.000000
L 4.75958346 1.01448287 4.75383327 0.9995 1 P 0 ;0,1,2=138,3=0.000000
L 4.7259 0.9995 4.7259 1.0305 1 P 0 ;0,1,2=138,3=0.000000
L 4.7259 1.0305 4.74008376 1.00828327 1 P 0 ;0,1,2=138,3=0.000000
L 4.74008376 1.00828327 4.72091634 1.00828327 1 P 0 ;0,1,2=138,3=0.000000
L 4.69950039 0.9995 4.69681693 1.00001654 1 P 0 ;0,1,2=138,3=0.000000
L 4.69681693 1.00001654 4.6937502 1.00156614 1 P 0 ;0,1,2=138,3=0.000000
L 4.6937502 1.00156614 4.69183327 1.00414892 1 P 0 ;0,1,2=138,3=0.000000
L 4.69183327 1.00414892 4.69106673 1.00776673 1 P 0 ;0,1,2=138,3=0.000000
L 4.69106673 1.00776673 4.69183327 1.01138268 1 P 0 ;0,1,2=138,3=0.000000
L 4.69183327 1.01138268 4.69413346 1.01448287 1 P 0 ;0,1,2=138,3=0.000000
L 4.69413346 1.01448287 4.69758346 1.01603356 1 P 0 ;0,1,2=138,3=0.000000
L 4.69758346 1.01603356 4.70141663 1.01603356 1 P 0 ;0,1,2=138,3=0.000000
L 4.70141663 1.01603356 4.70371683 1.01706663 1 P 0 ;0,1,2=138,3=0.000000
L 4.70371683 1.01706663 4.70563386 1.01964941 1 P 0 ;0,1,2=138,3=0.000000
L 4.70563386 1.01964941 4.7064003 1.02326624 1 P 0 ;0,1,2=138,3=0.000000
L 4.7064003 1.02326624 4.7052499 1.02688307 1 P 0 ;0,1,2=138,3=0.000000
L 4.7052499 1.02688307 4.70256713 1.02946683 1 P 0 ;0,1,2=138,3=0.000000
L 4.70256713 1.02946683 4.69950039 1.0305 1 P 0 ;0,1,2=138,3=0.000000
L 4.69950039 1.0305 4.69643366 1.02946683 1 P 0 ;0,1,2=138,3=0.000000
L 4.69643366 1.02946683 4.6937502 1.02688307 1 P 0 ;0,1,2=138,3=0.000000
L 4.6937502 1.02688307 4.6925998 1.02326624 1 P 0 ;0,1,2=138,3=0.000000
L 4.6925998 1.02326624 4.69336693 1.01964941 1 P 0 ;0,1,2=138,3=0.000000
L 4.69336693 1.01964941 4.69528327 1.01706663 1 P 0 ;0,1,2=138,3=0.000000
L 4.69528327 1.01706663 4.69758346 1.01603356 1 P 0 ;0,1,2=138,3=0.000000
L 4.69758346 1.01603356 4.70141663 1.01603356 1 P 0 ;0,1,2=138,3=0.000000
L 4.70141663 1.01603356 4.70486663 1.01448287 1 P 0 ;0,1,2=138,3=0.000000
L 4.70486663 1.01448287 4.70716683 1.01138268 1 P 0 ;0,1,2=138,3=0.000000
L 4.70716683 1.01138268 4.70793337 1.00776673 1 P 0 ;0,1,2=138,3=0.000000
L 4.70793337 1.00776673 4.70716683 1.00414892 1 P 0 ;0,1,2=138,3=0.000000
L 4.70716683 1.00414892 4.7052499 1.00156614 1 P 0 ;0,1,2=138,3=0.000000
L 4.7052499 1.00156614 4.70218317 1.00001654 1 P 0 ;0,1,2=138,3=0.000000
L 4.70218317 1.00001654 4.69950039 0.9995 1 P 0 ;0,1,2=138,3=0.000000
L 4.67578356 1.02533346 4.67348337 1.02843278 1 P 0 ;0,1,2=138,3=0.000000
L 4.67348337 1.02843278 4.6707999 1.02998337 1 P 0 ;0,1,2=138,3=0.000000
L 4.6707999 1.02998337 4.66773317 1.0305 1 P 0 ;0,1,2=138,3=0.000000
L 4.66773317 1.0305 4.6639 1.02946683 1 P 0 ;0,1,2=138,3=0.000000
L 4.6639 1.02946683 4.66121654 1.02688307 1 P 0 ;0,1,2=138,3=0.000000
L 4.66121654 1.02688307 4.66045 1.02378376 1 P 0 ;0,1,2=138,3=0.000000
L 4.66045 1.02378376 4.66083327 1.02068258 1 P 0 ;0,1,2=138,3=0.000000
L 4.66083327 1.02068258 4.66236693 1.0180998 1 P 0 ;0,1,2=138,3=0.000000
L 4.66236693 1.0180998 4.67003337 1.01293327 1 P 0 ;0,1,2=138,3=0.000000
L 4.67003337 1.01293327 4.67348337 1.00931644 1 P 0 ;0,1,2=138,3=0.000000
L 4.67348337 1.00931644 4.67578356 1.00414892 1 P 0 ;0,1,2=138,3=0.000000
L 4.67578356 1.00414892 4.6765501 0.9995 1 P 0 ;0,1,2=138,3=0.000000
L 4.6765501 0.9995 4.66045 0.9995 1 P 0 ;0,1,2=138,3=0.000000
L 4.039 3.313 4.039 3.269 1 P 0 
L 3.949 3.313 4.039 3.313 1 P 0 
L 4.039 3.269 3.949 3.269 1 P 0 
L 3.949 3.269 3.949 3.313 1 P 0 
L 4.05416683 3.3195 4.05416683 3.3505 1 P 0 ;0,1,2=139,3=0.000000
L 4.05416683 3.3505 4.04458346 3.3505 1 P 0 ;0,1,2=139,3=0.000000
L 4.04458346 3.3505 4.04151673 3.34894931 1 P 0 ;0,1,2=139,3=0.000000
L 4.04151673 3.34894931 4.0395998 3.34688307 1 P 0 ;0,1,2=139,3=0.000000
L 4.0395998 3.34688307 4.03883327 3.3427497 1 P 0 ;0,1,2=139,3=0.000000
L 4.03883327 3.3427497 4.0395998 3.33861634 1 P 0 ;0,1,2=139,3=0.000000
L 4.0395998 3.33861634 4.0419 3.33603356 1 P 0 ;0,1,2=139,3=0.000000
L 4.0419 3.33603356 4.04458346 3.33448287 1 P 0 ;0,1,2=139,3=0.000000
L 4.04458346 3.33448287 4.05416683 3.33448287 1 P 0 ;0,1,2=139,3=0.000000
L 4.04458346 3.33448287 4.03883327 3.3195 1 P 0 ;0,1,2=139,3=0.000000
L 4.0109 3.3195 4.0109 3.3505 1 P 0 ;0,1,2=139,3=0.000000
L 4.0109 3.3505 4.02508376 3.32828327 1 P 0 ;0,1,2=139,3=0.000000
L 4.02508376 3.32828327 4.00591634 3.32828327 1 P 0 ;0,1,2=139,3=0.000000
L 3.99293337 3.32414892 3.99063386 3.32156614 1 P 0 ;0,1,2=139,3=0.000000
L 3.99063386 3.32156614 3.98795039 3.32001654 1 P 0 ;0,1,2=139,3=0.000000
L 3.98795039 3.32001654 3.98450039 3.3195 1 P 0 ;0,1,2=139,3=0.000000
L 3.98450039 3.3195 3.9810497 3.32053307 1 P 0 ;0,1,2=139,3=0.000000
L 3.9810497 3.32053307 3.97836693 3.32259931 1 P 0 ;0,1,2=139,3=0.000000
L 3.97836693 3.32259931 3.97645 3.32621614 1 P 0 ;0,1,2=139,3=0.000000
L 3.97645 3.32621614 3.97606673 3.33034951 1 P 0 ;0,1,2=139,3=0.000000
L 3.97606673 3.33034951 3.97683327 3.33448287 1 P 0 ;0,1,2=139,3=0.000000
L 3.97683327 3.33448287 3.9787502 3.33706663 1 P 0 ;0,1,2=139,3=0.000000
L 3.9787502 3.33706663 3.98143366 3.33913287 1 P 0 ;0,1,2=139,3=0.000000
L 3.98143366 3.33913287 3.98411644 3.33964941 1 P 0 ;0,1,2=139,3=0.000000
L 3.98411644 3.33964941 3.9867999 3.33913287 1 P 0 ;0,1,2=139,3=0.000000
L 3.9867999 3.33913287 3.9902499 3.33706663 1 P 0 ;0,1,2=139,3=0.000000
L 3.9902499 3.33706663 3.9891001 3.3505 1 P 0 ;0,1,2=139,3=0.000000
L 3.9891001 3.3505 3.9787502 3.3505 1 P 0 ;0,1,2=139,3=0.000000
L 3.95426693 3.3195 3.95350039 3.32621614 1 P 0 ;0,1,2=139,3=0.000000
L 3.95350039 3.32621614 3.9523499 3.33189921 1 P 0 ;0,1,2=139,3=0.000000
L 3.9523499 3.33189921 3.95081693 3.33706663 1 P 0 ;0,1,2=139,3=0.000000
L 3.95081693 3.33706663 3.9489 3.3427497 1 P 0 ;0,1,2=139,3=0.000000
L 3.9489 3.3427497 3.94583327 3.3505 1 P 0 ;0,1,2=139,3=0.000000
L 3.94583327 3.3505 3.96116683 3.3505 1 P 0 ;0,1,2=139,3=0.000000
L 3.905 3.832 3.905 3.788 1 P 0 
L 3.905 3.788 3.815 3.788 1 P 0 
L 3.815 3.788 3.815 3.832 1 P 0 
L 3.815 3.832 3.905 3.832 1 P 0 
L 3.87916683 3.8595 3.87916683 3.8905 1 P 0 ;0,1,2=140,3=0.000000
L 3.87916683 3.8905 3.86958346 3.8905 1 P 0 ;0,1,2=140,3=0.000000
L 3.86958346 3.8905 3.86651673 3.88894931 1 P 0 ;0,1,2=140,3=0.000000
L 3.86651673 3.88894931 3.8645998 3.88688307 1 P 0 ;0,1,2=140,3=0.000000
L 3.8645998 3.88688307 3.86383327 3.8827497 1 P 0 ;0,1,2=140,3=0.000000
L 3.86383327 3.8827497 3.8645998 3.87861634 1 P 0 ;0,1,2=140,3=0.000000
L 3.8645998 3.87861634 3.8669 3.87603356 1 P 0 ;0,1,2=140,3=0.000000
L 3.8669 3.87603356 3.86958346 3.87448287 1 P 0 ;0,1,2=140,3=0.000000
L 3.86958346 3.87448287 3.87916683 3.87448287 1 P 0 ;0,1,2=140,3=0.000000
L 3.86958346 3.87448287 3.86383327 3.8595 1 P 0 ;0,1,2=140,3=0.000000
L 3.8359 3.8595 3.8359 3.8905 1 P 0 ;0,1,2=140,3=0.000000
L 3.8359 3.8905 3.85008376 3.86828327 1 P 0 ;0,1,2=140,3=0.000000
L 3.85008376 3.86828327 3.83091634 3.86828327 1 P 0 ;0,1,2=140,3=0.000000
L 3.81793337 3.86414892 3.81563386 3.86156614 1 P 0 ;0,1,2=140,3=0.000000
L 3.81563386 3.86156614 3.81295039 3.86001654 1 P 0 ;0,1,2=140,3=0.000000
L 3.81295039 3.86001654 3.80950039 3.8595 1 P 0 ;0,1,2=140,3=0.000000
L 3.80950039 3.8595 3.8060497 3.86053307 1 P 0 ;0,1,2=140,3=0.000000
L 3.8060497 3.86053307 3.80336693 3.86259931 1 P 0 ;0,1,2=140,3=0.000000
L 3.80336693 3.86259931 3.80145 3.86621614 1 P 0 ;0,1,2=140,3=0.000000
L 3.80145 3.86621614 3.80106673 3.87034951 1 P 0 ;0,1,2=140,3=0.000000
L 3.80106673 3.87034951 3.80183327 3.87448287 1 P 0 ;0,1,2=140,3=0.000000
L 3.80183327 3.87448287 3.8037502 3.87706663 1 P 0 ;0,1,2=140,3=0.000000
L 3.8037502 3.87706663 3.80643366 3.87913287 1 P 0 ;0,1,2=140,3=0.000000
L 3.80643366 3.87913287 3.80911644 3.87964941 1 P 0 ;0,1,2=140,3=0.000000
L 3.80911644 3.87964941 3.8117999 3.87913287 1 P 0 ;0,1,2=140,3=0.000000
L 3.8117999 3.87913287 3.8152499 3.87706663 1 P 0 ;0,1,2=140,3=0.000000
L 3.8152499 3.87706663 3.8141001 3.8905 1 P 0 ;0,1,2=140,3=0.000000
L 3.8141001 3.8905 3.8037502 3.8905 1 P 0 ;0,1,2=140,3=0.000000
L 3.77850039 3.8905 3.78156713 3.88946683 1 P 0 ;0,1,2=140,3=0.000000
L 3.78156713 3.88946683 3.78386663 3.88688307 1 P 0 ;0,1,2=140,3=0.000000
L 3.78386663 3.88688307 3.7854003 3.88378376 1 P 0 ;0,1,2=140,3=0.000000
L 3.7854003 3.88378376 3.7865501 3.87964941 1 P 0 ;0,1,2=140,3=0.000000
L 3.7865501 3.87964941 3.78693337 3.87499951 1 P 0 ;0,1,2=140,3=0.000000
L 3.78693337 3.87499951 3.7865501 3.87034951 1 P 0 ;0,1,2=140,3=0.000000
L 3.7865501 3.87034951 3.7854003 3.86621614 1 P 0 ;0,1,2=140,3=0.000000
L 3.7854003 3.86621614 3.78386663 3.86311585 1 P 0 ;0,1,2=140,3=0.000000
L 3.78386663 3.86311585 3.78156713 3.86053307 1 P 0 ;0,1,2=140,3=0.000000
L 3.78156713 3.86053307 3.77850039 3.8595 1 P 0 ;0,1,2=140,3=0.000000
L 3.77850039 3.8595 3.77543366 3.86053307 1 P 0 ;0,1,2=140,3=0.000000
L 3.77543366 3.86053307 3.77313346 3.86311585 1 P 0 ;0,1,2=140,3=0.000000
L 3.77313346 3.86311585 3.7715998 3.86621614 1 P 0 ;0,1,2=140,3=0.000000
L 3.7715998 3.86621614 3.77045 3.87034951 1 P 0 ;0,1,2=140,3=0.000000
L 3.77045 3.87034951 3.77006673 3.87499951 1 P 0 ;0,1,2=140,3=0.000000
L 3.77006673 3.87499951 3.77045 3.87964941 1 P 0 ;0,1,2=140,3=0.000000
L 3.77045 3.87964941 3.7715998 3.88378376 1 P 0 ;0,1,2=140,3=0.000000
L 3.7715998 3.88378376 3.77313346 3.88688307 1 P 0 ;0,1,2=140,3=0.000000
L 3.77313346 3.88688307 3.77543366 3.88946683 1 P 0 ;0,1,2=140,3=0.000000
L 3.77543366 3.88946683 3.77850039 3.8905 1 P 0 ;0,1,2=140,3=0.000000
L 4.128 2.576 4.172 2.576 1 P 0 
L 4.172 2.576 4.172 2.486 1 P 0 
L 4.172 2.486 4.128 2.486 1 P 0 
L 4.128 2.486 4.128 2.576 1 P 0 
L 4.1295 2.61583317 4.1605 2.61583317 1 P 0 ;0,1,2=141,3=90.000000
L 4.1605 2.61583317 4.1605 2.62541654 1 P 0 ;0,1,2=141,3=90.000000
L 4.1605 2.62541654 4.15894931 2.62848327 1 P 0 ;0,1,2=141,3=90.000000
L 4.15894931 2.62848327 4.15688307 2.6304002 1 P 0 ;0,1,2=141,3=90.000000
L 4.15688307 2.6304002 4.1527497 2.63116673 1 P 0 ;0,1,2=141,3=90.000000
L 4.1527497 2.63116673 4.14861634 2.6304002 1 P 0 ;0,1,2=141,3=90.000000
L 4.14861634 2.6304002 4.14603356 2.6281 1 P 0 ;0,1,2=141,3=90.000000
L 4.14603356 2.6281 4.14448287 2.62541654 1 P 0 ;0,1,2=141,3=90.000000
L 4.14448287 2.62541654 4.14448287 2.61583317 1 P 0 ;0,1,2=141,3=90.000000
L 4.14448287 2.62541654 4.1295 2.63116673 1 P 0 ;0,1,2=141,3=90.000000
L 4.13569961 2.64606663 4.13208278 2.64836614 1 P 0 ;0,1,2=141,3=90.000000
L 4.13208278 2.64836614 4.13001654 2.65143287 1 P 0 ;0,1,2=141,3=90.000000
L 4.13001654 2.65143287 4.1295 2.65488356 1 P 0 ;0,1,2=141,3=90.000000
L 4.1295 2.65488356 4.13001654 2.6579503 1 P 0 ;0,1,2=141,3=90.000000
L 4.13001654 2.6579503 4.13259931 2.66101703 1 P 0 ;0,1,2=141,3=90.000000
L 4.13259931 2.66101703 4.13569961 2.66293327 1 P 0 ;0,1,2=141,3=90.000000
L 4.13569961 2.66293327 4.1387999 2.66331654 1 P 0 ;0,1,2=141,3=90.000000
L 4.1387999 2.66331654 4.14241575 2.66255 1 P 0 ;0,1,2=141,3=90.000000
L 4.14241575 2.66255 4.14499951 2.65986654 1 P 0 ;0,1,2=141,3=90.000000
L 4.14499951 2.65986654 4.14603356 2.65718307 1 P 0 ;0,1,2=141,3=90.000000
L 4.14603356 2.65718307 4.14603356 2.65373307 1 P 0 ;0,1,2=141,3=90.000000
L 4.14603356 2.65718307 4.14758317 2.65948327 1 P 0 ;0,1,2=141,3=90.000000
L 4.14758317 2.65948327 4.15016594 2.6614002 1 P 0 ;0,1,2=141,3=90.000000
L 4.15016594 2.6614002 4.15326624 2.66216673 1 P 0 ;0,1,2=141,3=90.000000
L 4.15326624 2.66216673 4.15636654 2.6614002 1 P 0 ;0,1,2=141,3=90.000000
L 4.15636654 2.6614002 4.15894931 2.65948327 1 P 0 ;0,1,2=141,3=90.000000
L 4.15894931 2.65948327 4.1605 2.65603327 1 P 0 ;0,1,2=141,3=90.000000
L 4.1605 2.65603327 4.15998337 2.65258337 1 P 0 ;0,1,2=141,3=90.000000
L 4.15998337 2.65258337 4.15791624 2.64913337 1 P 0 ;0,1,2=141,3=90.000000
L 4.15533346 2.67821644 4.15843278 2.68051663 1 P 0 ;0,1,2=141,3=90.000000
L 4.15843278 2.68051663 4.15998337 2.6832001 1 P 0 ;0,1,2=141,3=90.000000
L 4.15998337 2.6832001 4.1605 2.68626683 1 P 0 ;0,1,2=141,3=90.000000
L 4.1605 2.68626683 4.15946683 2.6901 1 P 0 ;0,1,2=141,3=90.000000
L 4.15946683 2.6901 4.15688307 2.69278346 1 P 0 ;0,1,2=141,3=90.000000
L 4.15688307 2.69278346 4.15378376 2.69355 1 P 0 ;0,1,2=141,3=90.000000
L 4.15378376 2.69355 4.15068258 2.69316673 1 P 0 ;0,1,2=141,3=90.000000
L 4.15068258 2.69316673 4.1480998 2.69163307 1 P 0 ;0,1,2=141,3=90.000000
L 4.1480998 2.69163307 4.14293327 2.68396663 1 P 0 ;0,1,2=141,3=90.000000
L 4.14293327 2.68396663 4.13931644 2.68051663 1 P 0 ;0,1,2=141,3=90.000000
L 4.13931644 2.68051663 4.13414892 2.67821644 1 P 0 ;0,1,2=141,3=90.000000
L 4.13414892 2.67821644 4.1295 2.6774499 1 P 0 ;0,1,2=141,3=90.000000
L 4.1295 2.6774499 4.1295 2.69355 1 P 0 ;0,1,2=141,3=90.000000
L 4.1295 2.71649961 4.13001654 2.71918307 1 P 0 ;0,1,2=141,3=90.000000
L 4.13001654 2.71918307 4.13156614 2.7222498 1 P 0 ;0,1,2=141,3=90.000000
L 4.13156614 2.7222498 4.13414892 2.72416673 1 P 0 ;0,1,2=141,3=90.000000
L 4.13414892 2.72416673 4.13776673 2.72493327 1 P 0 ;0,1,2=141,3=90.000000
L 4.13776673 2.72493327 4.14138268 2.72416673 1 P 0 ;0,1,2=141,3=90.000000
L 4.14138268 2.72416673 4.14448287 2.72186654 1 P 0 ;0,1,2=141,3=90.000000
L 4.14448287 2.72186654 4.14603356 2.71841654 1 P 0 ;0,1,2=141,3=90.000000
L 4.14603356 2.71841654 4.14603356 2.71458337 1 P 0 ;0,1,2=141,3=90.000000
L 4.14603356 2.71458337 4.14706663 2.71228317 1 P 0 ;0,1,2=141,3=90.000000
L 4.14706663 2.71228317 4.14964941 2.71036614 1 P 0 ;0,1,2=141,3=90.000000
L 4.14964941 2.71036614 4.15326624 2.7095997 1 P 0 ;0,1,2=141,3=90.000000
L 4.15326624 2.7095997 4.15688307 2.7107501 1 P 0 ;0,1,2=141,3=90.000000
L 4.15688307 2.7107501 4.15946683 2.71343287 1 P 0 ;0,1,2=141,3=90.000000
L 4.15946683 2.71343287 4.1605 2.71649961 1 P 0 ;0,1,2=141,3=90.000000
L 4.1605 2.71649961 4.15946683 2.71956634 1 P 0 ;0,1,2=141,3=90.000000
L 4.15946683 2.71956634 4.15688307 2.7222498 1 P 0 ;0,1,2=141,3=90.000000
L 4.15688307 2.7222498 4.15326624 2.7234002 1 P 0 ;0,1,2=141,3=90.000000
L 4.15326624 2.7234002 4.14964941 2.72263307 1 P 0 ;0,1,2=141,3=90.000000
L 4.14964941 2.72263307 4.14706663 2.72071673 1 P 0 ;0,1,2=141,3=90.000000
L 4.14706663 2.72071673 4.14603356 2.71841654 1 P 0 ;0,1,2=141,3=90.000000
L 4.14603356 2.71841654 4.14603356 2.71458337 1 P 0 ;0,1,2=141,3=90.000000
L 4.14603356 2.71458337 4.14448287 2.71113337 1 P 0 ;0,1,2=141,3=90.000000
L 4.14448287 2.71113337 4.14138268 2.70883317 1 P 0 ;0,1,2=141,3=90.000000
L 4.14138268 2.70883317 4.13776673 2.70806663 1 P 0 ;0,1,2=141,3=90.000000
L 4.13776673 2.70806663 4.13414892 2.70883317 1 P 0 ;0,1,2=141,3=90.000000
L 4.13414892 2.70883317 4.13156614 2.7107501 1 P 0 ;0,1,2=141,3=90.000000
L 4.13156614 2.7107501 4.13001654 2.71381683 1 P 0 ;0,1,2=141,3=90.000000
L 4.13001654 2.71381683 4.1295 2.71649961 1 P 0 ;0,1,2=141,3=90.000000
L 4.187 2.576 4.231 2.576 1 P 0 
L 4.231 2.576 4.231 2.486 1 P 0 
L 4.231 2.486 4.187 2.486 1 P 0 
L 4.187 2.486 4.187 2.576 1 P 0 
L 4.1895 2.61583317 4.2205 2.61583317 1 P 0 ;0,1,2=142,3=90.000000
L 4.2205 2.61583317 4.2205 2.62541654 1 P 0 ;0,1,2=142,3=90.000000
L 4.2205 2.62541654 4.21894931 2.62848327 1 P 0 ;0,1,2=142,3=90.000000
L 4.21894931 2.62848327 4.21688307 2.6304002 1 P 0 ;0,1,2=142,3=90.000000
L 4.21688307 2.6304002 4.2127497 2.63116673 1 P 0 ;0,1,2=142,3=90.000000
L 4.2127497 2.63116673 4.20861634 2.6304002 1 P 0 ;0,1,2=142,3=90.000000
L 4.20861634 2.6304002 4.20603356 2.6281 1 P 0 ;0,1,2=142,3=90.000000
L 4.20603356 2.6281 4.20448287 2.62541654 1 P 0 ;0,1,2=142,3=90.000000
L 4.20448287 2.62541654 4.20448287 2.61583317 1 P 0 ;0,1,2=142,3=90.000000
L 4.20448287 2.62541654 4.1895 2.63116673 1 P 0 ;0,1,2=142,3=90.000000
L 4.19569961 2.64606663 4.19208278 2.64836614 1 P 0 ;0,1,2=142,3=90.000000
L 4.19208278 2.64836614 4.19001654 2.65143287 1 P 0 ;0,1,2=142,3=90.000000
L 4.19001654 2.65143287 4.1895 2.65488356 1 P 0 ;0,1,2=142,3=90.000000
L 4.1895 2.65488356 4.19001654 2.6579503 1 P 0 ;0,1,2=142,3=90.000000
L 4.19001654 2.6579503 4.19259931 2.66101703 1 P 0 ;0,1,2=142,3=90.000000
L 4.19259931 2.66101703 4.19569961 2.66293327 1 P 0 ;0,1,2=142,3=90.000000
L 4.19569961 2.66293327 4.1987999 2.66331654 1 P 0 ;0,1,2=142,3=90.000000
L 4.1987999 2.66331654 4.20241575 2.66255 1 P 0 ;0,1,2=142,3=90.000000
L 4.20241575 2.66255 4.20499951 2.65986654 1 P 0 ;0,1,2=142,3=90.000000
L 4.20499951 2.65986654 4.20603356 2.65718307 1 P 0 ;0,1,2=142,3=90.000000
L 4.20603356 2.65718307 4.20603356 2.65373307 1 P 0 ;0,1,2=142,3=90.000000
L 4.20603356 2.65718307 4.20758317 2.65948327 1 P 0 ;0,1,2=142,3=90.000000
L 4.20758317 2.65948327 4.21016594 2.6614002 1 P 0 ;0,1,2=142,3=90.000000
L 4.21016594 2.6614002 4.21326624 2.66216673 1 P 0 ;0,1,2=142,3=90.000000
L 4.21326624 2.66216673 4.21636654 2.6614002 1 P 0 ;0,1,2=142,3=90.000000
L 4.21636654 2.6614002 4.21894931 2.65948327 1 P 0 ;0,1,2=142,3=90.000000
L 4.21894931 2.65948327 4.2205 2.65603327 1 P 0 ;0,1,2=142,3=90.000000
L 4.2205 2.65603327 4.21998337 2.65258337 1 P 0 ;0,1,2=142,3=90.000000
L 4.21998337 2.65258337 4.21791624 2.64913337 1 P 0 ;0,1,2=142,3=90.000000
L 4.21533346 2.67821644 4.21843278 2.68051663 1 P 0 ;0,1,2=142,3=90.000000
L 4.21843278 2.68051663 4.21998337 2.6832001 1 P 0 ;0,1,2=142,3=90.000000
L 4.21998337 2.6832001 4.2205 2.68626683 1 P 0 ;0,1,2=142,3=90.000000
L 4.2205 2.68626683 4.21946683 2.6901 1 P 0 ;0,1,2=142,3=90.000000
L 4.21946683 2.6901 4.21688307 2.69278346 1 P 0 ;0,1,2=142,3=90.000000
L 4.21688307 2.69278346 4.21378376 2.69355 1 P 0 ;0,1,2=142,3=90.000000
L 4.21378376 2.69355 4.21068258 2.69316673 1 P 0 ;0,1,2=142,3=90.000000
L 4.21068258 2.69316673 4.2080998 2.69163307 1 P 0 ;0,1,2=142,3=90.000000
L 4.2080998 2.69163307 4.20293327 2.68396663 1 P 0 ;0,1,2=142,3=90.000000
L 4.20293327 2.68396663 4.19931644 2.68051663 1 P 0 ;0,1,2=142,3=90.000000
L 4.19931644 2.68051663 4.19414892 2.67821644 1 P 0 ;0,1,2=142,3=90.000000
L 4.19414892 2.67821644 4.1895 2.6774499 1 P 0 ;0,1,2=142,3=90.000000
L 4.1895 2.6774499 4.1895 2.69355 1 P 0 ;0,1,2=142,3=90.000000
L 4.20241575 2.70921644 4.20603356 2.7118999 1 P 0 ;0,1,2=142,3=90.000000
L 4.20603356 2.7118999 4.2080998 2.7142001 1 P 0 ;0,1,2=142,3=90.000000
L 4.2080998 2.7142001 4.20913287 2.71726683 1 P 0 ;0,1,2=142,3=90.000000
L 4.20913287 2.71726683 4.2080998 2.7199503 1 P 0 ;0,1,2=142,3=90.000000
L 4.2080998 2.7199503 4.20603356 2.72186654 1 P 0 ;0,1,2=142,3=90.000000
L 4.20603356 2.72186654 4.20293327 2.7234002 1 P 0 ;0,1,2=142,3=90.000000
L 4.20293327 2.7234002 4.19931644 2.72378346 1 P 0 ;0,1,2=142,3=90.000000
L 4.19931644 2.72378346 4.19621614 2.7234002 1 P 0 ;0,1,2=142,3=90.000000
L 4.19621614 2.7234002 4.19311585 2.72186654 1 P 0 ;0,1,2=142,3=90.000000
L 4.19311585 2.72186654 4.19053307 2.71956634 1 P 0 ;0,1,2=142,3=90.000000
L 4.19053307 2.71956634 4.1895 2.71688356 1 P 0 ;0,1,2=142,3=90.000000
L 4.1895 2.71688356 4.19053307 2.71381683 1 P 0 ;0,1,2=142,3=90.000000
L 4.19053307 2.71381683 4.19363238 2.71113337 1 P 0 ;0,1,2=142,3=90.000000
L 4.19363238 2.71113337 4.19828327 2.7095997 1 P 0 ;0,1,2=142,3=90.000000
L 4.19828327 2.7095997 4.2034498 2.70921644 1 P 0 ;0,1,2=142,3=90.000000
L 4.2034498 2.70921644 4.21016594 2.70998287 1 P 0 ;0,1,2=142,3=90.000000
L 4.21016594 2.70998287 4.21378376 2.71113337 1 P 0 ;0,1,2=142,3=90.000000
L 4.21378376 2.71113337 4.2173997 2.71304961 1 P 0 ;0,1,2=142,3=90.000000
L 4.2173997 2.71304961 4.21998337 2.71573307 1 P 0 ;0,1,2=142,3=90.000000
L 4.21998337 2.71573307 4.2205 2.71841654 1 P 0 ;0,1,2=142,3=90.000000
L 4.2205 2.71841654 4.21946683 2.7211 1 P 0 ;0,1,2=142,3=90.000000
L 4.21946683 2.7211 4.21688307 2.72301703 1 P 0 ;0,1,2=142,3=90.000000
L 4.071 2.576 4.115 2.576 1 P 0 
L 4.115 2.576 4.115 2.486 1 P 0 
L 4.115 2.486 4.071 2.486 1 P 0 
L 4.071 2.486 4.071 2.576 1 P 0 
L 4.0745 2.61583317 4.1055 2.61583317 1 P 0 ;0,1,2=143,3=90.000000
L 4.1055 2.61583317 4.1055 2.62541654 1 P 0 ;0,1,2=143,3=90.000000
L 4.1055 2.62541654 4.10394931 2.62848327 1 P 0 ;0,1,2=143,3=90.000000
L 4.10394931 2.62848327 4.10188307 2.6304002 1 P 0 ;0,1,2=143,3=90.000000
L 4.10188307 2.6304002 4.0977497 2.63116673 1 P 0 ;0,1,2=143,3=90.000000
L 4.0977497 2.63116673 4.09361634 2.6304002 1 P 0 ;0,1,2=143,3=90.000000
L 4.09361634 2.6304002 4.09103356 2.6281 1 P 0 ;0,1,2=143,3=90.000000
L 4.09103356 2.6281 4.08948287 2.62541654 1 P 0 ;0,1,2=143,3=90.000000
L 4.08948287 2.62541654 4.08948287 2.61583317 1 P 0 ;0,1,2=143,3=90.000000
L 4.08948287 2.62541654 4.0745 2.63116673 1 P 0 ;0,1,2=143,3=90.000000
L 4.08069961 2.64606663 4.07708278 2.64836614 1 P 0 ;0,1,2=143,3=90.000000
L 4.07708278 2.64836614 4.07501654 2.65143287 1 P 0 ;0,1,2=143,3=90.000000
L 4.07501654 2.65143287 4.0745 2.65488356 1 P 0 ;0,1,2=143,3=90.000000
L 4.0745 2.65488356 4.07501654 2.6579503 1 P 0 ;0,1,2=143,3=90.000000
L 4.07501654 2.6579503 4.07759931 2.66101703 1 P 0 ;0,1,2=143,3=90.000000
L 4.07759931 2.66101703 4.08069961 2.66293327 1 P 0 ;0,1,2=143,3=90.000000
L 4.08069961 2.66293327 4.0837999 2.66331654 1 P 0 ;0,1,2=143,3=90.000000
L 4.0837999 2.66331654 4.08741575 2.66255 1 P 0 ;0,1,2=143,3=90.000000
L 4.08741575 2.66255 4.08999951 2.65986654 1 P 0 ;0,1,2=143,3=90.000000
L 4.08999951 2.65986654 4.09103356 2.65718307 1 P 0 ;0,1,2=143,3=90.000000
L 4.09103356 2.65718307 4.09103356 2.65373307 1 P 0 ;0,1,2=143,3=90.000000
L 4.09103356 2.65718307 4.09258317 2.65948327 1 P 0 ;0,1,2=143,3=90.000000
L 4.09258317 2.65948327 4.09516594 2.6614002 1 P 0 ;0,1,2=143,3=90.000000
L 4.09516594 2.6614002 4.09826624 2.66216673 1 P 0 ;0,1,2=143,3=90.000000
L 4.09826624 2.66216673 4.10136654 2.6614002 1 P 0 ;0,1,2=143,3=90.000000
L 4.10136654 2.6614002 4.10394931 2.65948327 1 P 0 ;0,1,2=143,3=90.000000
L 4.10394931 2.65948327 4.1055 2.65603327 1 P 0 ;0,1,2=143,3=90.000000
L 4.1055 2.65603327 4.10498337 2.65258337 1 P 0 ;0,1,2=143,3=90.000000
L 4.10498337 2.65258337 4.10291624 2.64913337 1 P 0 ;0,1,2=143,3=90.000000
L 4.1055 2.68549961 4.10446683 2.68243287 1 P 0 ;0,1,2=143,3=90.000000
L 4.10446683 2.68243287 4.10188307 2.68013337 1 P 0 ;0,1,2=143,3=90.000000
L 4.10188307 2.68013337 4.09878376 2.6785997 1 P 0 ;0,1,2=143,3=90.000000
L 4.09878376 2.6785997 4.09464941 2.6774499 1 P 0 ;0,1,2=143,3=90.000000
L 4.09464941 2.6774499 4.08999951 2.67706663 1 P 0 ;0,1,2=143,3=90.000000
L 4.08999951 2.67706663 4.08534951 2.6774499 1 P 0 ;0,1,2=143,3=90.000000
L 4.08534951 2.6774499 4.08121614 2.6785997 1 P 0 ;0,1,2=143,3=90.000000
L 4.08121614 2.6785997 4.07811585 2.68013337 1 P 0 ;0,1,2=143,3=90.000000
L 4.07811585 2.68013337 4.07553307 2.68243287 1 P 0 ;0,1,2=143,3=90.000000
L 4.07553307 2.68243287 4.0745 2.68549961 1 P 0 ;0,1,2=143,3=90.000000
L 4.0745 2.68549961 4.07553307 2.68856634 1 P 0 ;0,1,2=143,3=90.000000
L 4.07553307 2.68856634 4.07811585 2.69086654 1 P 0 ;0,1,2=143,3=90.000000
L 4.07811585 2.69086654 4.08121614 2.6924002 1 P 0 ;0,1,2=143,3=90.000000
L 4.08121614 2.6924002 4.08534951 2.69355 1 P 0 ;0,1,2=143,3=90.000000
L 4.08534951 2.69355 4.08999951 2.69393327 1 P 0 ;0,1,2=143,3=90.000000
L 4.08999951 2.69393327 4.09464941 2.69355 1 P 0 ;0,1,2=143,3=90.000000
L 4.09464941 2.69355 4.09878376 2.6924002 1 P 0 ;0,1,2=143,3=90.000000
L 4.09878376 2.6924002 4.10188307 2.69086654 1 P 0 ;0,1,2=143,3=90.000000
L 4.10188307 2.69086654 4.10446683 2.68856634 1 P 0 ;0,1,2=143,3=90.000000
L 4.10446683 2.68856634 4.1055 2.68549961 1 P 0 ;0,1,2=143,3=90.000000
L 4.07811585 2.70998287 4.07553307 2.71266634 1 P 0 ;0,1,2=143,3=90.000000
L 4.07553307 2.71266634 4.0745 2.71573307 1 P 0 ;0,1,2=143,3=90.000000
L 4.0745 2.71573307 4.07553307 2.7187998 1 P 0 ;0,1,2=143,3=90.000000
L 4.07553307 2.7187998 4.07863238 2.72148327 1 P 0 ;0,1,2=143,3=90.000000
L 4.07863238 2.72148327 4.08328327 2.7234002 1 P 0 ;0,1,2=143,3=90.000000
L 4.08328327 2.7234002 4.08793327 2.72416673 1 P 0 ;0,1,2=143,3=90.000000
L 4.08793327 2.72416673 4.09361634 2.72416673 1 P 0 ;0,1,2=143,3=90.000000
L 4.09361634 2.72416673 4.09826624 2.7234002 1 P 0 ;0,1,2=143,3=90.000000
L 4.09826624 2.7234002 4.1023997 2.72148327 1 P 0 ;0,1,2=143,3=90.000000
L 4.1023997 2.72148327 4.10446683 2.71918307 1 P 0 ;0,1,2=143,3=90.000000
L 4.10446683 2.71918307 4.1055 2.71649961 1 P 0 ;0,1,2=143,3=90.000000
L 4.1055 2.71649961 4.10446683 2.71343287 1 P 0 ;0,1,2=143,3=90.000000
L 4.10446683 2.71343287 4.1023997 2.71113337 1 P 0 ;0,1,2=143,3=90.000000
L 4.1023997 2.71113337 4.0993003 2.7095997 1 P 0 ;0,1,2=143,3=90.000000
L 4.0993003 2.7095997 4.09516594 2.70883317 1 P 0 ;0,1,2=143,3=90.000000
L 4.09516594 2.70883317 4.0915501 2.7095997 1 P 0 ;0,1,2=143,3=90.000000
L 4.0915501 2.7095997 4.08793327 2.71151663 1 P 0 ;0,1,2=143,3=90.000000
L 4.08793327 2.71151663 4.08586604 2.71381683 1 P 0 ;0,1,2=143,3=90.000000
L 4.08586604 2.71381683 4.08534951 2.71649961 1 P 0 ;0,1,2=143,3=90.000000
L 4.08534951 2.71649961 4.08638268 2.71956634 1 P 0 ;0,1,2=143,3=90.000000
L 4.08638268 2.71956634 4.08896634 2.72186654 1 P 0 ;0,1,2=143,3=90.000000
L 4.08896634 2.72186654 4.09361634 2.72416673 1 P 0 ;0,1,2=143,3=90.000000
L 3.779 2.576 3.823 2.576 1 P 0 
L 3.823 2.576 3.823 2.486 1 P 0 
L 3.823 2.486 3.779 2.486 1 P 0 
L 3.779 2.486 3.779 2.576 1 P 0 
L 3.7995 2.61083317 3.8305 2.61083317 1 P 0 ;0,1,2=144,3=90.000000
L 3.8305 2.61083317 3.8305 2.62041654 1 P 0 ;0,1,2=144,3=90.000000
L 3.8305 2.62041654 3.82894931 2.62348327 1 P 0 ;0,1,2=144,3=90.000000
L 3.82894931 2.62348327 3.82688307 2.6254002 1 P 0 ;0,1,2=144,3=90.000000
L 3.82688307 2.6254002 3.8227497 2.62616673 1 P 0 ;0,1,2=144,3=90.000000
L 3.8227497 2.62616673 3.81861634 2.6254002 1 P 0 ;0,1,2=144,3=90.000000
L 3.81861634 2.6254002 3.81603356 2.6231 1 P 0 ;0,1,2=144,3=90.000000
L 3.81603356 2.6231 3.81448287 2.62041654 1 P 0 ;0,1,2=144,3=90.000000
L 3.81448287 2.62041654 3.81448287 2.61083317 1 P 0 ;0,1,2=144,3=90.000000
L 3.81448287 2.62041654 3.7995 2.62616673 1 P 0 ;0,1,2=144,3=90.000000
L 3.82533346 2.64221644 3.82843278 2.64451663 1 P 0 ;0,1,2=144,3=90.000000
L 3.82843278 2.64451663 3.82998337 2.6472001 1 P 0 ;0,1,2=144,3=90.000000
L 3.82998337 2.6472001 3.8305 2.65026683 1 P 0 ;0,1,2=144,3=90.000000
L 3.8305 2.65026683 3.82946683 2.6541 1 P 0 ;0,1,2=144,3=90.000000
L 3.82946683 2.6541 3.82688307 2.65678346 1 P 0 ;0,1,2=144,3=90.000000
L 3.82688307 2.65678346 3.82378376 2.65755 1 P 0 ;0,1,2=144,3=90.000000
L 3.82378376 2.65755 3.82068258 2.65716673 1 P 0 ;0,1,2=144,3=90.000000
L 3.82068258 2.65716673 3.8180998 2.65563307 1 P 0 ;0,1,2=144,3=90.000000
L 3.8180998 2.65563307 3.81293327 2.64796663 1 P 0 ;0,1,2=144,3=90.000000
L 3.81293327 2.64796663 3.80931644 2.64451663 1 P 0 ;0,1,2=144,3=90.000000
L 3.80931644 2.64451663 3.80414892 2.64221644 1 P 0 ;0,1,2=144,3=90.000000
L 3.80414892 2.64221644 3.7995 2.6414499 1 P 0 ;0,1,2=144,3=90.000000
L 3.7995 2.6414499 3.7995 2.65755 1 P 0 ;0,1,2=144,3=90.000000
L 3.7995 2.68049961 3.80001654 2.68318307 1 P 0 ;0,1,2=144,3=90.000000
L 3.80001654 2.68318307 3.80156614 2.6862498 1 P 0 ;0,1,2=144,3=90.000000
L 3.80156614 2.6862498 3.80414892 2.68816673 1 P 0 ;0,1,2=144,3=90.000000
L 3.80414892 2.68816673 3.80776673 2.68893327 1 P 0 ;0,1,2=144,3=90.000000
L 3.80776673 2.68893327 3.81138268 2.68816673 1 P 0 ;0,1,2=144,3=90.000000
L 3.81138268 2.68816673 3.81448287 2.68586654 1 P 0 ;0,1,2=144,3=90.000000
L 3.81448287 2.68586654 3.81603356 2.68241654 1 P 0 ;0,1,2=144,3=90.000000
L 3.81603356 2.68241654 3.81603356 2.67858337 1 P 0 ;0,1,2=144,3=90.000000
L 3.81603356 2.67858337 3.81706663 2.67628317 1 P 0 ;0,1,2=144,3=90.000000
L 3.81706663 2.67628317 3.81964941 2.67436614 1 P 0 ;0,1,2=144,3=90.000000
L 3.81964941 2.67436614 3.82326624 2.6735997 1 P 0 ;0,1,2=144,3=90.000000
L 3.82326624 2.6735997 3.82688307 2.6747501 1 P 0 ;0,1,2=144,3=90.000000
L 3.82688307 2.6747501 3.82946683 2.67743287 1 P 0 ;0,1,2=144,3=90.000000
L 3.82946683 2.67743287 3.8305 2.68049961 1 P 0 ;0,1,2=144,3=90.000000
L 3.8305 2.68049961 3.82946683 2.68356634 1 P 0 ;0,1,2=144,3=90.000000
L 3.82946683 2.68356634 3.82688307 2.6862498 1 P 0 ;0,1,2=144,3=90.000000
L 3.82688307 2.6862498 3.82326624 2.6874002 1 P 0 ;0,1,2=144,3=90.000000
L 3.82326624 2.6874002 3.81964941 2.68663307 1 P 0 ;0,1,2=144,3=90.000000
L 3.81964941 2.68663307 3.81706663 2.68471673 1 P 0 ;0,1,2=144,3=90.000000
L 3.81706663 2.68471673 3.81603356 2.68241654 1 P 0 ;0,1,2=144,3=90.000000
L 3.81603356 2.68241654 3.81603356 2.67858337 1 P 0 ;0,1,2=144,3=90.000000
L 3.81603356 2.67858337 3.81448287 2.67513337 1 P 0 ;0,1,2=144,3=90.000000
L 3.81448287 2.67513337 3.81138268 2.67283317 1 P 0 ;0,1,2=144,3=90.000000
L 3.81138268 2.67283317 3.80776673 2.67206663 1 P 0 ;0,1,2=144,3=90.000000
L 3.80776673 2.67206663 3.80414892 2.67283317 1 P 0 ;0,1,2=144,3=90.000000
L 3.80414892 2.67283317 3.80156614 2.6747501 1 P 0 ;0,1,2=144,3=90.000000
L 3.80156614 2.6747501 3.80001654 2.67781683 1 P 0 ;0,1,2=144,3=90.000000
L 3.80001654 2.67781683 3.7995 2.68049961 1 P 0 ;0,1,2=144,3=90.000000
L 3.81241575 2.70421644 3.81603356 2.7068999 1 P 0 ;0,1,2=144,3=90.000000
L 3.81603356 2.7068999 3.8180998 2.7092001 1 P 0 ;0,1,2=144,3=90.000000
L 3.8180998 2.7092001 3.81913287 2.71226683 1 P 0 ;0,1,2=144,3=90.000000
L 3.81913287 2.71226683 3.8180998 2.7149503 1 P 0 ;0,1,2=144,3=90.000000
L 3.8180998 2.7149503 3.81603356 2.71686654 1 P 0 ;0,1,2=144,3=90.000000
L 3.81603356 2.71686654 3.81293327 2.7184002 1 P 0 ;0,1,2=144,3=90.000000
L 3.81293327 2.7184002 3.80931644 2.71878346 1 P 0 ;0,1,2=144,3=90.000000
L 3.80931644 2.71878346 3.80621614 2.7184002 1 P 0 ;0,1,2=144,3=90.000000
L 3.80621614 2.7184002 3.80311585 2.71686654 1 P 0 ;0,1,2=144,3=90.000000
L 3.80311585 2.71686654 3.80053307 2.71456634 1 P 0 ;0,1,2=144,3=90.000000
L 3.80053307 2.71456634 3.7995 2.71188356 1 P 0 ;0,1,2=144,3=90.000000
L 3.7995 2.71188356 3.80053307 2.70881683 1 P 0 ;0,1,2=144,3=90.000000
L 3.80053307 2.70881683 3.80363238 2.70613337 1 P 0 ;0,1,2=144,3=90.000000
L 3.80363238 2.70613337 3.80828327 2.7045997 1 P 0 ;0,1,2=144,3=90.000000
L 3.80828327 2.7045997 3.8134498 2.70421644 1 P 0 ;0,1,2=144,3=90.000000
L 3.8134498 2.70421644 3.82016594 2.70498287 1 P 0 ;0,1,2=144,3=90.000000
L 3.82016594 2.70498287 3.82378376 2.70613337 1 P 0 ;0,1,2=144,3=90.000000
L 3.82378376 2.70613337 3.8273997 2.70804961 1 P 0 ;0,1,2=144,3=90.000000
L 3.8273997 2.70804961 3.82998337 2.71073307 1 P 0 ;0,1,2=144,3=90.000000
L 3.82998337 2.71073307 3.8305 2.71341654 1 P 0 ;0,1,2=144,3=90.000000
L 3.8305 2.71341654 3.82946683 2.7161 1 P 0 ;0,1,2=144,3=90.000000
L 3.82946683 2.7161 3.82688307 2.71801703 1 P 0 ;0,1,2=144,3=90.000000
L 3.838 2.576 3.882 2.576 1 P 0 
L 3.882 2.576 3.882 2.486 1 P 0 
L 3.882 2.486 3.838 2.486 1 P 0 
L 3.838 2.486 3.838 2.576 1 P 0 
L 3.8545 2.61083317 3.8855 2.61083317 1 P 0 ;0,1,2=145,3=90.000000
L 3.8855 2.61083317 3.8855 2.62041654 1 P 0 ;0,1,2=145,3=90.000000
L 3.8855 2.62041654 3.88394931 2.62348327 1 P 0 ;0,1,2=145,3=90.000000
L 3.88394931 2.62348327 3.88188307 2.6254002 1 P 0 ;0,1,2=145,3=90.000000
L 3.88188307 2.6254002 3.8777497 2.62616673 1 P 0 ;0,1,2=145,3=90.000000
L 3.8777497 2.62616673 3.87361634 2.6254002 1 P 0 ;0,1,2=145,3=90.000000
L 3.87361634 2.6254002 3.87103356 2.6231 1 P 0 ;0,1,2=145,3=90.000000
L 3.87103356 2.6231 3.86948287 2.62041654 1 P 0 ;0,1,2=145,3=90.000000
L 3.86948287 2.62041654 3.86948287 2.61083317 1 P 0 ;0,1,2=145,3=90.000000
L 3.86948287 2.62041654 3.8545 2.62616673 1 P 0 ;0,1,2=145,3=90.000000
L 3.88033346 2.64221644 3.88343278 2.64451663 1 P 0 ;0,1,2=145,3=90.000000
L 3.88343278 2.64451663 3.88498337 2.6472001 1 P 0 ;0,1,2=145,3=90.000000
L 3.88498337 2.6472001 3.8855 2.65026683 1 P 0 ;0,1,2=145,3=90.000000
L 3.8855 2.65026683 3.88446683 2.6541 1 P 0 ;0,1,2=145,3=90.000000
L 3.88446683 2.6541 3.88188307 2.65678346 1 P 0 ;0,1,2=145,3=90.000000
L 3.88188307 2.65678346 3.87878376 2.65755 1 P 0 ;0,1,2=145,3=90.000000
L 3.87878376 2.65755 3.87568258 2.65716673 1 P 0 ;0,1,2=145,3=90.000000
L 3.87568258 2.65716673 3.8730998 2.65563307 1 P 0 ;0,1,2=145,3=90.000000
L 3.8730998 2.65563307 3.86793327 2.64796663 1 P 0 ;0,1,2=145,3=90.000000
L 3.86793327 2.64796663 3.86431644 2.64451663 1 P 0 ;0,1,2=145,3=90.000000
L 3.86431644 2.64451663 3.85914892 2.64221644 1 P 0 ;0,1,2=145,3=90.000000
L 3.85914892 2.64221644 3.8545 2.6414499 1 P 0 ;0,1,2=145,3=90.000000
L 3.8545 2.6414499 3.8545 2.65755 1 P 0 ;0,1,2=145,3=90.000000
L 3.8545 2.68049961 3.85501654 2.68318307 1 P 0 ;0,1,2=145,3=90.000000
L 3.85501654 2.68318307 3.85656614 2.6862498 1 P 0 ;0,1,2=145,3=90.000000
L 3.85656614 2.6862498 3.85914892 2.68816673 1 P 0 ;0,1,2=145,3=90.000000
L 3.85914892 2.68816673 3.86276673 2.68893327 1 P 0 ;0,1,2=145,3=90.000000
L 3.86276673 2.68893327 3.86638268 2.68816673 1 P 0 ;0,1,2=145,3=90.000000
L 3.86638268 2.68816673 3.86948287 2.68586654 1 P 0 ;0,1,2=145,3=90.000000
L 3.86948287 2.68586654 3.87103356 2.68241654 1 P 0 ;0,1,2=145,3=90.000000
L 3.87103356 2.68241654 3.87103356 2.67858337 1 P 0 ;0,1,2=145,3=90.000000
L 3.87103356 2.67858337 3.87206663 2.67628317 1 P 0 ;0,1,2=145,3=90.000000
L 3.87206663 2.67628317 3.87464941 2.67436614 1 P 0 ;0,1,2=145,3=90.000000
L 3.87464941 2.67436614 3.87826624 2.6735997 1 P 0 ;0,1,2=145,3=90.000000
L 3.87826624 2.6735997 3.88188307 2.6747501 1 P 0 ;0,1,2=145,3=90.000000
L 3.88188307 2.6747501 3.88446683 2.67743287 1 P 0 ;0,1,2=145,3=90.000000
L 3.88446683 2.67743287 3.8855 2.68049961 1 P 0 ;0,1,2=145,3=90.000000
L 3.8855 2.68049961 3.88446683 2.68356634 1 P 0 ;0,1,2=145,3=90.000000
L 3.88446683 2.68356634 3.88188307 2.6862498 1 P 0 ;0,1,2=145,3=90.000000
L 3.88188307 2.6862498 3.87826624 2.6874002 1 P 0 ;0,1,2=145,3=90.000000
L 3.87826624 2.6874002 3.87464941 2.68663307 1 P 0 ;0,1,2=145,3=90.000000
L 3.87464941 2.68663307 3.87206663 2.68471673 1 P 0 ;0,1,2=145,3=90.000000
L 3.87206663 2.68471673 3.87103356 2.68241654 1 P 0 ;0,1,2=145,3=90.000000
L 3.87103356 2.68241654 3.87103356 2.67858337 1 P 0 ;0,1,2=145,3=90.000000
L 3.87103356 2.67858337 3.86948287 2.67513337 1 P 0 ;0,1,2=145,3=90.000000
L 3.86948287 2.67513337 3.86638268 2.67283317 1 P 0 ;0,1,2=145,3=90.000000
L 3.86638268 2.67283317 3.86276673 2.67206663 1 P 0 ;0,1,2=145,3=90.000000
L 3.86276673 2.67206663 3.85914892 2.67283317 1 P 0 ;0,1,2=145,3=90.000000
L 3.85914892 2.67283317 3.85656614 2.6747501 1 P 0 ;0,1,2=145,3=90.000000
L 3.85656614 2.6747501 3.85501654 2.67781683 1 P 0 ;0,1,2=145,3=90.000000
L 3.85501654 2.67781683 3.8545 2.68049961 1 P 0 ;0,1,2=145,3=90.000000
L 3.8545 2.7161 3.8855 2.7161 1 P 0 ;0,1,2=145,3=90.000000
L 3.8855 2.7161 3.86328327 2.70191624 1 P 0 ;0,1,2=145,3=90.000000
L 3.86328327 2.70191624 3.86328327 2.72108366 1 P 0 ;0,1,2=145,3=90.000000
L 0.77 3.133 0.68 3.133 1 P 0 
L 0.68 3.133 0.68 3.177 1 P 0 
L 0.68 3.177 0.77 3.177 1 P 0 
L 0.77 3.177 0.77 3.133 1 P 0 
L 0.92916683 3.1295 0.92916683 3.1605 1 P 0 ;0,1,2=146,3=0.000000
L 0.92916683 3.1605 0.91958346 3.1605 1 P 0 ;0,1,2=146,3=0.000000
L 0.91958346 3.1605 0.91651673 3.15894931 1 P 0 ;0,1,2=146,3=0.000000
L 0.91651673 3.15894931 0.9145998 3.15688307 1 P 0 ;0,1,2=146,3=0.000000
L 0.9145998 3.15688307 0.91383327 3.1527497 1 P 0 ;0,1,2=146,3=0.000000
L 0.91383327 3.1527497 0.9145998 3.14861634 1 P 0 ;0,1,2=146,3=0.000000
L 0.9145998 3.14861634 0.9169 3.14603356 1 P 0 ;0,1,2=146,3=0.000000
L 0.9169 3.14603356 0.91958346 3.14448287 1 P 0 ;0,1,2=146,3=0.000000
L 0.91958346 3.14448287 0.92916683 3.14448287 1 P 0 ;0,1,2=146,3=0.000000
L 0.91958346 3.14448287 0.91383327 3.1295 1 P 0 ;0,1,2=146,3=0.000000
L 0.8859 3.1295 0.8859 3.1605 1 P 0 ;0,1,2=146,3=0.000000
L 0.8859 3.1605 0.90008376 3.13828327 1 P 0 ;0,1,2=146,3=0.000000
L 0.90008376 3.13828327 0.88091634 3.13828327 1 P 0 ;0,1,2=146,3=0.000000
L 0.86026693 3.1295 0.85950039 3.13621614 1 P 0 ;0,1,2=146,3=0.000000
L 0.85950039 3.13621614 0.8583499 3.14189921 1 P 0 ;0,1,2=146,3=0.000000
L 0.8583499 3.14189921 0.85681693 3.14706663 1 P 0 ;0,1,2=146,3=0.000000
L 0.85681693 3.14706663 0.8549 3.1527497 1 P 0 ;0,1,2=146,3=0.000000
L 0.8549 3.1527497 0.85183327 3.1605 1 P 0 ;0,1,2=146,3=0.000000
L 0.85183327 3.1605 0.86716683 3.1605 1 P 0 ;0,1,2=146,3=0.000000
L 0.83693337 3.13569961 0.83463386 3.13208278 1 P 0 ;0,1,2=146,3=0.000000
L 0.83463386 3.13208278 0.83156713 3.13001654 1 P 0 ;0,1,2=146,3=0.000000
L 0.83156713 3.13001654 0.82811644 3.1295 1 P 0 ;0,1,2=146,3=0.000000
L 0.82811644 3.1295 0.8250497 3.13001654 1 P 0 ;0,1,2=146,3=0.000000
L 0.8250497 3.13001654 0.82198297 3.13259931 1 P 0 ;0,1,2=146,3=0.000000
L 0.82198297 3.13259931 0.82006673 3.13569961 1 P 0 ;0,1,2=146,3=0.000000
L 0.82006673 3.13569961 0.81968346 3.1387999 1 P 0 ;0,1,2=146,3=0.000000
L 0.81968346 3.1387999 0.82045 3.14241575 1 P 0 ;0,1,2=146,3=0.000000
L 0.82045 3.14241575 0.82313346 3.14499951 1 P 0 ;0,1,2=146,3=0.000000
L 0.82313346 3.14499951 0.82581693 3.14603356 1 P 0 ;0,1,2=146,3=0.000000
L 0.82581693 3.14603356 0.82926693 3.14603356 1 P 0 ;0,1,2=146,3=0.000000
L 0.82581693 3.14603356 0.82351673 3.14758317 1 P 0 ;0,1,2=146,3=0.000000
L 0.82351673 3.14758317 0.8215998 3.15016594 1 P 0 ;0,1,2=146,3=0.000000
L 0.8215998 3.15016594 0.82083327 3.15326624 1 P 0 ;0,1,2=146,3=0.000000
L 0.82083327 3.15326624 0.8215998 3.15636654 1 P 0 ;0,1,2=146,3=0.000000
L 0.8215998 3.15636654 0.82351673 3.15894931 1 P 0 ;0,1,2=146,3=0.000000
L 0.82351673 3.15894931 0.82696673 3.1605 1 P 0 ;0,1,2=146,3=0.000000
L 0.82696673 3.1605 0.83041663 3.15998337 1 P 0 ;0,1,2=146,3=0.000000
L 0.83041663 3.15998337 0.83386663 3.15791624 1 P 0 ;0,1,2=146,3=0.000000
L 0.935 3.432 0.935 3.388 1 P 0 
L 0.845 3.432 0.935 3.432 1 P 0 
L 0.935 3.388 0.845 3.388 1 P 0 
L 0.845 3.388 0.845 3.432 1 P 0 
L 0.98416683 3.2645 0.98416683 3.2955 1 P 0 ;0,1,2=147,3=0.000000
L 0.98416683 3.2955 0.97458346 3.2955 1 P 0 ;0,1,2=147,3=0.000000
L 0.97458346 3.2955 0.97151673 3.29394931 1 P 0 ;0,1,2=147,3=0.000000
L 0.97151673 3.29394931 0.9695998 3.29188307 1 P 0 ;0,1,2=147,3=0.000000
L 0.9695998 3.29188307 0.96883327 3.2877497 1 P 0 ;0,1,2=147,3=0.000000
L 0.96883327 3.2877497 0.9695998 3.28361634 1 P 0 ;0,1,2=147,3=0.000000
L 0.9695998 3.28361634 0.9719 3.28103356 1 P 0 ;0,1,2=147,3=0.000000
L 0.9719 3.28103356 0.97458346 3.27948287 1 P 0 ;0,1,2=147,3=0.000000
L 0.97458346 3.27948287 0.98416683 3.27948287 1 P 0 ;0,1,2=147,3=0.000000
L 0.97458346 3.27948287 0.96883327 3.2645 1 P 0 ;0,1,2=147,3=0.000000
L 0.9409 3.2645 0.9409 3.2955 1 P 0 ;0,1,2=147,3=0.000000
L 0.9409 3.2955 0.95508376 3.27328327 1 P 0 ;0,1,2=147,3=0.000000
L 0.95508376 3.27328327 0.93591634 3.27328327 1 P 0 ;0,1,2=147,3=0.000000
L 0.91526693 3.2645 0.91450039 3.27121614 1 P 0 ;0,1,2=147,3=0.000000
L 0.91450039 3.27121614 0.9133499 3.27689921 1 P 0 ;0,1,2=147,3=0.000000
L 0.9133499 3.27689921 0.91181693 3.28206663 1 P 0 ;0,1,2=147,3=0.000000
L 0.91181693 3.28206663 0.9099 3.2877497 1 P 0 ;0,1,2=147,3=0.000000
L 0.9099 3.2877497 0.90683327 3.2955 1 P 0 ;0,1,2=147,3=0.000000
L 0.90683327 3.2955 0.92216683 3.2955 1 P 0 ;0,1,2=147,3=0.000000
L 0.88350039 3.2955 0.88656713 3.29446683 1 P 0 ;0,1,2=147,3=0.000000
L 0.88656713 3.29446683 0.88886663 3.29188307 1 P 0 ;0,1,2=147,3=0.000000
L 0.88886663 3.29188307 0.8904003 3.28878376 1 P 0 ;0,1,2=147,3=0.000000
L 0.8904003 3.28878376 0.8915501 3.28464941 1 P 0 ;0,1,2=147,3=0.000000
L 0.8915501 3.28464941 0.89193337 3.27999951 1 P 0 ;0,1,2=147,3=0.000000
L 0.89193337 3.27999951 0.8915501 3.27534951 1 P 0 ;0,1,2=147,3=0.000000
L 0.8915501 3.27534951 0.8904003 3.27121614 1 P 0 ;0,1,2=147,3=0.000000
L 0.8904003 3.27121614 0.88886663 3.26811585 1 P 0 ;0,1,2=147,3=0.000000
L 0.88886663 3.26811585 0.88656713 3.26553307 1 P 0 ;0,1,2=147,3=0.000000
L 0.88656713 3.26553307 0.88350039 3.2645 1 P 0 ;0,1,2=147,3=0.000000
L 0.88350039 3.2645 0.88043366 3.26553307 1 P 0 ;0,1,2=147,3=0.000000
L 0.88043366 3.26553307 0.87813346 3.26811585 1 P 0 ;0,1,2=147,3=0.000000
L 0.87813346 3.26811585 0.8765998 3.27121614 1 P 0 ;0,1,2=147,3=0.000000
L 0.8765998 3.27121614 0.87545 3.27534951 1 P 0 ;0,1,2=147,3=0.000000
L 0.87545 3.27534951 0.87506673 3.27999951 1 P 0 ;0,1,2=147,3=0.000000
L 0.87506673 3.27999951 0.87545 3.28464941 1 P 0 ;0,1,2=147,3=0.000000
L 0.87545 3.28464941 0.8765998 3.28878376 1 P 0 ;0,1,2=147,3=0.000000
L 0.8765998 3.28878376 0.87813346 3.29188307 1 P 0 ;0,1,2=147,3=0.000000
L 0.87813346 3.29188307 0.88043366 3.29446683 1 P 0 ;0,1,2=147,3=0.000000
L 0.88043366 3.29446683 0.88350039 3.2955 1 P 0 ;0,1,2=147,3=0.000000
L 0.935 3.522 0.935 3.478 1 P 0 
L 0.845 3.522 0.935 3.522 1 P 0 
L 0.935 3.478 0.845 3.478 1 P 0 
L 0.845 3.478 0.845 3.522 1 P 0 
L 0.98416683 3.3445 0.98416683 3.3755 1 P 0 ;0,1,2=148,3=0.000000
L 0.98416683 3.3755 0.97458346 3.3755 1 P 0 ;0,1,2=148,3=0.000000
L 0.97458346 3.3755 0.97151673 3.37394931 1 P 0 ;0,1,2=148,3=0.000000
L 0.97151673 3.37394931 0.9695998 3.37188307 1 P 0 ;0,1,2=148,3=0.000000
L 0.9695998 3.37188307 0.96883327 3.3677497 1 P 0 ;0,1,2=148,3=0.000000
L 0.96883327 3.3677497 0.9695998 3.36361634 1 P 0 ;0,1,2=148,3=0.000000
L 0.9695998 3.36361634 0.9719 3.36103356 1 P 0 ;0,1,2=148,3=0.000000
L 0.9719 3.36103356 0.97458346 3.35948287 1 P 0 ;0,1,2=148,3=0.000000
L 0.97458346 3.35948287 0.98416683 3.35948287 1 P 0 ;0,1,2=148,3=0.000000
L 0.97458346 3.35948287 0.96883327 3.3445 1 P 0 ;0,1,2=148,3=0.000000
L 0.9409 3.3445 0.9409 3.3755 1 P 0 ;0,1,2=148,3=0.000000
L 0.9409 3.3755 0.95508376 3.35328327 1 P 0 ;0,1,2=148,3=0.000000
L 0.95508376 3.35328327 0.93591634 3.35328327 1 P 0 ;0,1,2=148,3=0.000000
L 0.92178356 3.35741575 0.9191001 3.36103356 1 P 0 ;0,1,2=148,3=0.000000
L 0.9191001 3.36103356 0.9167999 3.3630998 1 P 0 ;0,1,2=148,3=0.000000
L 0.9167999 3.3630998 0.91373317 3.36413287 1 P 0 ;0,1,2=148,3=0.000000
L 0.91373317 3.36413287 0.9110497 3.3630998 1 P 0 ;0,1,2=148,3=0.000000
L 0.9110497 3.3630998 0.90913346 3.36103356 1 P 0 ;0,1,2=148,3=0.000000
L 0.90913346 3.36103356 0.9075998 3.35793327 1 P 0 ;0,1,2=148,3=0.000000
L 0.9075998 3.35793327 0.90721654 3.35431644 1 P 0 ;0,1,2=148,3=0.000000
L 0.90721654 3.35431644 0.9075998 3.35121614 1 P 0 ;0,1,2=148,3=0.000000
L 0.9075998 3.35121614 0.90913346 3.34811585 1 P 0 ;0,1,2=148,3=0.000000
L 0.90913346 3.34811585 0.91143366 3.34553307 1 P 0 ;0,1,2=148,3=0.000000
L 0.91143366 3.34553307 0.91411644 3.3445 1 P 0 ;0,1,2=148,3=0.000000
L 0.91411644 3.3445 0.91718317 3.34553307 1 P 0 ;0,1,2=148,3=0.000000
L 0.91718317 3.34553307 0.91986663 3.34863238 1 P 0 ;0,1,2=148,3=0.000000
L 0.91986663 3.34863238 0.9214003 3.35328327 1 P 0 ;0,1,2=148,3=0.000000
L 0.9214003 3.35328327 0.92178356 3.3584498 1 P 0 ;0,1,2=148,3=0.000000
L 0.92178356 3.3584498 0.92101713 3.36516594 1 P 0 ;0,1,2=148,3=0.000000
L 0.92101713 3.36516594 0.91986663 3.36878376 1 P 0 ;0,1,2=148,3=0.000000
L 0.91986663 3.36878376 0.91795039 3.3723997 1 P 0 ;0,1,2=148,3=0.000000
L 0.91795039 3.3723997 0.91526693 3.37498337 1 P 0 ;0,1,2=148,3=0.000000
L 0.91526693 3.37498337 0.91258346 3.3755 1 P 0 ;0,1,2=148,3=0.000000
L 0.91258346 3.3755 0.9099 3.37446683 1 P 0 ;0,1,2=148,3=0.000000
L 0.9099 3.37446683 0.90798297 3.37188307 1 P 0 ;0,1,2=148,3=0.000000
L 0.89001713 3.34811585 0.88733366 3.34553307 1 P 0 ;0,1,2=148,3=0.000000
L 0.88733366 3.34553307 0.88426693 3.3445 1 P 0 ;0,1,2=148,3=0.000000
L 0.88426693 3.3445 0.8812002 3.34553307 1 P 0 ;0,1,2=148,3=0.000000
L 0.8812002 3.34553307 0.87851673 3.34863238 1 P 0 ;0,1,2=148,3=0.000000
L 0.87851673 3.34863238 0.8765998 3.35328327 1 P 0 ;0,1,2=148,3=0.000000
L 0.8765998 3.35328327 0.87583327 3.35793327 1 P 0 ;0,1,2=148,3=0.000000
L 0.87583327 3.35793327 0.87583327 3.36361634 1 P 0 ;0,1,2=148,3=0.000000
L 0.87583327 3.36361634 0.8765998 3.36826624 1 P 0 ;0,1,2=148,3=0.000000
L 0.8765998 3.36826624 0.87851673 3.3723997 1 P 0 ;0,1,2=148,3=0.000000
L 0.87851673 3.3723997 0.88081693 3.37446683 1 P 0 ;0,1,2=148,3=0.000000
L 0.88081693 3.37446683 0.88350039 3.3755 1 P 0 ;0,1,2=148,3=0.000000
L 0.88350039 3.3755 0.88656713 3.37446683 1 P 0 ;0,1,2=148,3=0.000000
L 0.88656713 3.37446683 0.88886663 3.3723997 1 P 0 ;0,1,2=148,3=0.000000
L 0.88886663 3.3723997 0.8904003 3.3693003 1 P 0 ;0,1,2=148,3=0.000000
L 0.8904003 3.3693003 0.89116683 3.36516594 1 P 0 ;0,1,2=148,3=0.000000
L 0.89116683 3.36516594 0.8904003 3.3615501 1 P 0 ;0,1,2=148,3=0.000000
L 0.8904003 3.3615501 0.88848337 3.35793327 1 P 0 ;0,1,2=148,3=0.000000
L 0.88848337 3.35793327 0.88618317 3.35586604 1 P 0 ;0,1,2=148,3=0.000000
L 0.88618317 3.35586604 0.88350039 3.35534951 1 P 0 ;0,1,2=148,3=0.000000
L 0.88350039 3.35534951 0.88043366 3.35638268 1 P 0 ;0,1,2=148,3=0.000000
L 0.88043366 3.35638268 0.87813346 3.35896634 1 P 0 ;0,1,2=148,3=0.000000
L 0.87813346 3.35896634 0.87583327 3.36361634 1 P 0 ;0,1,2=148,3=0.000000
L 0.86 3.619 0.904 3.619 1 P 0 
L 0.86 3.529 0.86 3.619 1 P 0 
L 0.904 3.619 0.904 3.529 1 P 0 
L 0.904 3.529 0.86 3.529 1 P 0 
L 0.6945 3.62083317 0.7255 3.62083317 1 P 0 ;0,1,2=149,3=90.000000
L 0.7255 3.62083317 0.7255 3.63041654 1 P 0 ;0,1,2=149,3=90.000000
L 0.7255 3.63041654 0.72394931 3.63348327 1 P 0 ;0,1,2=149,3=90.000000
L 0.72394931 3.63348327 0.72188307 3.6354002 1 P 0 ;0,1,2=149,3=90.000000
L 0.72188307 3.6354002 0.7177497 3.63616673 1 P 0 ;0,1,2=149,3=90.000000
L 0.7177497 3.63616673 0.71361634 3.6354002 1 P 0 ;0,1,2=149,3=90.000000
L 0.71361634 3.6354002 0.71103356 3.6331 1 P 0 ;0,1,2=149,3=90.000000
L 0.71103356 3.6331 0.70948287 3.63041654 1 P 0 ;0,1,2=149,3=90.000000
L 0.70948287 3.63041654 0.70948287 3.62083317 1 P 0 ;0,1,2=149,3=90.000000
L 0.70948287 3.63041654 0.6945 3.63616673 1 P 0 ;0,1,2=149,3=90.000000
L 0.6945 3.6641 0.7255 3.6641 1 P 0 ;0,1,2=149,3=90.000000
L 0.7255 3.6641 0.70328327 3.64991624 1 P 0 ;0,1,2=149,3=90.000000
L 0.70328327 3.64991624 0.70328327 3.66908366 1 P 0 ;0,1,2=149,3=90.000000
L 0.70741575 3.68321644 0.71103356 3.6858999 1 P 0 ;0,1,2=149,3=90.000000
L 0.71103356 3.6858999 0.7130998 3.6882001 1 P 0 ;0,1,2=149,3=90.000000
L 0.7130998 3.6882001 0.71413287 3.69126683 1 P 0 ;0,1,2=149,3=90.000000
L 0.71413287 3.69126683 0.7130998 3.6939503 1 P 0 ;0,1,2=149,3=90.000000
L 0.7130998 3.6939503 0.71103356 3.69586654 1 P 0 ;0,1,2=149,3=90.000000
L 0.71103356 3.69586654 0.70793327 3.6974002 1 P 0 ;0,1,2=149,3=90.000000
L 0.70793327 3.6974002 0.70431644 3.69778346 1 P 0 ;0,1,2=149,3=90.000000
L 0.70431644 3.69778346 0.70121614 3.6974002 1 P 0 ;0,1,2=149,3=90.000000
L 0.70121614 3.6974002 0.69811585 3.69586654 1 P 0 ;0,1,2=149,3=90.000000
L 0.69811585 3.69586654 0.69553307 3.69356634 1 P 0 ;0,1,2=149,3=90.000000
L 0.69553307 3.69356634 0.6945 3.69088356 1 P 0 ;0,1,2=149,3=90.000000
L 0.6945 3.69088356 0.69553307 3.68781683 1 P 0 ;0,1,2=149,3=90.000000
L 0.69553307 3.68781683 0.69863238 3.68513337 1 P 0 ;0,1,2=149,3=90.000000
L 0.69863238 3.68513337 0.70328327 3.6835997 1 P 0 ;0,1,2=149,3=90.000000
L 0.70328327 3.6835997 0.7084498 3.68321644 1 P 0 ;0,1,2=149,3=90.000000
L 0.7084498 3.68321644 0.71516594 3.68398287 1 P 0 ;0,1,2=149,3=90.000000
L 0.71516594 3.68398287 0.71878376 3.68513337 1 P 0 ;0,1,2=149,3=90.000000
L 0.71878376 3.68513337 0.7223997 3.68704961 1 P 0 ;0,1,2=149,3=90.000000
L 0.7223997 3.68704961 0.72498337 3.68973307 1 P 0 ;0,1,2=149,3=90.000000
L 0.72498337 3.68973307 0.7255 3.69241654 1 P 0 ;0,1,2=149,3=90.000000
L 0.7255 3.69241654 0.72446683 3.6951 1 P 0 ;0,1,2=149,3=90.000000
L 0.72446683 3.6951 0.72188307 3.69701703 1 P 0 ;0,1,2=149,3=90.000000
L 0.6945 3.72149961 0.69501654 3.72418307 1 P 0 ;0,1,2=149,3=90.000000
L 0.69501654 3.72418307 0.69656614 3.7272498 1 P 0 ;0,1,2=149,3=90.000000
L 0.69656614 3.7272498 0.69914892 3.72916673 1 P 0 ;0,1,2=149,3=90.000000
L 0.69914892 3.72916673 0.70276673 3.72993327 1 P 0 ;0,1,2=149,3=90.000000
L 0.70276673 3.72993327 0.70638268 3.72916673 1 P 0 ;0,1,2=149,3=90.000000
L 0.70638268 3.72916673 0.70948287 3.72686654 1 P 0 ;0,1,2=149,3=90.000000
L 0.70948287 3.72686654 0.71103356 3.72341654 1 P 0 ;0,1,2=149,3=90.000000
L 0.71103356 3.72341654 0.71103356 3.71958337 1 P 0 ;0,1,2=149,3=90.000000
L 0.71103356 3.71958337 0.71206663 3.71728317 1 P 0 ;0,1,2=149,3=90.000000
L 0.71206663 3.71728317 0.71464941 3.71536614 1 P 0 ;0,1,2=149,3=90.000000
L 0.71464941 3.71536614 0.71826624 3.7145997 1 P 0 ;0,1,2=149,3=90.000000
L 0.71826624 3.7145997 0.72188307 3.7157501 1 P 0 ;0,1,2=149,3=90.000000
L 0.72188307 3.7157501 0.72446683 3.71843287 1 P 0 ;0,1,2=149,3=90.000000
L 0.72446683 3.71843287 0.7255 3.72149961 1 P 0 ;0,1,2=149,3=90.000000
L 0.7255 3.72149961 0.72446683 3.72456634 1 P 0 ;0,1,2=149,3=90.000000
L 0.72446683 3.72456634 0.72188307 3.7272498 1 P 0 ;0,1,2=149,3=90.000000
L 0.72188307 3.7272498 0.71826624 3.7284002 1 P 0 ;0,1,2=149,3=90.000000
L 0.71826624 3.7284002 0.71464941 3.72763307 1 P 0 ;0,1,2=149,3=90.000000
L 0.71464941 3.72763307 0.71206663 3.72571673 1 P 0 ;0,1,2=149,3=90.000000
L 0.71206663 3.72571673 0.71103356 3.72341654 1 P 0 ;0,1,2=149,3=90.000000
L 0.71103356 3.72341654 0.71103356 3.71958337 1 P 0 ;0,1,2=149,3=90.000000
L 0.71103356 3.71958337 0.70948287 3.71613337 1 P 0 ;0,1,2=149,3=90.000000
L 0.70948287 3.71613337 0.70638268 3.71383317 1 P 0 ;0,1,2=149,3=90.000000
L 0.70638268 3.71383317 0.70276673 3.71306663 1 P 0 ;0,1,2=149,3=90.000000
L 0.70276673 3.71306663 0.69914892 3.71383317 1 P 0 ;0,1,2=149,3=90.000000
L 0.69914892 3.71383317 0.69656614 3.7157501 1 P 0 ;0,1,2=149,3=90.000000
L 0.69656614 3.7157501 0.69501654 3.71881683 1 P 0 ;0,1,2=149,3=90.000000
L 0.69501654 3.71881683 0.6945 3.72149961 1 P 0 ;0,1,2=149,3=90.000000
L 0.928 3.63 0.972 3.63 1 P 0 
L 0.928 3.54 0.928 3.63 1 P 0 
L 0.972 3.63 0.972 3.54 1 P 0 
L 0.972 3.54 0.928 3.54 1 P 0 
L 0.7345 3.62083317 0.7655 3.62083317 1 P 0 ;0,1,2=150,3=90.000000
L 0.7655 3.62083317 0.7655 3.63041654 1 P 0 ;0,1,2=150,3=90.000000
L 0.7655 3.63041654 0.76394931 3.63348327 1 P 0 ;0,1,2=150,3=90.000000
L 0.76394931 3.63348327 0.76188307 3.6354002 1 P 0 ;0,1,2=150,3=90.000000
L 0.76188307 3.6354002 0.7577497 3.63616673 1 P 0 ;0,1,2=150,3=90.000000
L 0.7577497 3.63616673 0.75361634 3.6354002 1 P 0 ;0,1,2=150,3=90.000000
L 0.75361634 3.6354002 0.75103356 3.6331 1 P 0 ;0,1,2=150,3=90.000000
L 0.75103356 3.6331 0.74948287 3.63041654 1 P 0 ;0,1,2=150,3=90.000000
L 0.74948287 3.63041654 0.74948287 3.62083317 1 P 0 ;0,1,2=150,3=90.000000
L 0.74948287 3.63041654 0.7345 3.63616673 1 P 0 ;0,1,2=150,3=90.000000
L 0.7345 3.6641 0.7655 3.6641 1 P 0 ;0,1,2=150,3=90.000000
L 0.7655 3.6641 0.74328327 3.64991624 1 P 0 ;0,1,2=150,3=90.000000
L 0.74328327 3.64991624 0.74328327 3.66908366 1 P 0 ;0,1,2=150,3=90.000000
L 0.74741575 3.68321644 0.75103356 3.6858999 1 P 0 ;0,1,2=150,3=90.000000
L 0.75103356 3.6858999 0.7530998 3.6882001 1 P 0 ;0,1,2=150,3=90.000000
L 0.7530998 3.6882001 0.75413287 3.69126683 1 P 0 ;0,1,2=150,3=90.000000
L 0.75413287 3.69126683 0.7530998 3.6939503 1 P 0 ;0,1,2=150,3=90.000000
L 0.7530998 3.6939503 0.75103356 3.69586654 1 P 0 ;0,1,2=150,3=90.000000
L 0.75103356 3.69586654 0.74793327 3.6974002 1 P 0 ;0,1,2=150,3=90.000000
L 0.74793327 3.6974002 0.74431644 3.69778346 1 P 0 ;0,1,2=150,3=90.000000
L 0.74431644 3.69778346 0.74121614 3.6974002 1 P 0 ;0,1,2=150,3=90.000000
L 0.74121614 3.6974002 0.73811585 3.69586654 1 P 0 ;0,1,2=150,3=90.000000
L 0.73811585 3.69586654 0.73553307 3.69356634 1 P 0 ;0,1,2=150,3=90.000000
L 0.73553307 3.69356634 0.7345 3.69088356 1 P 0 ;0,1,2=150,3=90.000000
L 0.7345 3.69088356 0.73553307 3.68781683 1 P 0 ;0,1,2=150,3=90.000000
L 0.73553307 3.68781683 0.73863238 3.68513337 1 P 0 ;0,1,2=150,3=90.000000
L 0.73863238 3.68513337 0.74328327 3.6835997 1 P 0 ;0,1,2=150,3=90.000000
L 0.74328327 3.6835997 0.7484498 3.68321644 1 P 0 ;0,1,2=150,3=90.000000
L 0.7484498 3.68321644 0.75516594 3.68398287 1 P 0 ;0,1,2=150,3=90.000000
L 0.75516594 3.68398287 0.75878376 3.68513337 1 P 0 ;0,1,2=150,3=90.000000
L 0.75878376 3.68513337 0.7623997 3.68704961 1 P 0 ;0,1,2=150,3=90.000000
L 0.7623997 3.68704961 0.76498337 3.68973307 1 P 0 ;0,1,2=150,3=90.000000
L 0.76498337 3.68973307 0.7655 3.69241654 1 P 0 ;0,1,2=150,3=90.000000
L 0.7655 3.69241654 0.76446683 3.6951 1 P 0 ;0,1,2=150,3=90.000000
L 0.76446683 3.6951 0.76188307 3.69701703 1 P 0 ;0,1,2=150,3=90.000000
L 0.7345 3.72073307 0.74121614 3.72149961 1 P 0 ;0,1,2=150,3=90.000000
L 0.74121614 3.72149961 0.74689921 3.7226501 1 P 0 ;0,1,2=150,3=90.000000
L 0.74689921 3.7226501 0.75206663 3.72418307 1 P 0 ;0,1,2=150,3=90.000000
L 0.75206663 3.72418307 0.7577497 3.7261 1 P 0 ;0,1,2=150,3=90.000000
L 0.7577497 3.7261 0.7655 3.72916673 1 P 0 ;0,1,2=150,3=90.000000
L 0.7655 3.72916673 0.7655 3.71383317 1 P 0 ;0,1,2=150,3=90.000000
L 5.958 1.805 6.002 1.805 1 P 0 
L 6.002 1.805 6.002 1.715 1 P 0 
L 6.002 1.715 5.958 1.715 1 P 0 
L 5.958 1.715 5.958 1.805 1 P 0 
L 6.05916683 1.3545 6.05916683 1.3855 1 P 0 ;0,1,2=151,3=0.000000
L 6.05916683 1.3855 6.04958346 1.3855 1 P 0 ;0,1,2=151,3=0.000000
L 6.04958346 1.3855 6.04651673 1.38394931 1 P 0 ;0,1,2=151,3=0.000000
L 6.04651673 1.38394931 6.0445998 1.38188307 1 P 0 ;0,1,2=151,3=0.000000
L 6.0445998 1.38188307 6.04383327 1.3777497 1 P 0 ;0,1,2=151,3=0.000000
L 6.04383327 1.3777497 6.0445998 1.37361634 1 P 0 ;0,1,2=151,3=0.000000
L 6.0445998 1.37361634 6.0469 1.37103356 1 P 0 ;0,1,2=151,3=0.000000
L 6.0469 1.37103356 6.04958346 1.36948287 1 P 0 ;0,1,2=151,3=0.000000
L 6.04958346 1.36948287 6.05916683 1.36948287 1 P 0 ;0,1,2=151,3=0.000000
L 6.04958346 1.36948287 6.04383327 1.3545 1 P 0 ;0,1,2=151,3=0.000000
L 6.0159 1.3545 6.0159 1.3855 1 P 0 ;0,1,2=151,3=0.000000
L 6.0159 1.3855 6.03008376 1.36328327 1 P 0 ;0,1,2=151,3=0.000000
L 6.03008376 1.36328327 6.01091634 1.36328327 1 P 0 ;0,1,2=151,3=0.000000
L 5.99793337 1.36069961 5.99563386 1.35708278 1 P 0 ;0,1,2=151,3=0.000000
L 5.99563386 1.35708278 5.99256713 1.35501654 1 P 0 ;0,1,2=151,3=0.000000
L 5.99256713 1.35501654 5.98911644 1.3545 1 P 0 ;0,1,2=151,3=0.000000
L 5.98911644 1.3545 5.9860497 1.35501654 1 P 0 ;0,1,2=151,3=0.000000
L 5.9860497 1.35501654 5.98298297 1.35759931 1 P 0 ;0,1,2=151,3=0.000000
L 5.98298297 1.35759931 5.98106673 1.36069961 1 P 0 ;0,1,2=151,3=0.000000
L 5.98106673 1.36069961 5.98068346 1.3637999 1 P 0 ;0,1,2=151,3=0.000000
L 5.98068346 1.3637999 5.98145 1.36741575 1 P 0 ;0,1,2=151,3=0.000000
L 5.98145 1.36741575 5.98413346 1.36999951 1 P 0 ;0,1,2=151,3=0.000000
L 5.98413346 1.36999951 5.98681693 1.37103356 1 P 0 ;0,1,2=151,3=0.000000
L 5.98681693 1.37103356 5.99026693 1.37103356 1 P 0 ;0,1,2=151,3=0.000000
L 5.98681693 1.37103356 5.98451673 1.37258317 1 P 0 ;0,1,2=151,3=0.000000
L 5.98451673 1.37258317 5.9825998 1.37516594 1 P 0 ;0,1,2=151,3=0.000000
L 5.9825998 1.37516594 5.98183327 1.37826624 1 P 0 ;0,1,2=151,3=0.000000
L 5.98183327 1.37826624 5.9825998 1.38136654 1 P 0 ;0,1,2=151,3=0.000000
L 5.9825998 1.38136654 5.98451673 1.38394931 1 P 0 ;0,1,2=151,3=0.000000
L 5.98451673 1.38394931 5.98796673 1.3855 1 P 0 ;0,1,2=151,3=0.000000
L 5.98796673 1.3855 5.99141663 1.38498337 1 P 0 ;0,1,2=151,3=0.000000
L 5.99141663 1.38498337 5.99486663 1.38291624 1 P 0 ;0,1,2=151,3=0.000000
L 5.9539 1.3545 5.9539 1.3855 1 P 0 ;0,1,2=151,3=0.000000
L 5.9539 1.3855 5.96808376 1.36328327 1 P 0 ;0,1,2=151,3=0.000000
L 5.96808376 1.36328327 5.94891634 1.36328327 1 P 0 ;0,1,2=151,3=0.000000
L 5.958 1.7 6.002 1.7 1 P 0 
L 6.002 1.7 6.002 1.61 1 P 0 
L 6.002 1.61 5.958 1.61 1 P 0 
L 5.958 1.61 5.958 1.7 1 P 0 
L 6.05916683 1.3095 6.05916683 1.3405 1 P 0 ;0,1,2=152,3=0.000000
L 6.05916683 1.3405 6.04958346 1.3405 1 P 0 ;0,1,2=152,3=0.000000
L 6.04958346 1.3405 6.04651673 1.33894931 1 P 0 ;0,1,2=152,3=0.000000
L 6.04651673 1.33894931 6.0445998 1.33688307 1 P 0 ;0,1,2=152,3=0.000000
L 6.0445998 1.33688307 6.04383327 1.3327497 1 P 0 ;0,1,2=152,3=0.000000
L 6.04383327 1.3327497 6.0445998 1.32861634 1 P 0 ;0,1,2=152,3=0.000000
L 6.0445998 1.32861634 6.0469 1.32603356 1 P 0 ;0,1,2=152,3=0.000000
L 6.0469 1.32603356 6.04958346 1.32448287 1 P 0 ;0,1,2=152,3=0.000000
L 6.04958346 1.32448287 6.05916683 1.32448287 1 P 0 ;0,1,2=152,3=0.000000
L 6.04958346 1.32448287 6.04383327 1.3095 1 P 0 ;0,1,2=152,3=0.000000
L 6.0159 1.3095 6.0159 1.3405 1 P 0 ;0,1,2=152,3=0.000000
L 6.0159 1.3405 6.03008376 1.31828327 1 P 0 ;0,1,2=152,3=0.000000
L 6.03008376 1.31828327 6.01091634 1.31828327 1 P 0 ;0,1,2=152,3=0.000000
L 5.99793337 1.31569961 5.99563386 1.31208278 1 P 0 ;0,1,2=152,3=0.000000
L 5.99563386 1.31208278 5.99256713 1.31001654 1 P 0 ;0,1,2=152,3=0.000000
L 5.99256713 1.31001654 5.98911644 1.3095 1 P 0 ;0,1,2=152,3=0.000000
L 5.98911644 1.3095 5.9860497 1.31001654 1 P 0 ;0,1,2=152,3=0.000000
L 5.9860497 1.31001654 5.98298297 1.31259931 1 P 0 ;0,1,2=152,3=0.000000
L 5.98298297 1.31259931 5.98106673 1.31569961 1 P 0 ;0,1,2=152,3=0.000000
L 5.98106673 1.31569961 5.98068346 1.3187999 1 P 0 ;0,1,2=152,3=0.000000
L 5.98068346 1.3187999 5.98145 1.32241575 1 P 0 ;0,1,2=152,3=0.000000
L 5.98145 1.32241575 5.98413346 1.32499951 1 P 0 ;0,1,2=152,3=0.000000
L 5.98413346 1.32499951 5.98681693 1.32603356 1 P 0 ;0,1,2=152,3=0.000000
L 5.98681693 1.32603356 5.99026693 1.32603356 1 P 0 ;0,1,2=152,3=0.000000
L 5.98681693 1.32603356 5.98451673 1.32758317 1 P 0 ;0,1,2=152,3=0.000000
L 5.98451673 1.32758317 5.9825998 1.33016594 1 P 0 ;0,1,2=152,3=0.000000
L 5.9825998 1.33016594 5.98183327 1.33326624 1 P 0 ;0,1,2=152,3=0.000000
L 5.98183327 1.33326624 5.9825998 1.33636654 1 P 0 ;0,1,2=152,3=0.000000
L 5.9825998 1.33636654 5.98451673 1.33894931 1 P 0 ;0,1,2=152,3=0.000000
L 5.98451673 1.33894931 5.98796673 1.3405 1 P 0 ;0,1,2=152,3=0.000000
L 5.98796673 1.3405 5.99141663 1.33998337 1 P 0 ;0,1,2=152,3=0.000000
L 5.99141663 1.33998337 5.99486663 1.33791624 1 P 0 ;0,1,2=152,3=0.000000
L 5.96693337 1.31569961 5.96463386 1.31208278 1 P 0 ;0,1,2=152,3=0.000000
L 5.96463386 1.31208278 5.96156713 1.31001654 1 P 0 ;0,1,2=152,3=0.000000
L 5.96156713 1.31001654 5.95811644 1.3095 1 P 0 ;0,1,2=152,3=0.000000
L 5.95811644 1.3095 5.9550497 1.31001654 1 P 0 ;0,1,2=152,3=0.000000
L 5.9550497 1.31001654 5.95198297 1.31259931 1 P 0 ;0,1,2=152,3=0.000000
L 5.95198297 1.31259931 5.95006673 1.31569961 1 P 0 ;0,1,2=152,3=0.000000
L 5.95006673 1.31569961 5.94968346 1.3187999 1 P 0 ;0,1,2=152,3=0.000000
L 5.94968346 1.3187999 5.95045 1.32241575 1 P 0 ;0,1,2=152,3=0.000000
L 5.95045 1.32241575 5.95313346 1.32499951 1 P 0 ;0,1,2=152,3=0.000000
L 5.95313346 1.32499951 5.95581693 1.32603356 1 P 0 ;0,1,2=152,3=0.000000
L 5.95581693 1.32603356 5.95926693 1.32603356 1 P 0 ;0,1,2=152,3=0.000000
L 5.95581693 1.32603356 5.95351673 1.32758317 1 P 0 ;0,1,2=152,3=0.000000
L 5.95351673 1.32758317 5.9515998 1.33016594 1 P 0 ;0,1,2=152,3=0.000000
L 5.9515998 1.33016594 5.95083327 1.33326624 1 P 0 ;0,1,2=152,3=0.000000
L 5.95083327 1.33326624 5.9515998 1.33636654 1 P 0 ;0,1,2=152,3=0.000000
L 5.9515998 1.33636654 5.95351673 1.33894931 1 P 0 ;0,1,2=152,3=0.000000
L 5.95351673 1.33894931 5.95696673 1.3405 1 P 0 ;0,1,2=152,3=0.000000
L 5.95696673 1.3405 5.96041663 1.33998337 1 P 0 ;0,1,2=152,3=0.000000
L 5.96041663 1.33998337 5.96386663 1.33791624 1 P 0 ;0,1,2=152,3=0.000000
L 6.002 1.605 6.002 1.515 1 P 0 
L 6.002 1.515 5.958 1.515 1 P 0 
L 5.958 1.515 5.958 1.605 1 P 0 
L 5.958 1.605 6.002 1.605 1 P 0 
L 6.05916683 1.2695 6.05916683 1.3005 1 P 0 ;0,1,2=153,3=0.000000
L 6.05916683 1.3005 6.04958346 1.3005 1 P 0 ;0,1,2=153,3=0.000000
L 6.04958346 1.3005 6.04651673 1.29894931 1 P 0 ;0,1,2=153,3=0.000000
L 6.04651673 1.29894931 6.0445998 1.29688307 1 P 0 ;0,1,2=153,3=0.000000
L 6.0445998 1.29688307 6.04383327 1.2927497 1 P 0 ;0,1,2=153,3=0.000000
L 6.04383327 1.2927497 6.0445998 1.28861634 1 P 0 ;0,1,2=153,3=0.000000
L 6.0445998 1.28861634 6.0469 1.28603356 1 P 0 ;0,1,2=153,3=0.000000
L 6.0469 1.28603356 6.04958346 1.28448287 1 P 0 ;0,1,2=153,3=0.000000
L 6.04958346 1.28448287 6.05916683 1.28448287 1 P 0 ;0,1,2=153,3=0.000000
L 6.04958346 1.28448287 6.04383327 1.2695 1 P 0 ;0,1,2=153,3=0.000000
L 6.0159 1.2695 6.0159 1.3005 1 P 0 ;0,1,2=153,3=0.000000
L 6.0159 1.3005 6.03008376 1.27828327 1 P 0 ;0,1,2=153,3=0.000000
L 6.03008376 1.27828327 6.01091634 1.27828327 1 P 0 ;0,1,2=153,3=0.000000
L 5.99793337 1.27569961 5.99563386 1.27208278 1 P 0 ;0,1,2=153,3=0.000000
L 5.99563386 1.27208278 5.99256713 1.27001654 1 P 0 ;0,1,2=153,3=0.000000
L 5.99256713 1.27001654 5.98911644 1.2695 1 P 0 ;0,1,2=153,3=0.000000
L 5.98911644 1.2695 5.9860497 1.27001654 1 P 0 ;0,1,2=153,3=0.000000
L 5.9860497 1.27001654 5.98298297 1.27259931 1 P 0 ;0,1,2=153,3=0.000000
L 5.98298297 1.27259931 5.98106673 1.27569961 1 P 0 ;0,1,2=153,3=0.000000
L 5.98106673 1.27569961 5.98068346 1.2787999 1 P 0 ;0,1,2=153,3=0.000000
L 5.98068346 1.2787999 5.98145 1.28241575 1 P 0 ;0,1,2=153,3=0.000000
L 5.98145 1.28241575 5.98413346 1.28499951 1 P 0 ;0,1,2=153,3=0.000000
L 5.98413346 1.28499951 5.98681693 1.28603356 1 P 0 ;0,1,2=153,3=0.000000
L 5.98681693 1.28603356 5.99026693 1.28603356 1 P 0 ;0,1,2=153,3=0.000000
L 5.98681693 1.28603356 5.98451673 1.28758317 1 P 0 ;0,1,2=153,3=0.000000
L 5.98451673 1.28758317 5.9825998 1.29016594 1 P 0 ;0,1,2=153,3=0.000000
L 5.9825998 1.29016594 5.98183327 1.29326624 1 P 0 ;0,1,2=153,3=0.000000
L 5.98183327 1.29326624 5.9825998 1.29636654 1 P 0 ;0,1,2=153,3=0.000000
L 5.9825998 1.29636654 5.98451673 1.29894931 1 P 0 ;0,1,2=153,3=0.000000
L 5.98451673 1.29894931 5.98796673 1.3005 1 P 0 ;0,1,2=153,3=0.000000
L 5.98796673 1.3005 5.99141663 1.29998337 1 P 0 ;0,1,2=153,3=0.000000
L 5.99141663 1.29998337 5.99486663 1.29791624 1 P 0 ;0,1,2=153,3=0.000000
L 5.96578356 1.29533346 5.96348337 1.29843278 1 P 0 ;0,1,2=153,3=0.000000
L 5.96348337 1.29843278 5.9607999 1.29998337 1 P 0 ;0,1,2=153,3=0.000000
L 5.9607999 1.29998337 5.95773317 1.3005 1 P 0 ;0,1,2=153,3=0.000000
L 5.95773317 1.3005 5.9539 1.29946683 1 P 0 ;0,1,2=153,3=0.000000
L 5.9539 1.29946683 5.95121654 1.29688307 1 P 0 ;0,1,2=153,3=0.000000
L 5.95121654 1.29688307 5.95045 1.29378376 1 P 0 ;0,1,2=153,3=0.000000
L 5.95045 1.29378376 5.95083327 1.29068258 1 P 0 ;0,1,2=153,3=0.000000
L 5.95083327 1.29068258 5.95236693 1.2880998 1 P 0 ;0,1,2=153,3=0.000000
L 5.95236693 1.2880998 5.96003337 1.28293327 1 P 0 ;0,1,2=153,3=0.000000
L 5.96003337 1.28293327 5.96348337 1.27931644 1 P 0 ;0,1,2=153,3=0.000000
L 5.96348337 1.27931644 5.96578356 1.27414892 1 P 0 ;0,1,2=153,3=0.000000
L 5.96578356 1.27414892 5.9665501 1.2695 1 P 0 ;0,1,2=153,3=0.000000
L 5.9665501 1.2695 5.95045 1.2695 1 P 0 ;0,1,2=153,3=0.000000
L 5.958 1.485 6.002 1.485 1 P 0 
L 6.002 1.485 6.002 1.395 1 P 0 
L 6.002 1.395 5.958 1.395 1 P 0 
L 5.958 1.395 5.958 1.485 1 P 0 
L 6.05916683 1.2295 6.05916683 1.2605 1 P 0 ;0,1,2=154,3=0.000000
L 6.05916683 1.2605 6.04958346 1.2605 1 P 0 ;0,1,2=154,3=0.000000
L 6.04958346 1.2605 6.04651673 1.25894931 1 P 0 ;0,1,2=154,3=0.000000
L 6.04651673 1.25894931 6.0445998 1.25688307 1 P 0 ;0,1,2=154,3=0.000000
L 6.0445998 1.25688307 6.04383327 1.2527497 1 P 0 ;0,1,2=154,3=0.000000
L 6.04383327 1.2527497 6.0445998 1.24861634 1 P 0 ;0,1,2=154,3=0.000000
L 6.0445998 1.24861634 6.0469 1.24603356 1 P 0 ;0,1,2=154,3=0.000000
L 6.0469 1.24603356 6.04958346 1.24448287 1 P 0 ;0,1,2=154,3=0.000000
L 6.04958346 1.24448287 6.05916683 1.24448287 1 P 0 ;0,1,2=154,3=0.000000
L 6.04958346 1.24448287 6.04383327 1.2295 1 P 0 ;0,1,2=154,3=0.000000
L 6.0159 1.2295 6.0159 1.2605 1 P 0 ;0,1,2=154,3=0.000000
L 6.0159 1.2605 6.03008376 1.23828327 1 P 0 ;0,1,2=154,3=0.000000
L 6.03008376 1.23828327 6.01091634 1.23828327 1 P 0 ;0,1,2=154,3=0.000000
L 5.99793337 1.23569961 5.99563386 1.23208278 1 P 0 ;0,1,2=154,3=0.000000
L 5.99563386 1.23208278 5.99256713 1.23001654 1 P 0 ;0,1,2=154,3=0.000000
L 5.99256713 1.23001654 5.98911644 1.2295 1 P 0 ;0,1,2=154,3=0.000000
L 5.98911644 1.2295 5.9860497 1.23001654 1 P 0 ;0,1,2=154,3=0.000000
L 5.9860497 1.23001654 5.98298297 1.23259931 1 P 0 ;0,1,2=154,3=0.000000
L 5.98298297 1.23259931 5.98106673 1.23569961 1 P 0 ;0,1,2=154,3=0.000000
L 5.98106673 1.23569961 5.98068346 1.2387999 1 P 0 ;0,1,2=154,3=0.000000
L 5.98068346 1.2387999 5.98145 1.24241575 1 P 0 ;0,1,2=154,3=0.000000
L 5.98145 1.24241575 5.98413346 1.24499951 1 P 0 ;0,1,2=154,3=0.000000
L 5.98413346 1.24499951 5.98681693 1.24603356 1 P 0 ;0,1,2=154,3=0.000000
L 5.98681693 1.24603356 5.99026693 1.24603356 1 P 0 ;0,1,2=154,3=0.000000
L 5.98681693 1.24603356 5.98451673 1.24758317 1 P 0 ;0,1,2=154,3=0.000000
L 5.98451673 1.24758317 5.9825998 1.25016594 1 P 0 ;0,1,2=154,3=0.000000
L 5.9825998 1.25016594 5.98183327 1.25326624 1 P 0 ;0,1,2=154,3=0.000000
L 5.98183327 1.25326624 5.9825998 1.25636654 1 P 0 ;0,1,2=154,3=0.000000
L 5.9825998 1.25636654 5.98451673 1.25894931 1 P 0 ;0,1,2=154,3=0.000000
L 5.98451673 1.25894931 5.98796673 1.2605 1 P 0 ;0,1,2=154,3=0.000000
L 5.98796673 1.2605 5.99141663 1.25998337 1 P 0 ;0,1,2=154,3=0.000000
L 5.99141663 1.25998337 5.99486663 1.25791624 1 P 0 ;0,1,2=154,3=0.000000
L 5.95850039 1.2295 5.95850039 1.2605 1 P 0 ;0,1,2=154,3=0.000000
L 5.95850039 1.2605 5.9631001 1.2543003 1 P 0 ;0,1,2=154,3=0.000000
L 5.9631001 1.2295 5.95390069 1.2295 1 P 0 ;0,1,2=154,3=0.000000
L 6.133 1.835 6.177 1.835 1 P 0 
L 6.177 1.835 6.177 1.745 1 P 0 
L 6.177 1.745 6.133 1.745 1 P 0 
L 6.133 1.745 6.133 1.835 1 P 0 
L 6.19916683 1.3545 6.19916683 1.3855 1 P 0 ;0,1,2=155,3=0.000000
L 6.19916683 1.3855 6.18958346 1.3855 1 P 0 ;0,1,2=155,3=0.000000
L 6.18958346 1.3855 6.18651673 1.38394931 1 P 0 ;0,1,2=155,3=0.000000
L 6.18651673 1.38394931 6.1845998 1.38188307 1 P 0 ;0,1,2=155,3=0.000000
L 6.1845998 1.38188307 6.18383327 1.3777497 1 P 0 ;0,1,2=155,3=0.000000
L 6.18383327 1.3777497 6.1845998 1.37361634 1 P 0 ;0,1,2=155,3=0.000000
L 6.1845998 1.37361634 6.1869 1.37103356 1 P 0 ;0,1,2=155,3=0.000000
L 6.1869 1.37103356 6.18958346 1.36948287 1 P 0 ;0,1,2=155,3=0.000000
L 6.18958346 1.36948287 6.19916683 1.36948287 1 P 0 ;0,1,2=155,3=0.000000
L 6.18958346 1.36948287 6.18383327 1.3545 1 P 0 ;0,1,2=155,3=0.000000
L 6.1559 1.3545 6.1559 1.3855 1 P 0 ;0,1,2=155,3=0.000000
L 6.1559 1.3855 6.17008376 1.36328327 1 P 0 ;0,1,2=155,3=0.000000
L 6.17008376 1.36328327 6.15091634 1.36328327 1 P 0 ;0,1,2=155,3=0.000000
L 6.13793337 1.36069961 6.13563386 1.35708278 1 P 0 ;0,1,2=155,3=0.000000
L 6.13563386 1.35708278 6.13256713 1.35501654 1 P 0 ;0,1,2=155,3=0.000000
L 6.13256713 1.35501654 6.12911644 1.3545 1 P 0 ;0,1,2=155,3=0.000000
L 6.12911644 1.3545 6.1260497 1.35501654 1 P 0 ;0,1,2=155,3=0.000000
L 6.1260497 1.35501654 6.12298297 1.35759931 1 P 0 ;0,1,2=155,3=0.000000
L 6.12298297 1.35759931 6.12106673 1.36069961 1 P 0 ;0,1,2=155,3=0.000000
L 6.12106673 1.36069961 6.12068346 1.3637999 1 P 0 ;0,1,2=155,3=0.000000
L 6.12068346 1.3637999 6.12145 1.36741575 1 P 0 ;0,1,2=155,3=0.000000
L 6.12145 1.36741575 6.12413346 1.36999951 1 P 0 ;0,1,2=155,3=0.000000
L 6.12413346 1.36999951 6.12681693 1.37103356 1 P 0 ;0,1,2=155,3=0.000000
L 6.12681693 1.37103356 6.13026693 1.37103356 1 P 0 ;0,1,2=155,3=0.000000
L 6.12681693 1.37103356 6.12451673 1.37258317 1 P 0 ;0,1,2=155,3=0.000000
L 6.12451673 1.37258317 6.1225998 1.37516594 1 P 0 ;0,1,2=155,3=0.000000
L 6.1225998 1.37516594 6.12183327 1.37826624 1 P 0 ;0,1,2=155,3=0.000000
L 6.12183327 1.37826624 6.1225998 1.38136654 1 P 0 ;0,1,2=155,3=0.000000
L 6.1225998 1.38136654 6.12451673 1.38394931 1 P 0 ;0,1,2=155,3=0.000000
L 6.12451673 1.38394931 6.12796673 1.3855 1 P 0 ;0,1,2=155,3=0.000000
L 6.12796673 1.3855 6.13141663 1.38498337 1 P 0 ;0,1,2=155,3=0.000000
L 6.13141663 1.38498337 6.13486663 1.38291624 1 P 0 ;0,1,2=155,3=0.000000
L 6.09850039 1.3855 6.10156713 1.38446683 1 P 0 ;0,1,2=155,3=0.000000
L 6.10156713 1.38446683 6.10386663 1.38188307 1 P 0 ;0,1,2=155,3=0.000000
L 6.10386663 1.38188307 6.1054003 1.37878376 1 P 0 ;0,1,2=155,3=0.000000
L 6.1054003 1.37878376 6.1065501 1.37464941 1 P 0 ;0,1,2=155,3=0.000000
L 6.1065501 1.37464941 6.10693337 1.36999951 1 P 0 ;0,1,2=155,3=0.000000
L 6.10693337 1.36999951 6.1065501 1.36534951 1 P 0 ;0,1,2=155,3=0.000000
L 6.1065501 1.36534951 6.1054003 1.36121614 1 P 0 ;0,1,2=155,3=0.000000
L 6.1054003 1.36121614 6.10386663 1.35811585 1 P 0 ;0,1,2=155,3=0.000000
L 6.10386663 1.35811585 6.10156713 1.35553307 1 P 0 ;0,1,2=155,3=0.000000
L 6.10156713 1.35553307 6.09850039 1.3545 1 P 0 ;0,1,2=155,3=0.000000
L 6.09850039 1.3545 6.09543366 1.35553307 1 P 0 ;0,1,2=155,3=0.000000
L 6.09543366 1.35553307 6.09313346 1.35811585 1 P 0 ;0,1,2=155,3=0.000000
L 6.09313346 1.35811585 6.0915998 1.36121614 1 P 0 ;0,1,2=155,3=0.000000
L 6.0915998 1.36121614 6.09045 1.36534951 1 P 0 ;0,1,2=155,3=0.000000
L 6.09045 1.36534951 6.09006673 1.36999951 1 P 0 ;0,1,2=155,3=0.000000
L 6.09006673 1.36999951 6.09045 1.37464941 1 P 0 ;0,1,2=155,3=0.000000
L 6.09045 1.37464941 6.0915998 1.37878376 1 P 0 ;0,1,2=155,3=0.000000
L 6.0915998 1.37878376 6.09313346 1.38188307 1 P 0 ;0,1,2=155,3=0.000000
L 6.09313346 1.38188307 6.09543366 1.38446683 1 P 0 ;0,1,2=155,3=0.000000
L 6.09543366 1.38446683 6.09850039 1.3855 1 P 0 ;0,1,2=155,3=0.000000
L 6.148 1.7 6.192 1.7 1 P 0 
L 6.148 1.61 6.148 1.7 1 P 0 
L 6.192 1.7 6.192 1.61 1 P 0 
L 6.192 1.61 6.148 1.61 1 P 0 
L 6.19916683 1.3145 6.19916683 1.3455 1 P 0 ;0,1,2=156,3=0.000000
L 6.19916683 1.3455 6.18958346 1.3455 1 P 0 ;0,1,2=156,3=0.000000
L 6.18958346 1.3455 6.18651673 1.34394931 1 P 0 ;0,1,2=156,3=0.000000
L 6.18651673 1.34394931 6.1845998 1.34188307 1 P 0 ;0,1,2=156,3=0.000000
L 6.1845998 1.34188307 6.18383327 1.3377497 1 P 0 ;0,1,2=156,3=0.000000
L 6.18383327 1.3377497 6.1845998 1.33361634 1 P 0 ;0,1,2=156,3=0.000000
L 6.1845998 1.33361634 6.1869 1.33103356 1 P 0 ;0,1,2=156,3=0.000000
L 6.1869 1.33103356 6.18958346 1.32948287 1 P 0 ;0,1,2=156,3=0.000000
L 6.18958346 1.32948287 6.19916683 1.32948287 1 P 0 ;0,1,2=156,3=0.000000
L 6.18958346 1.32948287 6.18383327 1.3145 1 P 0 ;0,1,2=156,3=0.000000
L 6.1559 1.3145 6.1559 1.3455 1 P 0 ;0,1,2=156,3=0.000000
L 6.1559 1.3455 6.17008376 1.32328327 1 P 0 ;0,1,2=156,3=0.000000
L 6.17008376 1.32328327 6.15091634 1.32328327 1 P 0 ;0,1,2=156,3=0.000000
L 6.13678356 1.34033346 6.13448337 1.34343278 1 P 0 ;0,1,2=156,3=0.000000
L 6.13448337 1.34343278 6.1317999 1.34498337 1 P 0 ;0,1,2=156,3=0.000000
L 6.1317999 1.34498337 6.12873317 1.3455 1 P 0 ;0,1,2=156,3=0.000000
L 6.12873317 1.3455 6.1249 1.34446683 1 P 0 ;0,1,2=156,3=0.000000
L 6.1249 1.34446683 6.12221654 1.34188307 1 P 0 ;0,1,2=156,3=0.000000
L 6.12221654 1.34188307 6.12145 1.33878376 1 P 0 ;0,1,2=156,3=0.000000
L 6.12145 1.33878376 6.12183327 1.33568258 1 P 0 ;0,1,2=156,3=0.000000
L 6.12183327 1.33568258 6.12336693 1.3330998 1 P 0 ;0,1,2=156,3=0.000000
L 6.12336693 1.3330998 6.13103337 1.32793327 1 P 0 ;0,1,2=156,3=0.000000
L 6.13103337 1.32793327 6.13448337 1.32431644 1 P 0 ;0,1,2=156,3=0.000000
L 6.13448337 1.32431644 6.13678356 1.31914892 1 P 0 ;0,1,2=156,3=0.000000
L 6.13678356 1.31914892 6.1375501 1.3145 1 P 0 ;0,1,2=156,3=0.000000
L 6.1375501 1.3145 6.12145 1.3145 1 P 0 ;0,1,2=156,3=0.000000
L 6.10501713 1.31811585 6.10233366 1.31553307 1 P 0 ;0,1,2=156,3=0.000000
L 6.10233366 1.31553307 6.09926693 1.3145 1 P 0 ;0,1,2=156,3=0.000000
L 6.09926693 1.3145 6.0962002 1.31553307 1 P 0 ;0,1,2=156,3=0.000000
L 6.0962002 1.31553307 6.09351673 1.31863238 1 P 0 ;0,1,2=156,3=0.000000
L 6.09351673 1.31863238 6.0915998 1.32328327 1 P 0 ;0,1,2=156,3=0.000000
L 6.0915998 1.32328327 6.09083327 1.32793327 1 P 0 ;0,1,2=156,3=0.000000
L 6.09083327 1.32793327 6.09083327 1.33361634 1 P 0 ;0,1,2=156,3=0.000000
L 6.09083327 1.33361634 6.0915998 1.33826624 1 P 0 ;0,1,2=156,3=0.000000
L 6.0915998 1.33826624 6.09351673 1.3423997 1 P 0 ;0,1,2=156,3=0.000000
L 6.09351673 1.3423997 6.09581693 1.34446683 1 P 0 ;0,1,2=156,3=0.000000
L 6.09581693 1.34446683 6.09850039 1.3455 1 P 0 ;0,1,2=156,3=0.000000
L 6.09850039 1.3455 6.10156713 1.34446683 1 P 0 ;0,1,2=156,3=0.000000
L 6.10156713 1.34446683 6.10386663 1.3423997 1 P 0 ;0,1,2=156,3=0.000000
L 6.10386663 1.3423997 6.1054003 1.3393003 1 P 0 ;0,1,2=156,3=0.000000
L 6.1054003 1.3393003 6.10616683 1.33516594 1 P 0 ;0,1,2=156,3=0.000000
L 6.10616683 1.33516594 6.1054003 1.3315501 1 P 0 ;0,1,2=156,3=0.000000
L 6.1054003 1.3315501 6.10348337 1.32793327 1 P 0 ;0,1,2=156,3=0.000000
L 6.10348337 1.32793327 6.10118317 1.32586604 1 P 0 ;0,1,2=156,3=0.000000
L 6.10118317 1.32586604 6.09850039 1.32534951 1 P 0 ;0,1,2=156,3=0.000000
L 6.09850039 1.32534951 6.09543366 1.32638268 1 P 0 ;0,1,2=156,3=0.000000
L 6.09543366 1.32638268 6.09313346 1.32896634 1 P 0 ;0,1,2=156,3=0.000000
L 6.09313346 1.32896634 6.09083327 1.33361634 1 P 0 ;0,1,2=156,3=0.000000
L 6.148 1.51 6.148 1.6 1 P 0 
L 6.148 1.6 6.192 1.6 1 P 0 
L 6.192 1.6 6.192 1.51 1 P 0 
L 6.192 1.51 6.148 1.51 1 P 0 
L 6.19916683 1.2745 6.19916683 1.3055 1 P 0 ;0,1,2=157,3=0.000000
L 6.19916683 1.3055 6.18958346 1.3055 1 P 0 ;0,1,2=157,3=0.000000
L 6.18958346 1.3055 6.18651673 1.30394931 1 P 0 ;0,1,2=157,3=0.000000
L 6.18651673 1.30394931 6.1845998 1.30188307 1 P 0 ;0,1,2=157,3=0.000000
L 6.1845998 1.30188307 6.18383327 1.2977497 1 P 0 ;0,1,2=157,3=0.000000
L 6.18383327 1.2977497 6.1845998 1.29361634 1 P 0 ;0,1,2=157,3=0.000000
L 6.1845998 1.29361634 6.1869 1.29103356 1 P 0 ;0,1,2=157,3=0.000000
L 6.1869 1.29103356 6.18958346 1.28948287 1 P 0 ;0,1,2=157,3=0.000000
L 6.18958346 1.28948287 6.19916683 1.28948287 1 P 0 ;0,1,2=157,3=0.000000
L 6.18958346 1.28948287 6.18383327 1.2745 1 P 0 ;0,1,2=157,3=0.000000
L 6.1559 1.2745 6.1559 1.3055 1 P 0 ;0,1,2=157,3=0.000000
L 6.1559 1.3055 6.17008376 1.28328327 1 P 0 ;0,1,2=157,3=0.000000
L 6.17008376 1.28328327 6.15091634 1.28328327 1 P 0 ;0,1,2=157,3=0.000000
L 6.13678356 1.30033346 6.13448337 1.30343278 1 P 0 ;0,1,2=157,3=0.000000
L 6.13448337 1.30343278 6.1317999 1.30498337 1 P 0 ;0,1,2=157,3=0.000000
L 6.1317999 1.30498337 6.12873317 1.3055 1 P 0 ;0,1,2=157,3=0.000000
L 6.12873317 1.3055 6.1249 1.30446683 1 P 0 ;0,1,2=157,3=0.000000
L 6.1249 1.30446683 6.12221654 1.30188307 1 P 0 ;0,1,2=157,3=0.000000
L 6.12221654 1.30188307 6.12145 1.29878376 1 P 0 ;0,1,2=157,3=0.000000
L 6.12145 1.29878376 6.12183327 1.29568258 1 P 0 ;0,1,2=157,3=0.000000
L 6.12183327 1.29568258 6.12336693 1.2930998 1 P 0 ;0,1,2=157,3=0.000000
L 6.12336693 1.2930998 6.13103337 1.28793327 1 P 0 ;0,1,2=157,3=0.000000
L 6.13103337 1.28793327 6.13448337 1.28431644 1 P 0 ;0,1,2=157,3=0.000000
L 6.13448337 1.28431644 6.13678356 1.27914892 1 P 0 ;0,1,2=157,3=0.000000
L 6.13678356 1.27914892 6.1375501 1.2745 1 P 0 ;0,1,2=157,3=0.000000
L 6.1375501 1.2745 6.12145 1.2745 1 P 0 ;0,1,2=157,3=0.000000
L 6.09850039 1.2745 6.09581693 1.27501654 1 P 0 ;0,1,2=157,3=0.000000
L 6.09581693 1.27501654 6.0927502 1.27656614 1 P 0 ;0,1,2=157,3=0.000000
L 6.0927502 1.27656614 6.09083327 1.27914892 1 P 0 ;0,1,2=157,3=0.000000
L 6.09083327 1.27914892 6.09006673 1.28276673 1 P 0 ;0,1,2=157,3=0.000000
L 6.09006673 1.28276673 6.09083327 1.28638268 1 P 0 ;0,1,2=157,3=0.000000
L 6.09083327 1.28638268 6.09313346 1.28948287 1 P 0 ;0,1,2=157,3=0.000000
L 6.09313346 1.28948287 6.09658346 1.29103356 1 P 0 ;0,1,2=157,3=0.000000
L 6.09658346 1.29103356 6.10041663 1.29103356 1 P 0 ;0,1,2=157,3=0.000000
L 6.10041663 1.29103356 6.10271683 1.29206663 1 P 0 ;0,1,2=157,3=0.000000
L 6.10271683 1.29206663 6.10463386 1.29464941 1 P 0 ;0,1,2=157,3=0.000000
L 6.10463386 1.29464941 6.1054003 1.29826624 1 P 0 ;0,1,2=157,3=0.000000
L 6.1054003 1.29826624 6.1042499 1.30188307 1 P 0 ;0,1,2=157,3=0.000000
L 6.1042499 1.30188307 6.10156713 1.30446683 1 P 0 ;0,1,2=157,3=0.000000
L 6.10156713 1.30446683 6.09850039 1.3055 1 P 0 ;0,1,2=157,3=0.000000
L 6.09850039 1.3055 6.09543366 1.30446683 1 P 0 ;0,1,2=157,3=0.000000
L 6.09543366 1.30446683 6.0927502 1.30188307 1 P 0 ;0,1,2=157,3=0.000000
L 6.0927502 1.30188307 6.0915998 1.29826624 1 P 0 ;0,1,2=157,3=0.000000
L 6.0915998 1.29826624 6.09236693 1.29464941 1 P 0 ;0,1,2=157,3=0.000000
L 6.09236693 1.29464941 6.09428327 1.29206663 1 P 0 ;0,1,2=157,3=0.000000
L 6.09428327 1.29206663 6.09658346 1.29103356 1 P 0 ;0,1,2=157,3=0.000000
L 6.09658346 1.29103356 6.10041663 1.29103356 1 P 0 ;0,1,2=157,3=0.000000
L 6.10041663 1.29103356 6.10386663 1.28948287 1 P 0 ;0,1,2=157,3=0.000000
L 6.10386663 1.28948287 6.10616683 1.28638268 1 P 0 ;0,1,2=157,3=0.000000
L 6.10616683 1.28638268 6.10693337 1.28276673 1 P 0 ;0,1,2=157,3=0.000000
L 6.10693337 1.28276673 6.10616683 1.27914892 1 P 0 ;0,1,2=157,3=0.000000
L 6.10616683 1.27914892 6.1042499 1.27656614 1 P 0 ;0,1,2=157,3=0.000000
L 6.1042499 1.27656614 6.10118317 1.27501654 1 P 0 ;0,1,2=157,3=0.000000
L 6.10118317 1.27501654 6.09850039 1.2745 1 P 0 ;0,1,2=157,3=0.000000
L 6.148 1.5 6.192 1.5 1 P 0 
L 6.148 1.41 6.148 1.5 1 P 0 
L 6.192 1.5 6.192 1.41 1 P 0 
L 6.192 1.41 6.148 1.41 1 P 0 
L 6.19916683 1.2345 6.19916683 1.2655 1 P 0 ;0,1,2=158,3=0.000000
L 6.19916683 1.2655 6.18958346 1.2655 1 P 0 ;0,1,2=158,3=0.000000
L 6.18958346 1.2655 6.18651673 1.26394931 1 P 0 ;0,1,2=158,3=0.000000
L 6.18651673 1.26394931 6.1845998 1.26188307 1 P 0 ;0,1,2=158,3=0.000000
L 6.1845998 1.26188307 6.18383327 1.2577497 1 P 0 ;0,1,2=158,3=0.000000
L 6.18383327 1.2577497 6.1845998 1.25361634 1 P 0 ;0,1,2=158,3=0.000000
L 6.1845998 1.25361634 6.1869 1.25103356 1 P 0 ;0,1,2=158,3=0.000000
L 6.1869 1.25103356 6.18958346 1.24948287 1 P 0 ;0,1,2=158,3=0.000000
L 6.18958346 1.24948287 6.19916683 1.24948287 1 P 0 ;0,1,2=158,3=0.000000
L 6.18958346 1.24948287 6.18383327 1.2345 1 P 0 ;0,1,2=158,3=0.000000
L 6.16893337 1.24069961 6.16663386 1.23708278 1 P 0 ;0,1,2=158,3=0.000000
L 6.16663386 1.23708278 6.16356713 1.23501654 1 P 0 ;0,1,2=158,3=0.000000
L 6.16356713 1.23501654 6.16011644 1.2345 1 P 0 ;0,1,2=158,3=0.000000
L 6.16011644 1.2345 6.1570497 1.23501654 1 P 0 ;0,1,2=158,3=0.000000
L 6.1570497 1.23501654 6.15398297 1.23759931 1 P 0 ;0,1,2=158,3=0.000000
L 6.15398297 1.23759931 6.15206673 1.24069961 1 P 0 ;0,1,2=158,3=0.000000
L 6.15206673 1.24069961 6.15168346 1.2437999 1 P 0 ;0,1,2=158,3=0.000000
L 6.15168346 1.2437999 6.15245 1.24741575 1 P 0 ;0,1,2=158,3=0.000000
L 6.15245 1.24741575 6.15513346 1.24999951 1 P 0 ;0,1,2=158,3=0.000000
L 6.15513346 1.24999951 6.15781693 1.25103356 1 P 0 ;0,1,2=158,3=0.000000
L 6.15781693 1.25103356 6.16126693 1.25103356 1 P 0 ;0,1,2=158,3=0.000000
L 6.15781693 1.25103356 6.15551673 1.25258317 1 P 0 ;0,1,2=158,3=0.000000
L 6.15551673 1.25258317 6.1535998 1.25516594 1 P 0 ;0,1,2=158,3=0.000000
L 6.1535998 1.25516594 6.15283327 1.25826624 1 P 0 ;0,1,2=158,3=0.000000
L 6.15283327 1.25826624 6.1535998 1.26136654 1 P 0 ;0,1,2=158,3=0.000000
L 6.1535998 1.26136654 6.15551673 1.26394931 1 P 0 ;0,1,2=158,3=0.000000
L 6.15551673 1.26394931 6.15896673 1.2655 1 P 0 ;0,1,2=158,3=0.000000
L 6.15896673 1.2655 6.16241663 1.26498337 1 P 0 ;0,1,2=158,3=0.000000
L 6.16241663 1.26498337 6.16586663 1.26291624 1 P 0 ;0,1,2=158,3=0.000000
L 6.13678356 1.26033346 6.13448337 1.26343278 1 P 0 ;0,1,2=158,3=0.000000
L 6.13448337 1.26343278 6.1317999 1.26498337 1 P 0 ;0,1,2=158,3=0.000000
L 6.1317999 1.26498337 6.12873317 1.2655 1 P 0 ;0,1,2=158,3=0.000000
L 6.12873317 1.2655 6.1249 1.26446683 1 P 0 ;0,1,2=158,3=0.000000
L 6.1249 1.26446683 6.12221654 1.26188307 1 P 0 ;0,1,2=158,3=0.000000
L 6.12221654 1.26188307 6.12145 1.25878376 1 P 0 ;0,1,2=158,3=0.000000
L 6.12145 1.25878376 6.12183327 1.25568258 1 P 0 ;0,1,2=158,3=0.000000
L 6.12183327 1.25568258 6.12336693 1.2530998 1 P 0 ;0,1,2=158,3=0.000000
L 6.12336693 1.2530998 6.13103337 1.24793327 1 P 0 ;0,1,2=158,3=0.000000
L 6.13103337 1.24793327 6.13448337 1.24431644 1 P 0 ;0,1,2=158,3=0.000000
L 6.13448337 1.24431644 6.13678356 1.23914892 1 P 0 ;0,1,2=158,3=0.000000
L 6.13678356 1.23914892 6.1375501 1.2345 1 P 0 ;0,1,2=158,3=0.000000
L 6.1375501 1.2345 6.12145 1.2345 1 P 0 ;0,1,2=158,3=0.000000
L 6.10501713 1.23811585 6.10233366 1.23553307 1 P 0 ;0,1,2=158,3=0.000000
L 6.10233366 1.23553307 6.09926693 1.2345 1 P 0 ;0,1,2=158,3=0.000000
L 6.09926693 1.2345 6.0962002 1.23553307 1 P 0 ;0,1,2=158,3=0.000000
L 6.0962002 1.23553307 6.09351673 1.23863238 1 P 0 ;0,1,2=158,3=0.000000
L 6.09351673 1.23863238 6.0915998 1.24328327 1 P 0 ;0,1,2=158,3=0.000000
L 6.0915998 1.24328327 6.09083327 1.24793327 1 P 0 ;0,1,2=158,3=0.000000
L 6.09083327 1.24793327 6.09083327 1.25361634 1 P 0 ;0,1,2=158,3=0.000000
L 6.09083327 1.25361634 6.0915998 1.25826624 1 P 0 ;0,1,2=158,3=0.000000
L 6.0915998 1.25826624 6.09351673 1.2623997 1 P 0 ;0,1,2=158,3=0.000000
L 6.09351673 1.2623997 6.09581693 1.26446683 1 P 0 ;0,1,2=158,3=0.000000
L 6.09581693 1.26446683 6.09850039 1.2655 1 P 0 ;0,1,2=158,3=0.000000
L 6.09850039 1.2655 6.10156713 1.26446683 1 P 0 ;0,1,2=158,3=0.000000
L 6.10156713 1.26446683 6.10386663 1.2623997 1 P 0 ;0,1,2=158,3=0.000000
L 6.10386663 1.2623997 6.1054003 1.2593003 1 P 0 ;0,1,2=158,3=0.000000
L 6.1054003 1.2593003 6.10616683 1.25516594 1 P 0 ;0,1,2=158,3=0.000000
L 6.10616683 1.25516594 6.1054003 1.2515501 1 P 0 ;0,1,2=158,3=0.000000
L 6.1054003 1.2515501 6.10348337 1.24793327 1 P 0 ;0,1,2=158,3=0.000000
L 6.10348337 1.24793327 6.10118317 1.24586604 1 P 0 ;0,1,2=158,3=0.000000
L 6.10118317 1.24586604 6.09850039 1.24534951 1 P 0 ;0,1,2=158,3=0.000000
L 6.09850039 1.24534951 6.09543366 1.24638268 1 P 0 ;0,1,2=158,3=0.000000
L 6.09543366 1.24638268 6.09313346 1.24896634 1 P 0 ;0,1,2=158,3=0.000000
L 6.09313346 1.24896634 6.09083327 1.25361634 1 P 0 ;0,1,2=158,3=0.000000
L 4.76 0.937 4.76 0.893 1 P 0 
L 4.67 0.937 4.76 0.937 1 P 0 
L 4.76 0.893 4.67 0.893 1 P 0 
L 4.67 0.893 4.67 0.937 1 P 0 
L 4.76916683 0.8545 4.76916683 0.8855 1 P 0 ;0,1,2=159,3=0.000000
L 4.76916683 0.8855 4.75958346 0.8855 1 P 0 ;0,1,2=159,3=0.000000
L 4.75958346 0.8855 4.75651673 0.88394931 1 P 0 ;0,1,2=159,3=0.000000
L 4.75651673 0.88394931 4.7545998 0.88188307 1 P 0 ;0,1,2=159,3=0.000000
L 4.7545998 0.88188307 4.75383327 0.8777497 1 P 0 ;0,1,2=159,3=0.000000
L 4.75383327 0.8777497 4.7545998 0.87361634 1 P 0 ;0,1,2=159,3=0.000000
L 4.7545998 0.87361634 4.7569 0.87103356 1 P 0 ;0,1,2=159,3=0.000000
L 4.7569 0.87103356 4.75958346 0.86948287 1 P 0 ;0,1,2=159,3=0.000000
L 4.75958346 0.86948287 4.76916683 0.86948287 1 P 0 ;0,1,2=159,3=0.000000
L 4.75958346 0.86948287 4.75383327 0.8545 1 P 0 ;0,1,2=159,3=0.000000
L 4.7259 0.8545 4.7259 0.8855 1 P 0 ;0,1,2=159,3=0.000000
L 4.7259 0.8855 4.74008376 0.86328327 1 P 0 ;0,1,2=159,3=0.000000
L 4.74008376 0.86328327 4.72091634 0.86328327 1 P 0 ;0,1,2=159,3=0.000000
L 4.69950039 0.8545 4.69681693 0.85501654 1 P 0 ;0,1,2=159,3=0.000000
L 4.69681693 0.85501654 4.6937502 0.85656614 1 P 0 ;0,1,2=159,3=0.000000
L 4.6937502 0.85656614 4.69183327 0.85914892 1 P 0 ;0,1,2=159,3=0.000000
L 4.69183327 0.85914892 4.69106673 0.86276673 1 P 0 ;0,1,2=159,3=0.000000
L 4.69106673 0.86276673 4.69183327 0.86638268 1 P 0 ;0,1,2=159,3=0.000000
L 4.69183327 0.86638268 4.69413346 0.86948287 1 P 0 ;0,1,2=159,3=0.000000
L 4.69413346 0.86948287 4.69758346 0.87103356 1 P 0 ;0,1,2=159,3=0.000000
L 4.69758346 0.87103356 4.70141663 0.87103356 1 P 0 ;0,1,2=159,3=0.000000
L 4.70141663 0.87103356 4.70371683 0.87206663 1 P 0 ;0,1,2=159,3=0.000000
L 4.70371683 0.87206663 4.70563386 0.87464941 1 P 0 ;0,1,2=159,3=0.000000
L 4.70563386 0.87464941 4.7064003 0.87826624 1 P 0 ;0,1,2=159,3=0.000000
L 4.7064003 0.87826624 4.7052499 0.88188307 1 P 0 ;0,1,2=159,3=0.000000
L 4.7052499 0.88188307 4.70256713 0.88446683 1 P 0 ;0,1,2=159,3=0.000000
L 4.70256713 0.88446683 4.69950039 0.8855 1 P 0 ;0,1,2=159,3=0.000000
L 4.69950039 0.8855 4.69643366 0.88446683 1 P 0 ;0,1,2=159,3=0.000000
L 4.69643366 0.88446683 4.6937502 0.88188307 1 P 0 ;0,1,2=159,3=0.000000
L 4.6937502 0.88188307 4.6925998 0.87826624 1 P 0 ;0,1,2=159,3=0.000000
L 4.6925998 0.87826624 4.69336693 0.87464941 1 P 0 ;0,1,2=159,3=0.000000
L 4.69336693 0.87464941 4.69528327 0.87206663 1 P 0 ;0,1,2=159,3=0.000000
L 4.69528327 0.87206663 4.69758346 0.87103356 1 P 0 ;0,1,2=159,3=0.000000
L 4.69758346 0.87103356 4.70141663 0.87103356 1 P 0 ;0,1,2=159,3=0.000000
L 4.70141663 0.87103356 4.70486663 0.86948287 1 P 0 ;0,1,2=159,3=0.000000
L 4.70486663 0.86948287 4.70716683 0.86638268 1 P 0 ;0,1,2=159,3=0.000000
L 4.70716683 0.86638268 4.70793337 0.86276673 1 P 0 ;0,1,2=159,3=0.000000
L 4.70793337 0.86276673 4.70716683 0.85914892 1 P 0 ;0,1,2=159,3=0.000000
L 4.70716683 0.85914892 4.7052499 0.85656614 1 P 0 ;0,1,2=159,3=0.000000
L 4.7052499 0.85656614 4.70218317 0.85501654 1 P 0 ;0,1,2=159,3=0.000000
L 4.70218317 0.85501654 4.69950039 0.8545 1 P 0 ;0,1,2=159,3=0.000000
L 4.67693337 0.86069961 4.67463386 0.85708278 1 P 0 ;0,1,2=159,3=0.000000
L 4.67463386 0.85708278 4.67156713 0.85501654 1 P 0 ;0,1,2=159,3=0.000000
L 4.67156713 0.85501654 4.66811644 0.8545 1 P 0 ;0,1,2=159,3=0.000000
L 4.66811644 0.8545 4.6650497 0.85501654 1 P 0 ;0,1,2=159,3=0.000000
L 4.6650497 0.85501654 4.66198297 0.85759931 1 P 0 ;0,1,2=159,3=0.000000
L 4.66198297 0.85759931 4.66006673 0.86069961 1 P 0 ;0,1,2=159,3=0.000000
L 4.66006673 0.86069961 4.65968346 0.8637999 1 P 0 ;0,1,2=159,3=0.000000
L 4.65968346 0.8637999 4.66045 0.86741575 1 P 0 ;0,1,2=159,3=0.000000
L 4.66045 0.86741575 4.66313346 0.86999951 1 P 0 ;0,1,2=159,3=0.000000
L 4.66313346 0.86999951 4.66581693 0.87103356 1 P 0 ;0,1,2=159,3=0.000000
L 4.66581693 0.87103356 4.66926693 0.87103356 1 P 0 ;0,1,2=159,3=0.000000
L 4.66581693 0.87103356 4.66351673 0.87258317 1 P 0 ;0,1,2=159,3=0.000000
L 4.66351673 0.87258317 4.6615998 0.87516594 1 P 0 ;0,1,2=159,3=0.000000
L 4.6615998 0.87516594 4.66083327 0.87826624 1 P 0 ;0,1,2=159,3=0.000000
L 4.66083327 0.87826624 4.6615998 0.88136654 1 P 0 ;0,1,2=159,3=0.000000
L 4.6615998 0.88136654 4.66351673 0.88394931 1 P 0 ;0,1,2=159,3=0.000000
L 4.66351673 0.88394931 4.66696673 0.8855 1 P 0 ;0,1,2=159,3=0.000000
L 4.66696673 0.8855 4.67041663 0.88498337 1 P 0 ;0,1,2=159,3=0.000000
L 4.67041663 0.88498337 4.67386663 0.88291624 1 P 0 ;0,1,2=159,3=0.000000
L 1.062 3.63 1.062 3.54 1 P 0 
L 1.018 3.63 1.062 3.63 1 P 0 
L 1.062 3.54 1.018 3.54 1 P 0 
L 1.018 3.54 1.018 3.63 1 P 0 
L 0.8245 3.62083317 0.8555 3.62083317 1 P 0 ;0,1,2=160,3=90.000000
L 0.8555 3.62083317 0.8555 3.63041654 1 P 0 ;0,1,2=160,3=90.000000
L 0.8555 3.63041654 0.85394931 3.63348327 1 P 0 ;0,1,2=160,3=90.000000
L 0.85394931 3.63348327 0.85188307 3.6354002 1 P 0 ;0,1,2=160,3=90.000000
L 0.85188307 3.6354002 0.8477497 3.63616673 1 P 0 ;0,1,2=160,3=90.000000
L 0.8477497 3.63616673 0.84361634 3.6354002 1 P 0 ;0,1,2=160,3=90.000000
L 0.84361634 3.6354002 0.84103356 3.6331 1 P 0 ;0,1,2=160,3=90.000000
L 0.84103356 3.6331 0.83948287 3.63041654 1 P 0 ;0,1,2=160,3=90.000000
L 0.83948287 3.63041654 0.83948287 3.62083317 1 P 0 ;0,1,2=160,3=90.000000
L 0.83948287 3.63041654 0.8245 3.63616673 1 P 0 ;0,1,2=160,3=90.000000
L 0.8245 3.6641 0.8555 3.6641 1 P 0 ;0,1,2=160,3=90.000000
L 0.8555 3.6641 0.83328327 3.64991624 1 P 0 ;0,1,2=160,3=90.000000
L 0.83328327 3.64991624 0.83328327 3.66908366 1 P 0 ;0,1,2=160,3=90.000000
L 0.83741575 3.68321644 0.84103356 3.6858999 1 P 0 ;0,1,2=160,3=90.000000
L 0.84103356 3.6858999 0.8430998 3.6882001 1 P 0 ;0,1,2=160,3=90.000000
L 0.8430998 3.6882001 0.84413287 3.69126683 1 P 0 ;0,1,2=160,3=90.000000
L 0.84413287 3.69126683 0.8430998 3.6939503 1 P 0 ;0,1,2=160,3=90.000000
L 0.8430998 3.6939503 0.84103356 3.69586654 1 P 0 ;0,1,2=160,3=90.000000
L 0.84103356 3.69586654 0.83793327 3.6974002 1 P 0 ;0,1,2=160,3=90.000000
L 0.83793327 3.6974002 0.83431644 3.69778346 1 P 0 ;0,1,2=160,3=90.000000
L 0.83431644 3.69778346 0.83121614 3.6974002 1 P 0 ;0,1,2=160,3=90.000000
L 0.83121614 3.6974002 0.82811585 3.69586654 1 P 0 ;0,1,2=160,3=90.000000
L 0.82811585 3.69586654 0.82553307 3.69356634 1 P 0 ;0,1,2=160,3=90.000000
L 0.82553307 3.69356634 0.8245 3.69088356 1 P 0 ;0,1,2=160,3=90.000000
L 0.8245 3.69088356 0.82553307 3.68781683 1 P 0 ;0,1,2=160,3=90.000000
L 0.82553307 3.68781683 0.82863238 3.68513337 1 P 0 ;0,1,2=160,3=90.000000
L 0.82863238 3.68513337 0.83328327 3.6835997 1 P 0 ;0,1,2=160,3=90.000000
L 0.83328327 3.6835997 0.8384498 3.68321644 1 P 0 ;0,1,2=160,3=90.000000
L 0.8384498 3.68321644 0.84516594 3.68398287 1 P 0 ;0,1,2=160,3=90.000000
L 0.84516594 3.68398287 0.84878376 3.68513337 1 P 0 ;0,1,2=160,3=90.000000
L 0.84878376 3.68513337 0.8523997 3.68704961 1 P 0 ;0,1,2=160,3=90.000000
L 0.8523997 3.68704961 0.85498337 3.68973307 1 P 0 ;0,1,2=160,3=90.000000
L 0.85498337 3.68973307 0.8555 3.69241654 1 P 0 ;0,1,2=160,3=90.000000
L 0.8555 3.69241654 0.85446683 3.6951 1 P 0 ;0,1,2=160,3=90.000000
L 0.85446683 3.6951 0.85188307 3.69701703 1 P 0 ;0,1,2=160,3=90.000000
L 0.8555 3.72149961 0.85446683 3.71843287 1 P 0 ;0,1,2=160,3=90.000000
L 0.85446683 3.71843287 0.85188307 3.71613337 1 P 0 ;0,1,2=160,3=90.000000
L 0.85188307 3.71613337 0.84878376 3.7145997 1 P 0 ;0,1,2=160,3=90.000000
L 0.84878376 3.7145997 0.84464941 3.7134499 1 P 0 ;0,1,2=160,3=90.000000
L 0.84464941 3.7134499 0.83999951 3.71306663 1 P 0 ;0,1,2=160,3=90.000000
L 0.83999951 3.71306663 0.83534951 3.7134499 1 P 0 ;0,1,2=160,3=90.000000
L 0.83534951 3.7134499 0.83121614 3.7145997 1 P 0 ;0,1,2=160,3=90.000000
L 0.83121614 3.7145997 0.82811585 3.71613337 1 P 0 ;0,1,2=160,3=90.000000
L 0.82811585 3.71613337 0.82553307 3.71843287 1 P 0 ;0,1,2=160,3=90.000000
L 0.82553307 3.71843287 0.8245 3.72149961 1 P 0 ;0,1,2=160,3=90.000000
L 0.8245 3.72149961 0.82553307 3.72456634 1 P 0 ;0,1,2=160,3=90.000000
L 0.82553307 3.72456634 0.82811585 3.72686654 1 P 0 ;0,1,2=160,3=90.000000
L 0.82811585 3.72686654 0.83121614 3.7284002 1 P 0 ;0,1,2=160,3=90.000000
L 0.83121614 3.7284002 0.83534951 3.72955 1 P 0 ;0,1,2=160,3=90.000000
L 0.83534951 3.72955 0.83999951 3.72993327 1 P 0 ;0,1,2=160,3=90.000000
L 0.83999951 3.72993327 0.84464941 3.72955 1 P 0 ;0,1,2=160,3=90.000000
L 0.84464941 3.72955 0.84878376 3.7284002 1 P 0 ;0,1,2=160,3=90.000000
L 0.84878376 3.7284002 0.85188307 3.72686654 1 P 0 ;0,1,2=160,3=90.000000
L 0.85188307 3.72686654 0.85446683 3.72456634 1 P 0 ;0,1,2=160,3=90.000000
L 0.85446683 3.72456634 0.8555 3.72149961 1 P 0 ;0,1,2=160,3=90.000000
L 4.039 3.261 4.039 3.217 1 P 0 
L 3.949 3.261 4.039 3.261 1 P 0 
L 4.039 3.217 3.949 3.217 1 P 0 
L 3.949 3.217 3.949 3.261 1 P 0 
L 4.04916683 3.1595 4.04916683 3.1905 1 P 0 ;0,1,2=161,3=0.000000
L 4.04916683 3.1905 4.03958346 3.1905 1 P 0 ;0,1,2=161,3=0.000000
L 4.03958346 3.1905 4.03651673 3.18894931 1 P 0 ;0,1,2=161,3=0.000000
L 4.03651673 3.18894931 4.0345998 3.18688307 1 P 0 ;0,1,2=161,3=0.000000
L 4.0345998 3.18688307 4.03383327 3.1827497 1 P 0 ;0,1,2=161,3=0.000000
L 4.03383327 3.1827497 4.0345998 3.17861634 1 P 0 ;0,1,2=161,3=0.000000
L 4.0345998 3.17861634 4.0369 3.17603356 1 P 0 ;0,1,2=161,3=0.000000
L 4.0369 3.17603356 4.03958346 3.17448287 1 P 0 ;0,1,2=161,3=0.000000
L 4.03958346 3.17448287 4.04916683 3.17448287 1 P 0 ;0,1,2=161,3=0.000000
L 4.03958346 3.17448287 4.03383327 3.1595 1 P 0 ;0,1,2=161,3=0.000000
L 4.0059 3.1595 4.0059 3.1905 1 P 0 ;0,1,2=161,3=0.000000
L 4.0059 3.1905 4.02008376 3.16828327 1 P 0 ;0,1,2=161,3=0.000000
L 4.02008376 3.16828327 4.00091634 3.16828327 1 P 0 ;0,1,2=161,3=0.000000
L 3.98793337 3.16414892 3.98563386 3.16156614 1 P 0 ;0,1,2=161,3=0.000000
L 3.98563386 3.16156614 3.98295039 3.16001654 1 P 0 ;0,1,2=161,3=0.000000
L 3.98295039 3.16001654 3.97950039 3.1595 1 P 0 ;0,1,2=161,3=0.000000
L 3.97950039 3.1595 3.9760497 3.16053307 1 P 0 ;0,1,2=161,3=0.000000
L 3.9760497 3.16053307 3.97336693 3.16259931 1 P 0 ;0,1,2=161,3=0.000000
L 3.97336693 3.16259931 3.97145 3.16621614 1 P 0 ;0,1,2=161,3=0.000000
L 3.97145 3.16621614 3.97106673 3.17034951 1 P 0 ;0,1,2=161,3=0.000000
L 3.97106673 3.17034951 3.97183327 3.17448287 1 P 0 ;0,1,2=161,3=0.000000
L 3.97183327 3.17448287 3.9737502 3.17706663 1 P 0 ;0,1,2=161,3=0.000000
L 3.9737502 3.17706663 3.97643366 3.17913287 1 P 0 ;0,1,2=161,3=0.000000
L 3.97643366 3.17913287 3.97911644 3.17964941 1 P 0 ;0,1,2=161,3=0.000000
L 3.97911644 3.17964941 3.9817999 3.17913287 1 P 0 ;0,1,2=161,3=0.000000
L 3.9817999 3.17913287 3.9852499 3.17706663 1 P 0 ;0,1,2=161,3=0.000000
L 3.9852499 3.17706663 3.9841001 3.1905 1 P 0 ;0,1,2=161,3=0.000000
L 3.9841001 3.1905 3.9737502 3.1905 1 P 0 ;0,1,2=161,3=0.000000
L 3.94850039 3.1595 3.94581693 3.16001654 1 P 0 ;0,1,2=161,3=0.000000
L 3.94581693 3.16001654 3.9427502 3.16156614 1 P 0 ;0,1,2=161,3=0.000000
L 3.9427502 3.16156614 3.94083327 3.16414892 1 P 0 ;0,1,2=161,3=0.000000
L 3.94083327 3.16414892 3.94006673 3.16776673 1 P 0 ;0,1,2=161,3=0.000000
L 3.94006673 3.16776673 3.94083327 3.17138268 1 P 0 ;0,1,2=161,3=0.000000
L 3.94083327 3.17138268 3.94313346 3.17448287 1 P 0 ;0,1,2=161,3=0.000000
L 3.94313346 3.17448287 3.94658346 3.17603356 1 P 0 ;0,1,2=161,3=0.000000
L 3.94658346 3.17603356 3.95041663 3.17603356 1 P 0 ;0,1,2=161,3=0.000000
L 3.95041663 3.17603356 3.95271683 3.17706663 1 P 0 ;0,1,2=161,3=0.000000
L 3.95271683 3.17706663 3.95463386 3.17964941 1 P 0 ;0,1,2=161,3=0.000000
L 3.95463386 3.17964941 3.9554003 3.18326624 1 P 0 ;0,1,2=161,3=0.000000
L 3.9554003 3.18326624 3.9542499 3.18688307 1 P 0 ;0,1,2=161,3=0.000000
L 3.9542499 3.18688307 3.95156713 3.18946683 1 P 0 ;0,1,2=161,3=0.000000
L 3.95156713 3.18946683 3.94850039 3.1905 1 P 0 ;0,1,2=161,3=0.000000
L 3.94850039 3.1905 3.94543366 3.18946683 1 P 0 ;0,1,2=161,3=0.000000
L 3.94543366 3.18946683 3.9427502 3.18688307 1 P 0 ;0,1,2=161,3=0.000000
L 3.9427502 3.18688307 3.9415998 3.18326624 1 P 0 ;0,1,2=161,3=0.000000
L 3.9415998 3.18326624 3.94236693 3.17964941 1 P 0 ;0,1,2=161,3=0.000000
L 3.94236693 3.17964941 3.94428327 3.17706663 1 P 0 ;0,1,2=161,3=0.000000
L 3.94428327 3.17706663 3.94658346 3.17603356 1 P 0 ;0,1,2=161,3=0.000000
L 3.94658346 3.17603356 3.95041663 3.17603356 1 P 0 ;0,1,2=161,3=0.000000
L 3.95041663 3.17603356 3.95386663 3.17448287 1 P 0 ;0,1,2=161,3=0.000000
L 3.95386663 3.17448287 3.95616683 3.17138268 1 P 0 ;0,1,2=161,3=0.000000
L 3.95616683 3.17138268 3.95693337 3.16776673 1 P 0 ;0,1,2=161,3=0.000000
L 3.95693337 3.16776673 3.95616683 3.16414892 1 P 0 ;0,1,2=161,3=0.000000
L 3.95616683 3.16414892 3.9542499 3.16156614 1 P 0 ;0,1,2=161,3=0.000000
L 3.9542499 3.16156614 3.95118317 3.16001654 1 P 0 ;0,1,2=161,3=0.000000
L 3.95118317 3.16001654 3.94850039 3.1595 1 P 0 ;0,1,2=161,3=0.000000
L 3.905 3.78 3.905 3.736 1 P 0 
L 3.905 3.736 3.815 3.736 1 P 0 
L 3.815 3.736 3.815 3.78 1 P 0 
L 3.815 3.78 3.905 3.78 1 P 0 
L 4.01916683 3.7395 4.01916683 3.7705 1 P 0 ;0,1,2=162,3=0.000000
L 4.01916683 3.7705 4.00958346 3.7705 1 P 0 ;0,1,2=162,3=0.000000
L 4.00958346 3.7705 4.00651673 3.76894931 1 P 0 ;0,1,2=162,3=0.000000
L 4.00651673 3.76894931 4.0045998 3.76688307 1 P 0 ;0,1,2=162,3=0.000000
L 4.0045998 3.76688307 4.00383327 3.7627497 1 P 0 ;0,1,2=162,3=0.000000
L 4.00383327 3.7627497 4.0045998 3.75861634 1 P 0 ;0,1,2=162,3=0.000000
L 4.0045998 3.75861634 4.0069 3.75603356 1 P 0 ;0,1,2=162,3=0.000000
L 4.0069 3.75603356 4.00958346 3.75448287 1 P 0 ;0,1,2=162,3=0.000000
L 4.00958346 3.75448287 4.01916683 3.75448287 1 P 0 ;0,1,2=162,3=0.000000
L 4.00958346 3.75448287 4.00383327 3.7395 1 P 0 ;0,1,2=162,3=0.000000
L 3.9759 3.7395 3.9759 3.7705 1 P 0 ;0,1,2=162,3=0.000000
L 3.9759 3.7705 3.99008376 3.74828327 1 P 0 ;0,1,2=162,3=0.000000
L 3.99008376 3.74828327 3.97091634 3.74828327 1 P 0 ;0,1,2=162,3=0.000000
L 3.95793337 3.74414892 3.95563386 3.74156614 1 P 0 ;0,1,2=162,3=0.000000
L 3.95563386 3.74156614 3.95295039 3.74001654 1 P 0 ;0,1,2=162,3=0.000000
L 3.95295039 3.74001654 3.94950039 3.7395 1 P 0 ;0,1,2=162,3=0.000000
L 3.94950039 3.7395 3.9460497 3.74053307 1 P 0 ;0,1,2=162,3=0.000000
L 3.9460497 3.74053307 3.94336693 3.74259931 1 P 0 ;0,1,2=162,3=0.000000
L 3.94336693 3.74259931 3.94145 3.74621614 1 P 0 ;0,1,2=162,3=0.000000
L 3.94145 3.74621614 3.94106673 3.75034951 1 P 0 ;0,1,2=162,3=0.000000
L 3.94106673 3.75034951 3.94183327 3.75448287 1 P 0 ;0,1,2=162,3=0.000000
L 3.94183327 3.75448287 3.9437502 3.75706663 1 P 0 ;0,1,2=162,3=0.000000
L 3.9437502 3.75706663 3.94643366 3.75913287 1 P 0 ;0,1,2=162,3=0.000000
L 3.94643366 3.75913287 3.94911644 3.75964941 1 P 0 ;0,1,2=162,3=0.000000
L 3.94911644 3.75964941 3.9517999 3.75913287 1 P 0 ;0,1,2=162,3=0.000000
L 3.9517999 3.75913287 3.9552499 3.75706663 1 P 0 ;0,1,2=162,3=0.000000
L 3.9552499 3.75706663 3.9541001 3.7705 1 P 0 ;0,1,2=162,3=0.000000
L 3.9541001 3.7705 3.9437502 3.7705 1 P 0 ;0,1,2=162,3=0.000000
L 3.91850039 3.7395 3.91850039 3.7705 1 P 0 ;0,1,2=162,3=0.000000
L 3.91850039 3.7705 3.9231001 3.7643003 1 P 0 ;0,1,2=162,3=0.000000
L 3.9231001 3.7395 3.91390069 3.7395 1 P 0 ;0,1,2=162,3=0.000000
L 0.68 3.222 0.77 3.222 1 P 0 
L 0.68 3.178 0.68 3.222 1 P 0 
L 0.77 3.178 0.68 3.178 1 P 0 
L 0.77 3.222 0.77 3.178 1 P 0 
L 0.92916683 3.1695 0.92916683 3.2005 1 P 0 ;0,1,2=163,3=0.000000
L 0.92916683 3.2005 0.91958346 3.2005 1 P 0 ;0,1,2=163,3=0.000000
L 0.91958346 3.2005 0.91651673 3.19894931 1 P 0 ;0,1,2=163,3=0.000000
L 0.91651673 3.19894931 0.9145998 3.19688307 1 P 0 ;0,1,2=163,3=0.000000
L 0.9145998 3.19688307 0.91383327 3.1927497 1 P 0 ;0,1,2=163,3=0.000000
L 0.91383327 3.1927497 0.9145998 3.18861634 1 P 0 ;0,1,2=163,3=0.000000
L 0.9145998 3.18861634 0.9169 3.18603356 1 P 0 ;0,1,2=163,3=0.000000
L 0.9169 3.18603356 0.91958346 3.18448287 1 P 0 ;0,1,2=163,3=0.000000
L 0.91958346 3.18448287 0.92916683 3.18448287 1 P 0 ;0,1,2=163,3=0.000000
L 0.91958346 3.18448287 0.91383327 3.1695 1 P 0 ;0,1,2=163,3=0.000000
L 0.8859 3.1695 0.8859 3.2005 1 P 0 ;0,1,2=163,3=0.000000
L 0.8859 3.2005 0.90008376 3.17828327 1 P 0 ;0,1,2=163,3=0.000000
L 0.90008376 3.17828327 0.88091634 3.17828327 1 P 0 ;0,1,2=163,3=0.000000
L 0.86026693 3.1695 0.85950039 3.17621614 1 P 0 ;0,1,2=163,3=0.000000
L 0.85950039 3.17621614 0.8583499 3.18189921 1 P 0 ;0,1,2=163,3=0.000000
L 0.8583499 3.18189921 0.85681693 3.18706663 1 P 0 ;0,1,2=163,3=0.000000
L 0.85681693 3.18706663 0.8549 3.1927497 1 P 0 ;0,1,2=163,3=0.000000
L 0.8549 3.1927497 0.85183327 3.2005 1 P 0 ;0,1,2=163,3=0.000000
L 0.85183327 3.2005 0.86716683 3.2005 1 P 0 ;0,1,2=163,3=0.000000
L 0.83501713 3.17311585 0.83233366 3.17053307 1 P 0 ;0,1,2=163,3=0.000000
L 0.83233366 3.17053307 0.82926693 3.1695 1 P 0 ;0,1,2=163,3=0.000000
L 0.82926693 3.1695 0.8262002 3.17053307 1 P 0 ;0,1,2=163,3=0.000000
L 0.8262002 3.17053307 0.82351673 3.17363238 1 P 0 ;0,1,2=163,3=0.000000
L 0.82351673 3.17363238 0.8215998 3.17828327 1 P 0 ;0,1,2=163,3=0.000000
L 0.8215998 3.17828327 0.82083327 3.18293327 1 P 0 ;0,1,2=163,3=0.000000
L 0.82083327 3.18293327 0.82083327 3.18861634 1 P 0 ;0,1,2=163,3=0.000000
L 0.82083327 3.18861634 0.8215998 3.19326624 1 P 0 ;0,1,2=163,3=0.000000
L 0.8215998 3.19326624 0.82351673 3.1973997 1 P 0 ;0,1,2=163,3=0.000000
L 0.82351673 3.1973997 0.82581693 3.19946683 1 P 0 ;0,1,2=163,3=0.000000
L 0.82581693 3.19946683 0.82850039 3.2005 1 P 0 ;0,1,2=163,3=0.000000
L 0.82850039 3.2005 0.83156713 3.19946683 1 P 0 ;0,1,2=163,3=0.000000
L 0.83156713 3.19946683 0.83386663 3.1973997 1 P 0 ;0,1,2=163,3=0.000000
L 0.83386663 3.1973997 0.8354003 3.1943003 1 P 0 ;0,1,2=163,3=0.000000
L 0.8354003 3.1943003 0.83616683 3.19016594 1 P 0 ;0,1,2=163,3=0.000000
L 0.83616683 3.19016594 0.8354003 3.1865501 1 P 0 ;0,1,2=163,3=0.000000
L 0.8354003 3.1865501 0.83348337 3.18293327 1 P 0 ;0,1,2=163,3=0.000000
L 0.83348337 3.18293327 0.83118317 3.18086604 1 P 0 ;0,1,2=163,3=0.000000
L 0.83118317 3.18086604 0.82850039 3.18034951 1 P 0 ;0,1,2=163,3=0.000000
L 0.82850039 3.18034951 0.82543366 3.18138268 1 P 0 ;0,1,2=163,3=0.000000
L 0.82543366 3.18138268 0.82313346 3.18396634 1 P 0 ;0,1,2=163,3=0.000000
L 0.82313346 3.18396634 0.82083327 3.18861634 1 P 0 ;0,1,2=163,3=0.000000
L 0.68 3.223 0.68 3.267 1 P 0 
L 0.77 3.223 0.68 3.223 1 P 0 
L 0.77 3.267 0.77 3.223 1 P 0 
L 0.68 3.267 0.77 3.267 1 P 0 
L 0.92416683 3.2145 0.92416683 3.2455 1 P 0 ;0,1,2=164,3=0.000000
L 0.92416683 3.2455 0.91458346 3.2455 1 P 0 ;0,1,2=164,3=0.000000
L 0.91458346 3.2455 0.91151673 3.24394931 1 P 0 ;0,1,2=164,3=0.000000
L 0.91151673 3.24394931 0.9095998 3.24188307 1 P 0 ;0,1,2=164,3=0.000000
L 0.9095998 3.24188307 0.90883327 3.2377497 1 P 0 ;0,1,2=164,3=0.000000
L 0.90883327 3.2377497 0.9095998 3.23361634 1 P 0 ;0,1,2=164,3=0.000000
L 0.9095998 3.23361634 0.9119 3.23103356 1 P 0 ;0,1,2=164,3=0.000000
L 0.9119 3.23103356 0.91458346 3.22948287 1 P 0 ;0,1,2=164,3=0.000000
L 0.91458346 3.22948287 0.92416683 3.22948287 1 P 0 ;0,1,2=164,3=0.000000
L 0.91458346 3.22948287 0.90883327 3.2145 1 P 0 ;0,1,2=164,3=0.000000
L 0.8809 3.2145 0.8809 3.2455 1 P 0 ;0,1,2=164,3=0.000000
L 0.8809 3.2455 0.89508376 3.22328327 1 P 0 ;0,1,2=164,3=0.000000
L 0.89508376 3.22328327 0.87591634 3.22328327 1 P 0 ;0,1,2=164,3=0.000000
L 0.85526693 3.2145 0.85450039 3.22121614 1 P 0 ;0,1,2=164,3=0.000000
L 0.85450039 3.22121614 0.8533499 3.22689921 1 P 0 ;0,1,2=164,3=0.000000
L 0.8533499 3.22689921 0.85181693 3.23206663 1 P 0 ;0,1,2=164,3=0.000000
L 0.85181693 3.23206663 0.8499 3.2377497 1 P 0 ;0,1,2=164,3=0.000000
L 0.8499 3.2377497 0.84683327 3.2455 1 P 0 ;0,1,2=164,3=0.000000
L 0.84683327 3.2455 0.86216683 3.2455 1 P 0 ;0,1,2=164,3=0.000000
L 0.82350039 3.2145 0.82081693 3.21501654 1 P 0 ;0,1,2=164,3=0.000000
L 0.82081693 3.21501654 0.8177502 3.21656614 1 P 0 ;0,1,2=164,3=0.000000
L 0.8177502 3.21656614 0.81583327 3.21914892 1 P 0 ;0,1,2=164,3=0.000000
L 0.81583327 3.21914892 0.81506673 3.22276673 1 P 0 ;0,1,2=164,3=0.000000
L 0.81506673 3.22276673 0.81583327 3.22638268 1 P 0 ;0,1,2=164,3=0.000000
L 0.81583327 3.22638268 0.81813346 3.22948287 1 P 0 ;0,1,2=164,3=0.000000
L 0.81813346 3.22948287 0.82158346 3.23103356 1 P 0 ;0,1,2=164,3=0.000000
L 0.82158346 3.23103356 0.82541663 3.23103356 1 P 0 ;0,1,2=164,3=0.000000
L 0.82541663 3.23103356 0.82771683 3.23206663 1 P 0 ;0,1,2=164,3=0.000000
L 0.82771683 3.23206663 0.82963386 3.23464941 1 P 0 ;0,1,2=164,3=0.000000
L 0.82963386 3.23464941 0.8304003 3.23826624 1 P 0 ;0,1,2=164,3=0.000000
L 0.8304003 3.23826624 0.8292499 3.24188307 1 P 0 ;0,1,2=164,3=0.000000
L 0.8292499 3.24188307 0.82656713 3.24446683 1 P 0 ;0,1,2=164,3=0.000000
L 0.82656713 3.24446683 0.82350039 3.2455 1 P 0 ;0,1,2=164,3=0.000000
L 0.82350039 3.2455 0.82043366 3.24446683 1 P 0 ;0,1,2=164,3=0.000000
L 0.82043366 3.24446683 0.8177502 3.24188307 1 P 0 ;0,1,2=164,3=0.000000
L 0.8177502 3.24188307 0.8165998 3.23826624 1 P 0 ;0,1,2=164,3=0.000000
L 0.8165998 3.23826624 0.81736693 3.23464941 1 P 0 ;0,1,2=164,3=0.000000
L 0.81736693 3.23464941 0.81928327 3.23206663 1 P 0 ;0,1,2=164,3=0.000000
L 0.81928327 3.23206663 0.82158346 3.23103356 1 P 0 ;0,1,2=164,3=0.000000
L 0.82158346 3.23103356 0.82541663 3.23103356 1 P 0 ;0,1,2=164,3=0.000000
L 0.82541663 3.23103356 0.82886663 3.22948287 1 P 0 ;0,1,2=164,3=0.000000
L 0.82886663 3.22948287 0.83116683 3.22638268 1 P 0 ;0,1,2=164,3=0.000000
L 0.83116683 3.22638268 0.83193337 3.22276673 1 P 0 ;0,1,2=164,3=0.000000
L 0.83193337 3.22276673 0.83116683 3.21914892 1 P 0 ;0,1,2=164,3=0.000000
L 0.83116683 3.21914892 0.8292499 3.21656614 1 P 0 ;0,1,2=164,3=0.000000
L 0.8292499 3.21656614 0.82618317 3.21501654 1 P 0 ;0,1,2=164,3=0.000000
L 0.82618317 3.21501654 0.82350039 3.2145 1 P 0 ;0,1,2=164,3=0.000000
L 0.935 3.477 0.935 3.433 1 P 0 
L 0.845 3.477 0.935 3.477 1 P 0 
L 0.935 3.433 0.845 3.433 1 P 0 
L 0.845 3.433 0.845 3.477 1 P 0 
L 0.98416683 3.3045 0.98416683 3.3355 1 P 0 ;0,1,2=165,3=0.000000
L 0.98416683 3.3355 0.97458346 3.3355 1 P 0 ;0,1,2=165,3=0.000000
L 0.97458346 3.3355 0.97151673 3.33394931 1 P 0 ;0,1,2=165,3=0.000000
L 0.97151673 3.33394931 0.9695998 3.33188307 1 P 0 ;0,1,2=165,3=0.000000
L 0.9695998 3.33188307 0.96883327 3.3277497 1 P 0 ;0,1,2=165,3=0.000000
L 0.96883327 3.3277497 0.9695998 3.32361634 1 P 0 ;0,1,2=165,3=0.000000
L 0.9695998 3.32361634 0.9719 3.32103356 1 P 0 ;0,1,2=165,3=0.000000
L 0.9719 3.32103356 0.97458346 3.31948287 1 P 0 ;0,1,2=165,3=0.000000
L 0.97458346 3.31948287 0.98416683 3.31948287 1 P 0 ;0,1,2=165,3=0.000000
L 0.97458346 3.31948287 0.96883327 3.3045 1 P 0 ;0,1,2=165,3=0.000000
L 0.9409 3.3045 0.9409 3.3355 1 P 0 ;0,1,2=165,3=0.000000
L 0.9409 3.3355 0.95508376 3.31328327 1 P 0 ;0,1,2=165,3=0.000000
L 0.95508376 3.31328327 0.93591634 3.31328327 1 P 0 ;0,1,2=165,3=0.000000
L 0.92178356 3.31741575 0.9191001 3.32103356 1 P 0 ;0,1,2=165,3=0.000000
L 0.9191001 3.32103356 0.9167999 3.3230998 1 P 0 ;0,1,2=165,3=0.000000
L 0.9167999 3.3230998 0.91373317 3.32413287 1 P 0 ;0,1,2=165,3=0.000000
L 0.91373317 3.32413287 0.9110497 3.3230998 1 P 0 ;0,1,2=165,3=0.000000
L 0.9110497 3.3230998 0.90913346 3.32103356 1 P 0 ;0,1,2=165,3=0.000000
L 0.90913346 3.32103356 0.9075998 3.31793327 1 P 0 ;0,1,2=165,3=0.000000
L 0.9075998 3.31793327 0.90721654 3.31431644 1 P 0 ;0,1,2=165,3=0.000000
L 0.90721654 3.31431644 0.9075998 3.31121614 1 P 0 ;0,1,2=165,3=0.000000
L 0.9075998 3.31121614 0.90913346 3.30811585 1 P 0 ;0,1,2=165,3=0.000000
L 0.90913346 3.30811585 0.91143366 3.30553307 1 P 0 ;0,1,2=165,3=0.000000
L 0.91143366 3.30553307 0.91411644 3.3045 1 P 0 ;0,1,2=165,3=0.000000
L 0.91411644 3.3045 0.91718317 3.30553307 1 P 0 ;0,1,2=165,3=0.000000
L 0.91718317 3.30553307 0.91986663 3.30863238 1 P 0 ;0,1,2=165,3=0.000000
L 0.91986663 3.30863238 0.9214003 3.31328327 1 P 0 ;0,1,2=165,3=0.000000
L 0.9214003 3.31328327 0.92178356 3.3184498 1 P 0 ;0,1,2=165,3=0.000000
L 0.92178356 3.3184498 0.92101713 3.32516594 1 P 0 ;0,1,2=165,3=0.000000
L 0.92101713 3.32516594 0.91986663 3.32878376 1 P 0 ;0,1,2=165,3=0.000000
L 0.91986663 3.32878376 0.91795039 3.3323997 1 P 0 ;0,1,2=165,3=0.000000
L 0.91795039 3.3323997 0.91526693 3.33498337 1 P 0 ;0,1,2=165,3=0.000000
L 0.91526693 3.33498337 0.91258346 3.3355 1 P 0 ;0,1,2=165,3=0.000000
L 0.91258346 3.3355 0.9099 3.33446683 1 P 0 ;0,1,2=165,3=0.000000
L 0.9099 3.33446683 0.90798297 3.33188307 1 P 0 ;0,1,2=165,3=0.000000
L 0.89078356 3.31741575 0.8881001 3.32103356 1 P 0 ;0,1,2=165,3=0.000000
L 0.8881001 3.32103356 0.8857999 3.3230998 1 P 0 ;0,1,2=165,3=0.000000
L 0.8857999 3.3230998 0.88273317 3.32413287 1 P 0 ;0,1,2=165,3=0.000000
L 0.88273317 3.32413287 0.8800497 3.3230998 1 P 0 ;0,1,2=165,3=0.000000
L 0.8800497 3.3230998 0.87813346 3.32103356 1 P 0 ;0,1,2=165,3=0.000000
L 0.87813346 3.32103356 0.8765998 3.31793327 1 P 0 ;0,1,2=165,3=0.000000
L 0.8765998 3.31793327 0.87621654 3.31431644 1 P 0 ;0,1,2=165,3=0.000000
L 0.87621654 3.31431644 0.8765998 3.31121614 1 P 0 ;0,1,2=165,3=0.000000
L 0.8765998 3.31121614 0.87813346 3.30811585 1 P 0 ;0,1,2=165,3=0.000000
L 0.87813346 3.30811585 0.88043366 3.30553307 1 P 0 ;0,1,2=165,3=0.000000
L 0.88043366 3.30553307 0.88311644 3.3045 1 P 0 ;0,1,2=165,3=0.000000
L 0.88311644 3.3045 0.88618317 3.30553307 1 P 0 ;0,1,2=165,3=0.000000
L 0.88618317 3.30553307 0.88886663 3.30863238 1 P 0 ;0,1,2=165,3=0.000000
L 0.88886663 3.30863238 0.8904003 3.31328327 1 P 0 ;0,1,2=165,3=0.000000
L 0.8904003 3.31328327 0.89078356 3.3184498 1 P 0 ;0,1,2=165,3=0.000000
L 0.89078356 3.3184498 0.89001713 3.32516594 1 P 0 ;0,1,2=165,3=0.000000
L 0.89001713 3.32516594 0.88886663 3.32878376 1 P 0 ;0,1,2=165,3=0.000000
L 0.88886663 3.32878376 0.88695039 3.3323997 1 P 0 ;0,1,2=165,3=0.000000
L 0.88695039 3.3323997 0.88426693 3.33498337 1 P 0 ;0,1,2=165,3=0.000000
L 0.88426693 3.33498337 0.88158346 3.3355 1 P 0 ;0,1,2=165,3=0.000000
L 0.88158346 3.3355 0.8789 3.33446683 1 P 0 ;0,1,2=165,3=0.000000
L 0.8789 3.33446683 0.87698297 3.33188307 1 P 0 ;0,1,2=165,3=0.000000
L 1.907 3.005 1.907 2.915 1 P 0 
L 1.863 2.915 1.863 3.005 1 P 0 
L 1.863 3.005 1.907 3.005 1 P 0 
L 1.907 2.915 1.863 2.915 1 P 0 
L 1.9195 2.89083317 1.9505 2.89083317 1 P 0 ;0,1,2=166,3=90.000000
L 1.9505 2.89083317 1.9505 2.90041654 1 P 0 ;0,1,2=166,3=90.000000
L 1.9505 2.90041654 1.94894931 2.90348327 1 P 0 ;0,1,2=166,3=90.000000
L 1.94894931 2.90348327 1.94688307 2.9054002 1 P 0 ;0,1,2=166,3=90.000000
L 1.94688307 2.9054002 1.9427497 2.90616673 1 P 0 ;0,1,2=166,3=90.000000
L 1.9427497 2.90616673 1.93861634 2.9054002 1 P 0 ;0,1,2=166,3=90.000000
L 1.93861634 2.9054002 1.93603356 2.9031 1 P 0 ;0,1,2=166,3=90.000000
L 1.93603356 2.9031 1.93448287 2.90041654 1 P 0 ;0,1,2=166,3=90.000000
L 1.93448287 2.90041654 1.93448287 2.89083317 1 P 0 ;0,1,2=166,3=90.000000
L 1.93448287 2.90041654 1.9195 2.90616673 1 P 0 ;0,1,2=166,3=90.000000
L 1.9195 2.9341 1.9505 2.9341 1 P 0 ;0,1,2=166,3=90.000000
L 1.9505 2.9341 1.92828327 2.91991624 1 P 0 ;0,1,2=166,3=90.000000
L 1.92828327 2.91991624 1.92828327 2.93908366 1 P 0 ;0,1,2=166,3=90.000000
L 1.9195 2.96049961 1.92001654 2.96318307 1 P 0 ;0,1,2=166,3=90.000000
L 1.92001654 2.96318307 1.92156614 2.9662498 1 P 0 ;0,1,2=166,3=90.000000
L 1.92156614 2.9662498 1.92414892 2.96816673 1 P 0 ;0,1,2=166,3=90.000000
L 1.92414892 2.96816673 1.92776673 2.96893327 1 P 0 ;0,1,2=166,3=90.000000
L 1.92776673 2.96893327 1.93138268 2.96816673 1 P 0 ;0,1,2=166,3=90.000000
L 1.93138268 2.96816673 1.93448287 2.96586654 1 P 0 ;0,1,2=166,3=90.000000
L 1.93448287 2.96586654 1.93603356 2.96241654 1 P 0 ;0,1,2=166,3=90.000000
L 1.93603356 2.96241654 1.93603356 2.95858337 1 P 0 ;0,1,2=166,3=90.000000
L 1.93603356 2.95858337 1.93706663 2.95628317 1 P 0 ;0,1,2=166,3=90.000000
L 1.93706663 2.95628317 1.93964941 2.95436614 1 P 0 ;0,1,2=166,3=90.000000
L 1.93964941 2.95436614 1.94326624 2.9535997 1 P 0 ;0,1,2=166,3=90.000000
L 1.94326624 2.9535997 1.94688307 2.9547501 1 P 0 ;0,1,2=166,3=90.000000
L 1.94688307 2.9547501 1.94946683 2.95743287 1 P 0 ;0,1,2=166,3=90.000000
L 1.94946683 2.95743287 1.9505 2.96049961 1 P 0 ;0,1,2=166,3=90.000000
L 1.9505 2.96049961 1.94946683 2.96356634 1 P 0 ;0,1,2=166,3=90.000000
L 1.94946683 2.96356634 1.94688307 2.9662498 1 P 0 ;0,1,2=166,3=90.000000
L 1.94688307 2.9662498 1.94326624 2.9674002 1 P 0 ;0,1,2=166,3=90.000000
L 1.94326624 2.9674002 1.93964941 2.96663307 1 P 0 ;0,1,2=166,3=90.000000
L 1.93964941 2.96663307 1.93706663 2.96471673 1 P 0 ;0,1,2=166,3=90.000000
L 1.93706663 2.96471673 1.93603356 2.96241654 1 P 0 ;0,1,2=166,3=90.000000
L 1.93603356 2.96241654 1.93603356 2.95858337 1 P 0 ;0,1,2=166,3=90.000000
L 1.93603356 2.95858337 1.93448287 2.95513337 1 P 0 ;0,1,2=166,3=90.000000
L 1.93448287 2.95513337 1.93138268 2.95283317 1 P 0 ;0,1,2=166,3=90.000000
L 1.93138268 2.95283317 1.92776673 2.95206663 1 P 0 ;0,1,2=166,3=90.000000
L 1.92776673 2.95206663 1.92414892 2.95283317 1 P 0 ;0,1,2=166,3=90.000000
L 1.92414892 2.95283317 1.92156614 2.9547501 1 P 0 ;0,1,2=166,3=90.000000
L 1.92156614 2.9547501 1.92001654 2.95781683 1 P 0 ;0,1,2=166,3=90.000000
L 1.92001654 2.95781683 1.9195 2.96049961 1 P 0 ;0,1,2=166,3=90.000000
L 1.9195 2.99149961 1.92001654 2.99418307 1 P 0 ;0,1,2=166,3=90.000000
L 1.92001654 2.99418307 1.92156614 2.9972498 1 P 0 ;0,1,2=166,3=90.000000
L 1.92156614 2.9972498 1.92414892 2.99916673 1 P 0 ;0,1,2=166,3=90.000000
L 1.92414892 2.99916673 1.92776673 2.99993327 1 P 0 ;0,1,2=166,3=90.000000
L 1.92776673 2.99993327 1.93138268 2.99916673 1 P 0 ;0,1,2=166,3=90.000000
L 1.93138268 2.99916673 1.93448287 2.99686654 1 P 0 ;0,1,2=166,3=90.000000
L 1.93448287 2.99686654 1.93603356 2.99341654 1 P 0 ;0,1,2=166,3=90.000000
L 1.93603356 2.99341654 1.93603356 2.98958337 1 P 0 ;0,1,2=166,3=90.000000
L 1.93603356 2.98958337 1.93706663 2.98728317 1 P 0 ;0,1,2=166,3=90.000000
L 1.93706663 2.98728317 1.93964941 2.98536614 1 P 0 ;0,1,2=166,3=90.000000
L 1.93964941 2.98536614 1.94326624 2.9845997 1 P 0 ;0,1,2=166,3=90.000000
L 1.94326624 2.9845997 1.94688307 2.9857501 1 P 0 ;0,1,2=166,3=90.000000
L 1.94688307 2.9857501 1.94946683 2.98843287 1 P 0 ;0,1,2=166,3=90.000000
L 1.94946683 2.98843287 1.9505 2.99149961 1 P 0 ;0,1,2=166,3=90.000000
L 1.9505 2.99149961 1.94946683 2.99456634 1 P 0 ;0,1,2=166,3=90.000000
L 1.94946683 2.99456634 1.94688307 2.9972498 1 P 0 ;0,1,2=166,3=90.000000
L 1.94688307 2.9972498 1.94326624 2.9984002 1 P 0 ;0,1,2=166,3=90.000000
L 1.94326624 2.9984002 1.93964941 2.99763307 1 P 0 ;0,1,2=166,3=90.000000
L 1.93964941 2.99763307 1.93706663 2.99571673 1 P 0 ;0,1,2=166,3=90.000000
L 1.93706663 2.99571673 1.93603356 2.99341654 1 P 0 ;0,1,2=166,3=90.000000
L 1.93603356 2.99341654 1.93603356 2.98958337 1 P 0 ;0,1,2=166,3=90.000000
L 1.93603356 2.98958337 1.93448287 2.98613337 1 P 0 ;0,1,2=166,3=90.000000
L 1.93448287 2.98613337 1.93138268 2.98383317 1 P 0 ;0,1,2=166,3=90.000000
L 1.93138268 2.98383317 1.92776673 2.98306663 1 P 0 ;0,1,2=166,3=90.000000
L 1.92776673 2.98306663 1.92414892 2.98383317 1 P 0 ;0,1,2=166,3=90.000000
L 1.92414892 2.98383317 1.92156614 2.9857501 1 P 0 ;0,1,2=166,3=90.000000
L 1.92156614 2.9857501 1.92001654 2.98881683 1 P 0 ;0,1,2=166,3=90.000000
L 1.92001654 2.98881683 1.9195 2.99149961 1 P 0 ;0,1,2=166,3=90.000000
L 2.17 3.478 2.08 3.478 1 P 0 
L 2.08 3.478 2.08 3.522 1 P 0 
L 2.08 3.522 2.17 3.522 1 P 0 
L 2.17 3.522 2.17 3.478 1 P 0 
L 2.18416683 3.6595 2.18416683 3.6905 1 P 0 ;0,1,2=167,3=0.000000
L 2.18416683 3.6905 2.17458346 3.6905 1 P 0 ;0,1,2=167,3=0.000000
L 2.17458346 3.6905 2.17151673 3.68894931 1 P 0 ;0,1,2=167,3=0.000000
L 2.17151673 3.68894931 2.1695998 3.68688307 1 P 0 ;0,1,2=167,3=0.000000
L 2.1695998 3.68688307 2.16883327 3.6827497 1 P 0 ;0,1,2=167,3=0.000000
L 2.16883327 3.6827497 2.1695998 3.67861634 1 P 0 ;0,1,2=167,3=0.000000
L 2.1695998 3.67861634 2.1719 3.67603356 1 P 0 ;0,1,2=167,3=0.000000
L 2.1719 3.67603356 2.17458346 3.67448287 1 P 0 ;0,1,2=167,3=0.000000
L 2.17458346 3.67448287 2.18416683 3.67448287 1 P 0 ;0,1,2=167,3=0.000000
L 2.17458346 3.67448287 2.16883327 3.6595 1 P 0 ;0,1,2=167,3=0.000000
L 2.1409 3.6595 2.1409 3.6905 1 P 0 ;0,1,2=167,3=0.000000
L 2.1409 3.6905 2.15508376 3.66828327 1 P 0 ;0,1,2=167,3=0.000000
L 2.15508376 3.66828327 2.13591634 3.66828327 1 P 0 ;0,1,2=167,3=0.000000
L 2.1099 3.6595 2.1099 3.6905 1 P 0 ;0,1,2=167,3=0.000000
L 2.1099 3.6905 2.12408376 3.66828327 1 P 0 ;0,1,2=167,3=0.000000
L 2.12408376 3.66828327 2.10491634 3.66828327 1 P 0 ;0,1,2=167,3=0.000000
L 2.08426693 3.6595 2.08350039 3.66621614 1 P 0 ;0,1,2=167,3=0.000000
L 2.08350039 3.66621614 2.0823499 3.67189921 1 P 0 ;0,1,2=167,3=0.000000
L 2.0823499 3.67189921 2.08081693 3.67706663 1 P 0 ;0,1,2=167,3=0.000000
L 2.08081693 3.67706663 2.0789 3.6827497 1 P 0 ;0,1,2=167,3=0.000000
L 2.0789 3.6827497 2.07583327 3.6905 1 P 0 ;0,1,2=167,3=0.000000
L 2.07583327 3.6905 2.09116683 3.6905 1 P 0 ;0,1,2=167,3=0.000000
L 2.08 3.572 2.17 3.572 1 P 0 
L 2.17 3.528 2.08 3.528 1 P 0 
L 2.08 3.528 2.08 3.572 1 P 0 
L 2.17 3.572 2.17 3.528 1 P 0 
L 2.18416683 3.6995 2.18416683 3.7305 1 P 0 ;0,1,2=168,3=0.000000
L 2.18416683 3.7305 2.17458346 3.7305 1 P 0 ;0,1,2=168,3=0.000000
L 2.17458346 3.7305 2.17151673 3.72894931 1 P 0 ;0,1,2=168,3=0.000000
L 2.17151673 3.72894931 2.1695998 3.72688307 1 P 0 ;0,1,2=168,3=0.000000
L 2.1695998 3.72688307 2.16883327 3.7227497 1 P 0 ;0,1,2=168,3=0.000000
L 2.16883327 3.7227497 2.1695998 3.71861634 1 P 0 ;0,1,2=168,3=0.000000
L 2.1695998 3.71861634 2.1719 3.71603356 1 P 0 ;0,1,2=168,3=0.000000
L 2.1719 3.71603356 2.17458346 3.71448287 1 P 0 ;0,1,2=168,3=0.000000
L 2.17458346 3.71448287 2.18416683 3.71448287 1 P 0 ;0,1,2=168,3=0.000000
L 2.17458346 3.71448287 2.16883327 3.6995 1 P 0 ;0,1,2=168,3=0.000000
L 2.1409 3.6995 2.1409 3.7305 1 P 0 ;0,1,2=168,3=0.000000
L 2.1409 3.7305 2.15508376 3.70828327 1 P 0 ;0,1,2=168,3=0.000000
L 2.15508376 3.70828327 2.13591634 3.70828327 1 P 0 ;0,1,2=168,3=0.000000
L 2.1099 3.6995 2.1099 3.7305 1 P 0 ;0,1,2=168,3=0.000000
L 2.1099 3.7305 2.12408376 3.70828327 1 P 0 ;0,1,2=168,3=0.000000
L 2.12408376 3.70828327 2.10491634 3.70828327 1 P 0 ;0,1,2=168,3=0.000000
L 2.09078356 3.71241575 2.0881001 3.71603356 1 P 0 ;0,1,2=168,3=0.000000
L 2.0881001 3.71603356 2.0857999 3.7180998 1 P 0 ;0,1,2=168,3=0.000000
L 2.0857999 3.7180998 2.08273317 3.71913287 1 P 0 ;0,1,2=168,3=0.000000
L 2.08273317 3.71913287 2.0800497 3.7180998 1 P 0 ;0,1,2=168,3=0.000000
L 2.0800497 3.7180998 2.07813346 3.71603356 1 P 0 ;0,1,2=168,3=0.000000
L 2.07813346 3.71603356 2.0765998 3.71293327 1 P 0 ;0,1,2=168,3=0.000000
L 2.0765998 3.71293327 2.07621654 3.70931644 1 P 0 ;0,1,2=168,3=0.000000
L 2.07621654 3.70931644 2.0765998 3.70621614 1 P 0 ;0,1,2=168,3=0.000000
L 2.0765998 3.70621614 2.07813346 3.70311585 1 P 0 ;0,1,2=168,3=0.000000
L 2.07813346 3.70311585 2.08043366 3.70053307 1 P 0 ;0,1,2=168,3=0.000000
L 2.08043366 3.70053307 2.08311644 3.6995 1 P 0 ;0,1,2=168,3=0.000000
L 2.08311644 3.6995 2.08618317 3.70053307 1 P 0 ;0,1,2=168,3=0.000000
L 2.08618317 3.70053307 2.08886663 3.70363238 1 P 0 ;0,1,2=168,3=0.000000
L 2.08886663 3.70363238 2.0904003 3.70828327 1 P 0 ;0,1,2=168,3=0.000000
L 2.0904003 3.70828327 2.09078356 3.7134498 1 P 0 ;0,1,2=168,3=0.000000
L 2.09078356 3.7134498 2.09001713 3.72016594 1 P 0 ;0,1,2=168,3=0.000000
L 2.09001713 3.72016594 2.08886663 3.72378376 1 P 0 ;0,1,2=168,3=0.000000
L 2.08886663 3.72378376 2.08695039 3.7273997 1 P 0 ;0,1,2=168,3=0.000000
L 2.08695039 3.7273997 2.08426693 3.72998337 1 P 0 ;0,1,2=168,3=0.000000
L 2.08426693 3.72998337 2.08158346 3.7305 1 P 0 ;0,1,2=168,3=0.000000
L 2.08158346 3.7305 2.0789 3.72946683 1 P 0 ;0,1,2=168,3=0.000000
L 2.0789 3.72946683 2.07698297 3.72688307 1 P 0 ;0,1,2=168,3=0.000000
L 2.08 3.382 2.17 3.382 1 P 0 
L 2.17 3.338 2.08 3.338 1 P 0 
L 2.08 3.338 2.08 3.382 1 P 0 
L 2.17 3.382 2.17 3.338 1 P 0 
L 2.18416683 3.5795 2.18416683 3.6105 1 P 0 ;0,1,2=169,3=0.000000
L 2.18416683 3.6105 2.17458346 3.6105 1 P 0 ;0,1,2=169,3=0.000000
L 2.17458346 3.6105 2.17151673 3.60894931 1 P 0 ;0,1,2=169,3=0.000000
L 2.17151673 3.60894931 2.1695998 3.60688307 1 P 0 ;0,1,2=169,3=0.000000
L 2.1695998 3.60688307 2.16883327 3.6027497 1 P 0 ;0,1,2=169,3=0.000000
L 2.16883327 3.6027497 2.1695998 3.59861634 1 P 0 ;0,1,2=169,3=0.000000
L 2.1695998 3.59861634 2.1719 3.59603356 1 P 0 ;0,1,2=169,3=0.000000
L 2.1719 3.59603356 2.17458346 3.59448287 1 P 0 ;0,1,2=169,3=0.000000
L 2.17458346 3.59448287 2.18416683 3.59448287 1 P 0 ;0,1,2=169,3=0.000000
L 2.17458346 3.59448287 2.16883327 3.5795 1 P 0 ;0,1,2=169,3=0.000000
L 2.1409 3.5795 2.1409 3.6105 1 P 0 ;0,1,2=169,3=0.000000
L 2.1409 3.6105 2.15508376 3.58828327 1 P 0 ;0,1,2=169,3=0.000000
L 2.15508376 3.58828327 2.13591634 3.58828327 1 P 0 ;0,1,2=169,3=0.000000
L 2.1099 3.5795 2.1099 3.6105 1 P 0 ;0,1,2=169,3=0.000000
L 2.1099 3.6105 2.12408376 3.58828327 1 P 0 ;0,1,2=169,3=0.000000
L 2.12408376 3.58828327 2.10491634 3.58828327 1 P 0 ;0,1,2=169,3=0.000000
L 2.0789 3.5795 2.0789 3.6105 1 P 0 ;0,1,2=169,3=0.000000
L 2.0789 3.6105 2.09308376 3.58828327 1 P 0 ;0,1,2=169,3=0.000000
L 2.09308376 3.58828327 2.07391634 3.58828327 1 P 0 ;0,1,2=169,3=0.000000
L 4.607 1.205 4.607 1.115 1 P 0 
L 4.607 1.115 4.563 1.115 1 P 0 
L 4.563 1.115 4.563 1.205 1 P 0 
L 4.563 1.205 4.607 1.205 1 P 0 
L 4.5695 0.97083317 4.6005 0.97083317 1 P 0 ;0,1,2=170,3=90.000000
L 4.6005 0.97083317 4.6005 0.98041654 1 P 0 ;0,1,2=170,3=90.000000
L 4.6005 0.98041654 4.59894931 0.98348327 1 P 0 ;0,1,2=170,3=90.000000
L 4.59894931 0.98348327 4.59688307 0.9854002 1 P 0 ;0,1,2=170,3=90.000000
L 4.59688307 0.9854002 4.5927497 0.98616673 1 P 0 ;0,1,2=170,3=90.000000
L 4.5927497 0.98616673 4.58861634 0.9854002 1 P 0 ;0,1,2=170,3=90.000000
L 4.58861634 0.9854002 4.58603356 0.9831 1 P 0 ;0,1,2=170,3=90.000000
L 4.58603356 0.9831 4.58448287 0.98041654 1 P 0 ;0,1,2=170,3=90.000000
L 4.58448287 0.98041654 4.58448287 0.97083317 1 P 0 ;0,1,2=170,3=90.000000
L 4.58448287 0.98041654 4.5695 0.98616673 1 P 0 ;0,1,2=170,3=90.000000
L 4.5695 1.0141 4.6005 1.0141 1 P 0 ;0,1,2=170,3=90.000000
L 4.6005 1.0141 4.57828327 0.99991624 1 P 0 ;0,1,2=170,3=90.000000
L 4.57828327 0.99991624 4.57828327 1.01908366 1 P 0 ;0,1,2=170,3=90.000000
L 4.5695 1.0451 4.6005 1.0451 1 P 0 ;0,1,2=170,3=90.000000
L 4.6005 1.0451 4.57828327 1.03091624 1 P 0 ;0,1,2=170,3=90.000000
L 4.57828327 1.03091624 4.57828327 1.05008366 1 P 0 ;0,1,2=170,3=90.000000
L 4.5695 1.07149961 4.6005 1.07149961 1 P 0 ;0,1,2=170,3=90.000000
L 4.6005 1.07149961 4.5943003 1.0668999 1 P 0 ;0,1,2=170,3=90.000000
L 4.5695 1.0668999 4.5695 1.07609931 1 P 0 ;0,1,2=170,3=90.000000
L 4.552 1.205 4.552 1.115 1 P 0 
L 4.552 1.115 4.508 1.115 1 P 0 
L 4.508 1.115 4.508 1.205 1 P 0 
L 4.508 1.205 4.552 1.205 1 P 0 
L 4.5195 0.96583317 4.5505 0.96583317 1 P 0 ;0,1,2=171,3=90.000000
L 4.5505 0.96583317 4.5505 0.97541654 1 P 0 ;0,1,2=171,3=90.000000
L 4.5505 0.97541654 4.54894931 0.97848327 1 P 0 ;0,1,2=171,3=90.000000
L 4.54894931 0.97848327 4.54688307 0.9804002 1 P 0 ;0,1,2=171,3=90.000000
L 4.54688307 0.9804002 4.5427497 0.98116673 1 P 0 ;0,1,2=171,3=90.000000
L 4.5427497 0.98116673 4.53861634 0.9804002 1 P 0 ;0,1,2=171,3=90.000000
L 4.53861634 0.9804002 4.53603356 0.9781 1 P 0 ;0,1,2=171,3=90.000000
L 4.53603356 0.9781 4.53448287 0.97541654 1 P 0 ;0,1,2=171,3=90.000000
L 4.53448287 0.97541654 4.53448287 0.96583317 1 P 0 ;0,1,2=171,3=90.000000
L 4.53448287 0.97541654 4.5195 0.98116673 1 P 0 ;0,1,2=171,3=90.000000
L 4.5195 1.0091 4.5505 1.0091 1 P 0 ;0,1,2=171,3=90.000000
L 4.5505 1.0091 4.52828327 0.99491624 1 P 0 ;0,1,2=171,3=90.000000
L 4.52828327 0.99491624 4.52828327 1.01408366 1 P 0 ;0,1,2=171,3=90.000000
L 4.5195 1.0401 4.5505 1.0401 1 P 0 ;0,1,2=171,3=90.000000
L 4.5505 1.0401 4.52828327 1.02591624 1 P 0 ;0,1,2=171,3=90.000000
L 4.52828327 1.02591624 4.52828327 1.04508366 1 P 0 ;0,1,2=171,3=90.000000
L 4.5505 1.06649961 4.54946683 1.06343287 1 P 0 ;0,1,2=171,3=90.000000
L 4.54946683 1.06343287 4.54688307 1.06113337 1 P 0 ;0,1,2=171,3=90.000000
L 4.54688307 1.06113337 4.54378376 1.0595997 1 P 0 ;0,1,2=171,3=90.000000
L 4.54378376 1.0595997 4.53964941 1.0584499 1 P 0 ;0,1,2=171,3=90.000000
L 4.53964941 1.0584499 4.53499951 1.05806663 1 P 0 ;0,1,2=171,3=90.000000
L 4.53499951 1.05806663 4.53034951 1.0584499 1 P 0 ;0,1,2=171,3=90.000000
L 4.53034951 1.0584499 4.52621614 1.0595997 1 P 0 ;0,1,2=171,3=90.000000
L 4.52621614 1.0595997 4.52311585 1.06113337 1 P 0 ;0,1,2=171,3=90.000000
L 4.52311585 1.06113337 4.52053307 1.06343287 1 P 0 ;0,1,2=171,3=90.000000
L 4.52053307 1.06343287 4.5195 1.06649961 1 P 0 ;0,1,2=171,3=90.000000
L 4.5195 1.06649961 4.52053307 1.06956634 1 P 0 ;0,1,2=171,3=90.000000
L 4.52053307 1.06956634 4.52311585 1.07186654 1 P 0 ;0,1,2=171,3=90.000000
L 4.52311585 1.07186654 4.52621614 1.0734002 1 P 0 ;0,1,2=171,3=90.000000
L 4.52621614 1.0734002 4.53034951 1.07455 1 P 0 ;0,1,2=171,3=90.000000
L 4.53034951 1.07455 4.53499951 1.07493327 1 P 0 ;0,1,2=171,3=90.000000
L 4.53499951 1.07493327 4.53964941 1.07455 1 P 0 ;0,1,2=171,3=90.000000
L 4.53964941 1.07455 4.54378376 1.0734002 1 P 0 ;0,1,2=171,3=90.000000
L 4.54378376 1.0734002 4.54688307 1.07186654 1 P 0 ;0,1,2=171,3=90.000000
L 4.54688307 1.07186654 4.54946683 1.06956634 1 P 0 ;0,1,2=171,3=90.000000
L 4.54946683 1.06956634 4.5505 1.06649961 1 P 0 ;0,1,2=171,3=90.000000
L 1.6 3.907 1.69 3.907 1 P 0 
L 1.69 3.907 1.69 3.863 1 P 0 
L 1.69 3.863 1.6 3.863 1 P 0 
L 1.6 3.863 1.6 3.907 1 P 0 
L 1.65366683 3.9195 1.65366683 3.9505 1 P 0 ;0,1,2=172,3=0.000000
L 1.65366683 3.9505 1.64408346 3.9505 1 P 0 ;0,1,2=172,3=0.000000
L 1.64408346 3.9505 1.64101673 3.94894931 1 P 0 ;0,1,2=172,3=0.000000
L 1.64101673 3.94894931 1.6390998 3.94688307 1 P 0 ;0,1,2=172,3=0.000000
L 1.6390998 3.94688307 1.63833327 3.9427497 1 P 0 ;0,1,2=172,3=0.000000
L 1.63833327 3.9427497 1.6390998 3.93861634 1 P 0 ;0,1,2=172,3=0.000000
L 1.6390998 3.93861634 1.6414 3.93603356 1 P 0 ;0,1,2=172,3=0.000000
L 1.6414 3.93603356 1.64408346 3.93448287 1 P 0 ;0,1,2=172,3=0.000000
L 1.64408346 3.93448287 1.65366683 3.93448287 1 P 0 ;0,1,2=172,3=0.000000
L 1.64408346 3.93448287 1.63833327 3.9195 1 P 0 ;0,1,2=172,3=0.000000
L 1.62343337 3.92569961 1.62113386 3.92208278 1 P 0 ;0,1,2=172,3=0.000000
L 1.62113386 3.92208278 1.61806713 3.92001654 1 P 0 ;0,1,2=172,3=0.000000
L 1.61806713 3.92001654 1.61461644 3.9195 1 P 0 ;0,1,2=172,3=0.000000
L 1.61461644 3.9195 1.6115497 3.92001654 1 P 0 ;0,1,2=172,3=0.000000
L 1.6115497 3.92001654 1.60848297 3.92259931 1 P 0 ;0,1,2=172,3=0.000000
L 1.60848297 3.92259931 1.60656673 3.92569961 1 P 0 ;0,1,2=172,3=0.000000
L 1.60656673 3.92569961 1.60618346 3.9287999 1 P 0 ;0,1,2=172,3=0.000000
L 1.60618346 3.9287999 1.60695 3.93241575 1 P 0 ;0,1,2=172,3=0.000000
L 1.60695 3.93241575 1.60963346 3.93499951 1 P 0 ;0,1,2=172,3=0.000000
L 1.60963346 3.93499951 1.61231693 3.93603356 1 P 0 ;0,1,2=172,3=0.000000
L 1.61231693 3.93603356 1.61576693 3.93603356 1 P 0 ;0,1,2=172,3=0.000000
L 1.61231693 3.93603356 1.61001673 3.93758317 1 P 0 ;0,1,2=172,3=0.000000
L 1.61001673 3.93758317 1.6080998 3.94016594 1 P 0 ;0,1,2=172,3=0.000000
L 1.6080998 3.94016594 1.60733327 3.94326624 1 P 0 ;0,1,2=172,3=0.000000
L 1.60733327 3.94326624 1.6080998 3.94636654 1 P 0 ;0,1,2=172,3=0.000000
L 1.6080998 3.94636654 1.61001673 3.94894931 1 P 0 ;0,1,2=172,3=0.000000
L 1.61001673 3.94894931 1.61346673 3.9505 1 P 0 ;0,1,2=172,3=0.000000
L 1.61346673 3.9505 1.61691663 3.94998337 1 P 0 ;0,1,2=172,3=0.000000
L 1.61691663 3.94998337 1.62036663 3.94791624 1 P 0 ;0,1,2=172,3=0.000000
L 1.58400039 3.9195 1.58400039 3.9505 1 P 0 ;0,1,2=172,3=0.000000
L 1.58400039 3.9505 1.5886001 3.9443003 1 P 0 ;0,1,2=172,3=0.000000
L 1.5886001 3.9195 1.57940069 3.9195 1 P 0 ;0,1,2=172,3=0.000000
L 3.32 4.117 3.41 4.117 1 P 0 
L 3.41 4.073 3.32 4.073 1 P 0 
L 3.32 4.073 3.32 4.117 1 P 0 
L 3.41 4.117 3.41 4.073 1 P 0 
L 3.40366683 4.0295 3.40366683 4.0605 1 P 0 ;0,1,2=173,3=0.000000
L 3.40366683 4.0605 3.39408346 4.0605 1 P 0 ;0,1,2=173,3=0.000000
L 3.39408346 4.0605 3.39101673 4.05894931 1 P 0 ;0,1,2=173,3=0.000000
L 3.39101673 4.05894931 3.3890998 4.05688307 1 P 0 ;0,1,2=173,3=0.000000
L 3.3890998 4.05688307 3.38833327 4.0527497 1 P 0 ;0,1,2=173,3=0.000000
L 3.38833327 4.0527497 3.3890998 4.04861634 1 P 0 ;0,1,2=173,3=0.000000
L 3.3890998 4.04861634 3.3914 4.04603356 1 P 0 ;0,1,2=173,3=0.000000
L 3.3914 4.04603356 3.39408346 4.04448287 1 P 0 ;0,1,2=173,3=0.000000
L 3.39408346 4.04448287 3.40366683 4.04448287 1 P 0 ;0,1,2=173,3=0.000000
L 3.39408346 4.04448287 3.38833327 4.0295 1 P 0 ;0,1,2=173,3=0.000000
L 3.37343337 4.03569961 3.37113386 4.03208278 1 P 0 ;0,1,2=173,3=0.000000
L 3.37113386 4.03208278 3.36806713 4.03001654 1 P 0 ;0,1,2=173,3=0.000000
L 3.36806713 4.03001654 3.36461644 4.0295 1 P 0 ;0,1,2=173,3=0.000000
L 3.36461644 4.0295 3.3615497 4.03001654 1 P 0 ;0,1,2=173,3=0.000000
L 3.3615497 4.03001654 3.35848297 4.03259931 1 P 0 ;0,1,2=173,3=0.000000
L 3.35848297 4.03259931 3.35656673 4.03569961 1 P 0 ;0,1,2=173,3=0.000000
L 3.35656673 4.03569961 3.35618346 4.0387999 1 P 0 ;0,1,2=173,3=0.000000
L 3.35618346 4.0387999 3.35695 4.04241575 1 P 0 ;0,1,2=173,3=0.000000
L 3.35695 4.04241575 3.35963346 4.04499951 1 P 0 ;0,1,2=173,3=0.000000
L 3.35963346 4.04499951 3.36231693 4.04603356 1 P 0 ;0,1,2=173,3=0.000000
L 3.36231693 4.04603356 3.36576693 4.04603356 1 P 0 ;0,1,2=173,3=0.000000
L 3.36231693 4.04603356 3.36001673 4.04758317 1 P 0 ;0,1,2=173,3=0.000000
L 3.36001673 4.04758317 3.3580998 4.05016594 1 P 0 ;0,1,2=173,3=0.000000
L 3.3580998 4.05016594 3.35733327 4.05326624 1 P 0 ;0,1,2=173,3=0.000000
L 3.35733327 4.05326624 3.3580998 4.05636654 1 P 0 ;0,1,2=173,3=0.000000
L 3.3580998 4.05636654 3.36001673 4.05894931 1 P 0 ;0,1,2=173,3=0.000000
L 3.36001673 4.05894931 3.36346673 4.0605 1 P 0 ;0,1,2=173,3=0.000000
L 3.36346673 4.0605 3.36691663 4.05998337 1 P 0 ;0,1,2=173,3=0.000000
L 3.36691663 4.05998337 3.37036663 4.05791624 1 P 0 ;0,1,2=173,3=0.000000
L 3.33476693 4.0295 3.33400039 4.03621614 1 P 0 ;0,1,2=173,3=0.000000
L 3.33400039 4.03621614 3.3328499 4.04189921 1 P 0 ;0,1,2=173,3=0.000000
L 3.3328499 4.04189921 3.33131693 4.04706663 1 P 0 ;0,1,2=173,3=0.000000
L 3.33131693 4.04706663 3.3294 4.0527497 1 P 0 ;0,1,2=173,3=0.000000
L 3.3294 4.0527497 3.32633327 4.0605 1 P 0 ;0,1,2=173,3=0.000000
L 3.32633327 4.0605 3.34166683 4.0605 1 P 0 ;0,1,2=173,3=0.000000
L 3.002 3.232 3.092 3.232 1 P 0 
L 3.092 3.232 3.092 3.188 1 P 0 
L 3.092 3.188 3.002 3.188 1 P 0 
L 3.002 3.188 3.002 3.232 1 P 0 
L 2.96866683 3.1945 2.96866683 3.2255 1 P 0 ;0,1,2=174,3=0.000000
L 2.96866683 3.2255 2.95908346 3.2255 1 P 0 ;0,1,2=174,3=0.000000
L 2.95908346 3.2255 2.95601673 3.22394931 1 P 0 ;0,1,2=174,3=0.000000
L 2.95601673 3.22394931 2.9540998 3.22188307 1 P 0 ;0,1,2=174,3=0.000000
L 2.9540998 3.22188307 2.95333327 3.2177497 1 P 0 ;0,1,2=174,3=0.000000
L 2.95333327 3.2177497 2.9540998 3.21361634 1 P 0 ;0,1,2=174,3=0.000000
L 2.9540998 3.21361634 2.9564 3.21103356 1 P 0 ;0,1,2=174,3=0.000000
L 2.9564 3.21103356 2.95908346 3.20948287 1 P 0 ;0,1,2=174,3=0.000000
L 2.95908346 3.20948287 2.96866683 3.20948287 1 P 0 ;0,1,2=174,3=0.000000
L 2.95908346 3.20948287 2.95333327 3.1945 1 P 0 ;0,1,2=174,3=0.000000
L 2.93728356 3.20741575 2.9346001 3.21103356 1 P 0 ;0,1,2=174,3=0.000000
L 2.9346001 3.21103356 2.9322999 3.2130998 1 P 0 ;0,1,2=174,3=0.000000
L 2.9322999 3.2130998 2.92923317 3.21413287 1 P 0 ;0,1,2=174,3=0.000000
L 2.92923317 3.21413287 2.9265497 3.2130998 1 P 0 ;0,1,2=174,3=0.000000
L 2.9265497 3.2130998 2.92463346 3.21103356 1 P 0 ;0,1,2=174,3=0.000000
L 2.92463346 3.21103356 2.9230998 3.20793327 1 P 0 ;0,1,2=174,3=0.000000
L 2.9230998 3.20793327 2.92271654 3.20431644 1 P 0 ;0,1,2=174,3=0.000000
L 2.92271654 3.20431644 2.9230998 3.20121614 1 P 0 ;0,1,2=174,3=0.000000
L 2.9230998 3.20121614 2.92463346 3.19811585 1 P 0 ;0,1,2=174,3=0.000000
L 2.92463346 3.19811585 2.92693366 3.19553307 1 P 0 ;0,1,2=174,3=0.000000
L 2.92693366 3.19553307 2.92961644 3.1945 1 P 0 ;0,1,2=174,3=0.000000
L 2.92961644 3.1945 2.93268317 3.19553307 1 P 0 ;0,1,2=174,3=0.000000
L 2.93268317 3.19553307 2.93536663 3.19863238 1 P 0 ;0,1,2=174,3=0.000000
L 2.93536663 3.19863238 2.9369003 3.20328327 1 P 0 ;0,1,2=174,3=0.000000
L 2.9369003 3.20328327 2.93728356 3.2084498 1 P 0 ;0,1,2=174,3=0.000000
L 2.93728356 3.2084498 2.93651713 3.21516594 1 P 0 ;0,1,2=174,3=0.000000
L 2.93651713 3.21516594 2.93536663 3.21878376 1 P 0 ;0,1,2=174,3=0.000000
L 2.93536663 3.21878376 2.93345039 3.2223997 1 P 0 ;0,1,2=174,3=0.000000
L 2.93345039 3.2223997 2.93076693 3.22498337 1 P 0 ;0,1,2=174,3=0.000000
L 2.93076693 3.22498337 2.92808346 3.2255 1 P 0 ;0,1,2=174,3=0.000000
L 2.92808346 3.2255 2.9254 3.22446683 1 P 0 ;0,1,2=174,3=0.000000
L 2.9254 3.22446683 2.92348297 3.22188307 1 P 0 ;0,1,2=174,3=0.000000
L 2.89900039 3.1945 2.89900039 3.2255 1 P 0 ;0,1,2=174,3=0.000000
L 2.89900039 3.2255 2.9036001 3.2193003 1 P 0 ;0,1,2=174,3=0.000000
L 2.9036001 3.1945 2.89440069 3.1945 1 P 0 ;0,1,2=174,3=0.000000
L 3.002 3.282 3.092 3.282 1 P 0 
L 3.092 3.282 3.092 3.238 1 P 0 
L 3.092 3.238 3.002 3.238 1 P 0 
L 3.002 3.238 3.002 3.282 1 P 0 
L 2.96866683 3.2345 2.96866683 3.2655 1 P 0 ;0,1,2=175,3=0.000000
L 2.96866683 3.2655 2.95908346 3.2655 1 P 0 ;0,1,2=175,3=0.000000
L 2.95908346 3.2655 2.95601673 3.26394931 1 P 0 ;0,1,2=175,3=0.000000
L 2.95601673 3.26394931 2.9540998 3.26188307 1 P 0 ;0,1,2=175,3=0.000000
L 2.9540998 3.26188307 2.95333327 3.2577497 1 P 0 ;0,1,2=175,3=0.000000
L 2.95333327 3.2577497 2.9540998 3.25361634 1 P 0 ;0,1,2=175,3=0.000000
L 2.9540998 3.25361634 2.9564 3.25103356 1 P 0 ;0,1,2=175,3=0.000000
L 2.9564 3.25103356 2.95908346 3.24948287 1 P 0 ;0,1,2=175,3=0.000000
L 2.95908346 3.24948287 2.96866683 3.24948287 1 P 0 ;0,1,2=175,3=0.000000
L 2.95908346 3.24948287 2.95333327 3.2345 1 P 0 ;0,1,2=175,3=0.000000
L 2.93728356 3.24741575 2.9346001 3.25103356 1 P 0 ;0,1,2=175,3=0.000000
L 2.9346001 3.25103356 2.9322999 3.2530998 1 P 0 ;0,1,2=175,3=0.000000
L 2.9322999 3.2530998 2.92923317 3.25413287 1 P 0 ;0,1,2=175,3=0.000000
L 2.92923317 3.25413287 2.9265497 3.2530998 1 P 0 ;0,1,2=175,3=0.000000
L 2.9265497 3.2530998 2.92463346 3.25103356 1 P 0 ;0,1,2=175,3=0.000000
L 2.92463346 3.25103356 2.9230998 3.24793327 1 P 0 ;0,1,2=175,3=0.000000
L 2.9230998 3.24793327 2.92271654 3.24431644 1 P 0 ;0,1,2=175,3=0.000000
L 2.92271654 3.24431644 2.9230998 3.24121614 1 P 0 ;0,1,2=175,3=0.000000
L 2.9230998 3.24121614 2.92463346 3.23811585 1 P 0 ;0,1,2=175,3=0.000000
L 2.92463346 3.23811585 2.92693366 3.23553307 1 P 0 ;0,1,2=175,3=0.000000
L 2.92693366 3.23553307 2.92961644 3.2345 1 P 0 ;0,1,2=175,3=0.000000
L 2.92961644 3.2345 2.93268317 3.23553307 1 P 0 ;0,1,2=175,3=0.000000
L 2.93268317 3.23553307 2.93536663 3.23863238 1 P 0 ;0,1,2=175,3=0.000000
L 2.93536663 3.23863238 2.9369003 3.24328327 1 P 0 ;0,1,2=175,3=0.000000
L 2.9369003 3.24328327 2.93728356 3.2484498 1 P 0 ;0,1,2=175,3=0.000000
L 2.93728356 3.2484498 2.93651713 3.25516594 1 P 0 ;0,1,2=175,3=0.000000
L 2.93651713 3.25516594 2.93536663 3.25878376 1 P 0 ;0,1,2=175,3=0.000000
L 2.93536663 3.25878376 2.93345039 3.2623997 1 P 0 ;0,1,2=175,3=0.000000
L 2.93345039 3.2623997 2.93076693 3.26498337 1 P 0 ;0,1,2=175,3=0.000000
L 2.93076693 3.26498337 2.92808346 3.2655 1 P 0 ;0,1,2=175,3=0.000000
L 2.92808346 3.2655 2.9254 3.26446683 1 P 0 ;0,1,2=175,3=0.000000
L 2.9254 3.26446683 2.92348297 3.26188307 1 P 0 ;0,1,2=175,3=0.000000
L 2.90628356 3.26033346 2.90398337 3.26343278 1 P 0 ;0,1,2=175,3=0.000000
L 2.90398337 3.26343278 2.9012999 3.26498337 1 P 0 ;0,1,2=175,3=0.000000
L 2.9012999 3.26498337 2.89823317 3.2655 1 P 0 ;0,1,2=175,3=0.000000
L 2.89823317 3.2655 2.8944 3.26446683 1 P 0 ;0,1,2=175,3=0.000000
L 2.8944 3.26446683 2.89171654 3.26188307 1 P 0 ;0,1,2=175,3=0.000000
L 2.89171654 3.26188307 2.89095 3.25878376 1 P 0 ;0,1,2=175,3=0.000000
L 2.89095 3.25878376 2.89133327 3.25568258 1 P 0 ;0,1,2=175,3=0.000000
L 2.89133327 3.25568258 2.89286693 3.2530998 1 P 0 ;0,1,2=175,3=0.000000
L 2.89286693 3.2530998 2.90053337 3.24793327 1 P 0 ;0,1,2=175,3=0.000000
L 2.90053337 3.24793327 2.90398337 3.24431644 1 P 0 ;0,1,2=175,3=0.000000
L 2.90398337 3.24431644 2.90628356 3.23914892 1 P 0 ;0,1,2=175,3=0.000000
L 2.90628356 3.23914892 2.9070501 3.2345 1 P 0 ;0,1,2=175,3=0.000000
L 2.9070501 3.2345 2.89095 3.2345 1 P 0 ;0,1,2=175,3=0.000000
L 4.95 1.877 4.95 1.833 1 P 0 
L 4.95 1.833 4.86 1.833 1 P 0 
L 4.86 1.833 4.86 1.877 1 P 0 
L 4.86 1.877 4.95 1.877 1 P 0 
L 5.10366683 1.8345 5.10366683 1.8655 1 P 0 ;0,1,2=176,3=0.000000
L 5.10366683 1.8655 5.09408346 1.8655 1 P 0 ;0,1,2=176,3=0.000000
L 5.09408346 1.8655 5.09101673 1.86394931 1 P 0 ;0,1,2=176,3=0.000000
L 5.09101673 1.86394931 5.0890998 1.86188307 1 P 0 ;0,1,2=176,3=0.000000
L 5.0890998 1.86188307 5.08833327 1.8577497 1 P 0 ;0,1,2=176,3=0.000000
L 5.08833327 1.8577497 5.0890998 1.85361634 1 P 0 ;0,1,2=176,3=0.000000
L 5.0890998 1.85361634 5.0914 1.85103356 1 P 0 ;0,1,2=176,3=0.000000
L 5.0914 1.85103356 5.09408346 1.84948287 1 P 0 ;0,1,2=176,3=0.000000
L 5.09408346 1.84948287 5.10366683 1.84948287 1 P 0 ;0,1,2=176,3=0.000000
L 5.09408346 1.84948287 5.08833327 1.8345 1 P 0 ;0,1,2=176,3=0.000000
L 5.07151713 1.83811585 5.06883366 1.83553307 1 P 0 ;0,1,2=176,3=0.000000
L 5.06883366 1.83553307 5.06576693 1.8345 1 P 0 ;0,1,2=176,3=0.000000
L 5.06576693 1.8345 5.0627002 1.83553307 1 P 0 ;0,1,2=176,3=0.000000
L 5.0627002 1.83553307 5.06001673 1.83863238 1 P 0 ;0,1,2=176,3=0.000000
L 5.06001673 1.83863238 5.0580998 1.84328327 1 P 0 ;0,1,2=176,3=0.000000
L 5.0580998 1.84328327 5.05733327 1.84793327 1 P 0 ;0,1,2=176,3=0.000000
L 5.05733327 1.84793327 5.05733327 1.85361634 1 P 0 ;0,1,2=176,3=0.000000
L 5.05733327 1.85361634 5.0580998 1.85826624 1 P 0 ;0,1,2=176,3=0.000000
L 5.0580998 1.85826624 5.06001673 1.8623997 1 P 0 ;0,1,2=176,3=0.000000
L 5.06001673 1.8623997 5.06231693 1.86446683 1 P 0 ;0,1,2=176,3=0.000000
L 5.06231693 1.86446683 5.06500039 1.8655 1 P 0 ;0,1,2=176,3=0.000000
L 5.06500039 1.8655 5.06806713 1.86446683 1 P 0 ;0,1,2=176,3=0.000000
L 5.06806713 1.86446683 5.07036663 1.8623997 1 P 0 ;0,1,2=176,3=0.000000
L 5.07036663 1.8623997 5.0719003 1.8593003 1 P 0 ;0,1,2=176,3=0.000000
L 5.0719003 1.8593003 5.07266683 1.85516594 1 P 0 ;0,1,2=176,3=0.000000
L 5.07266683 1.85516594 5.0719003 1.8515501 1 P 0 ;0,1,2=176,3=0.000000
L 5.0719003 1.8515501 5.06998337 1.84793327 1 P 0 ;0,1,2=176,3=0.000000
L 5.06998337 1.84793327 5.06768317 1.84586604 1 P 0 ;0,1,2=176,3=0.000000
L 5.06768317 1.84586604 5.06500039 1.84534951 1 P 0 ;0,1,2=176,3=0.000000
L 5.06500039 1.84534951 5.06193366 1.84638268 1 P 0 ;0,1,2=176,3=0.000000
L 5.06193366 1.84638268 5.05963346 1.84896634 1 P 0 ;0,1,2=176,3=0.000000
L 5.05963346 1.84896634 5.05733327 1.85361634 1 P 0 ;0,1,2=176,3=0.000000
L 5.04128356 1.86033346 5.03898337 1.86343278 1 P 0 ;0,1,2=176,3=0.000000
L 5.03898337 1.86343278 5.0362999 1.86498337 1 P 0 ;0,1,2=176,3=0.000000
L 5.0362999 1.86498337 5.03323317 1.8655 1 P 0 ;0,1,2=176,3=0.000000
L 5.03323317 1.8655 5.0294 1.86446683 1 P 0 ;0,1,2=176,3=0.000000
L 5.0294 1.86446683 5.02671654 1.86188307 1 P 0 ;0,1,2=176,3=0.000000
L 5.02671654 1.86188307 5.02595 1.85878376 1 P 0 ;0,1,2=176,3=0.000000
L 5.02595 1.85878376 5.02633327 1.85568258 1 P 0 ;0,1,2=176,3=0.000000
L 5.02633327 1.85568258 5.02786693 1.8530998 1 P 0 ;0,1,2=176,3=0.000000
L 5.02786693 1.8530998 5.03553337 1.84793327 1 P 0 ;0,1,2=176,3=0.000000
L 5.03553337 1.84793327 5.03898337 1.84431644 1 P 0 ;0,1,2=176,3=0.000000
L 5.03898337 1.84431644 5.04128356 1.83914892 1 P 0 ;0,1,2=176,3=0.000000
L 5.04128356 1.83914892 5.0420501 1.8345 1 P 0 ;0,1,2=176,3=0.000000
L 5.0420501 1.8345 5.02595 1.8345 1 P 0 ;0,1,2=176,3=0.000000
L 5.488 2.195 5.532 2.195 1 P 0 
L 5.532 2.195 5.532 2.105 1 P 0 
L 5.532 2.105 5.488 2.105 1 P 0 
L 5.488 2.105 5.488 2.195 1 P 0 
L 5.5395 2.11583317 5.5705 2.11583317 1 P 0 ;0,1,2=177,3=90.000000
L 5.5705 2.11583317 5.5705 2.12541654 1 P 0 ;0,1,2=177,3=90.000000
L 5.5705 2.12541654 5.56894931 2.12848327 1 P 0 ;0,1,2=177,3=90.000000
L 5.56894931 2.12848327 5.56688307 2.1304002 1 P 0 ;0,1,2=177,3=90.000000
L 5.56688307 2.1304002 5.5627497 2.13116673 1 P 0 ;0,1,2=177,3=90.000000
L 5.5627497 2.13116673 5.55861634 2.1304002 1 P 0 ;0,1,2=177,3=90.000000
L 5.55861634 2.1304002 5.55603356 2.1281 1 P 0 ;0,1,2=177,3=90.000000
L 5.55603356 2.1281 5.55448287 2.12541654 1 P 0 ;0,1,2=177,3=90.000000
L 5.55448287 2.12541654 5.55448287 2.11583317 1 P 0 ;0,1,2=177,3=90.000000
L 5.55448287 2.12541654 5.5395 2.13116673 1 P 0 ;0,1,2=177,3=90.000000
L 5.56533346 2.14721644 5.56843278 2.14951663 1 P 0 ;0,1,2=177,3=90.000000
L 5.56843278 2.14951663 5.56998337 2.1522001 1 P 0 ;0,1,2=177,3=90.000000
L 5.56998337 2.1522001 5.5705 2.15526683 1 P 0 ;0,1,2=177,3=90.000000
L 5.5705 2.15526683 5.56946683 2.1591 1 P 0 ;0,1,2=177,3=90.000000
L 5.56946683 2.1591 5.56688307 2.16178346 1 P 0 ;0,1,2=177,3=90.000000
L 5.56688307 2.16178346 5.56378376 2.16255 1 P 0 ;0,1,2=177,3=90.000000
L 5.56378376 2.16255 5.56068258 2.16216673 1 P 0 ;0,1,2=177,3=90.000000
L 5.56068258 2.16216673 5.5580998 2.16063307 1 P 0 ;0,1,2=177,3=90.000000
L 5.5580998 2.16063307 5.55293327 2.15296663 1 P 0 ;0,1,2=177,3=90.000000
L 5.55293327 2.15296663 5.54931644 2.14951663 1 P 0 ;0,1,2=177,3=90.000000
L 5.54931644 2.14951663 5.54414892 2.14721644 1 P 0 ;0,1,2=177,3=90.000000
L 5.54414892 2.14721644 5.5395 2.1464499 1 P 0 ;0,1,2=177,3=90.000000
L 5.5395 2.1464499 5.5395 2.16255 1 P 0 ;0,1,2=177,3=90.000000
L 5.54414892 2.17706663 5.54156614 2.17936614 1 P 0 ;0,1,2=177,3=90.000000
L 5.54156614 2.17936614 5.54001654 2.18204961 1 P 0 ;0,1,2=177,3=90.000000
L 5.54001654 2.18204961 5.5395 2.18549961 1 P 0 ;0,1,2=177,3=90.000000
L 5.5395 2.18549961 5.54053307 2.1889503 1 P 0 ;0,1,2=177,3=90.000000
L 5.54053307 2.1889503 5.54259931 2.19163307 1 P 0 ;0,1,2=177,3=90.000000
L 5.54259931 2.19163307 5.54621614 2.19355 1 P 0 ;0,1,2=177,3=90.000000
L 5.54621614 2.19355 5.55034951 2.19393327 1 P 0 ;0,1,2=177,3=90.000000
L 5.55034951 2.19393327 5.55448287 2.19316673 1 P 0 ;0,1,2=177,3=90.000000
L 5.55448287 2.19316673 5.55706663 2.1912498 1 P 0 ;0,1,2=177,3=90.000000
L 5.55706663 2.1912498 5.55913287 2.18856634 1 P 0 ;0,1,2=177,3=90.000000
L 5.55913287 2.18856634 5.55964941 2.18588356 1 P 0 ;0,1,2=177,3=90.000000
L 5.55964941 2.18588356 5.55913287 2.1832001 1 P 0 ;0,1,2=177,3=90.000000
L 5.55913287 2.1832001 5.55706663 2.1797501 1 P 0 ;0,1,2=177,3=90.000000
L 5.55706663 2.1797501 5.5705 2.1808999 1 P 0 ;0,1,2=177,3=90.000000
L 5.5705 2.1808999 5.5705 2.1912498 1 P 0 ;0,1,2=177,3=90.000000
L 5.5705 2.21649961 5.56946683 2.21343287 1 P 0 ;0,1,2=177,3=90.000000
L 5.56946683 2.21343287 5.56688307 2.21113337 1 P 0 ;0,1,2=177,3=90.000000
L 5.56688307 2.21113337 5.56378376 2.2095997 1 P 0 ;0,1,2=177,3=90.000000
L 5.56378376 2.2095997 5.55964941 2.2084499 1 P 0 ;0,1,2=177,3=90.000000
L 5.55964941 2.2084499 5.55499951 2.20806663 1 P 0 ;0,1,2=177,3=90.000000
L 5.55499951 2.20806663 5.55034951 2.2084499 1 P 0 ;0,1,2=177,3=90.000000
L 5.55034951 2.2084499 5.54621614 2.2095997 1 P 0 ;0,1,2=177,3=90.000000
L 5.54621614 2.2095997 5.54311585 2.21113337 1 P 0 ;0,1,2=177,3=90.000000
L 5.54311585 2.21113337 5.54053307 2.21343287 1 P 0 ;0,1,2=177,3=90.000000
L 5.54053307 2.21343287 5.5395 2.21649961 1 P 0 ;0,1,2=177,3=90.000000
L 5.5395 2.21649961 5.54053307 2.21956634 1 P 0 ;0,1,2=177,3=90.000000
L 5.54053307 2.21956634 5.54311585 2.22186654 1 P 0 ;0,1,2=177,3=90.000000
L 5.54311585 2.22186654 5.54621614 2.2234002 1 P 0 ;0,1,2=177,3=90.000000
L 5.54621614 2.2234002 5.55034951 2.22455 1 P 0 ;0,1,2=177,3=90.000000
L 5.55034951 2.22455 5.55499951 2.22493327 1 P 0 ;0,1,2=177,3=90.000000
L 5.55499951 2.22493327 5.55964941 2.22455 1 P 0 ;0,1,2=177,3=90.000000
L 5.55964941 2.22455 5.56378376 2.2234002 1 P 0 ;0,1,2=177,3=90.000000
L 5.56378376 2.2234002 5.56688307 2.22186654 1 P 0 ;0,1,2=177,3=90.000000
L 5.56688307 2.22186654 5.56946683 2.21956634 1 P 0 ;0,1,2=177,3=90.000000
L 5.56946683 2.21956634 5.5705 2.21649961 1 P 0 ;0,1,2=177,3=90.000000
L 0.88 2.855 0.88 2.765 1 P 0 
L 0.836 2.855 0.88 2.855 1 P 0 
L 0.836 2.765 0.836 2.855 1 P 0 
L 0.88 2.765 0.836 2.765 1 P 0 
L 0.7995 2.76583317 0.8305 2.76583317 1 P 0 ;0,1,2=178,3=90.000000
L 0.8305 2.76583317 0.8305 2.77541654 1 P 0 ;0,1,2=178,3=90.000000
L 0.8305 2.77541654 0.82894931 2.77848327 1 P 0 ;0,1,2=178,3=90.000000
L 0.82894931 2.77848327 0.82688307 2.7804002 1 P 0 ;0,1,2=178,3=90.000000
L 0.82688307 2.7804002 0.8227497 2.78116673 1 P 0 ;0,1,2=178,3=90.000000
L 0.8227497 2.78116673 0.81861634 2.7804002 1 P 0 ;0,1,2=178,3=90.000000
L 0.81861634 2.7804002 0.81603356 2.7781 1 P 0 ;0,1,2=178,3=90.000000
L 0.81603356 2.7781 0.81448287 2.77541654 1 P 0 ;0,1,2=178,3=90.000000
L 0.81448287 2.77541654 0.81448287 2.76583317 1 P 0 ;0,1,2=178,3=90.000000
L 0.81448287 2.77541654 0.7995 2.78116673 1 P 0 ;0,1,2=178,3=90.000000
L 0.80569961 2.79606663 0.80208278 2.79836614 1 P 0 ;0,1,2=178,3=90.000000
L 0.80208278 2.79836614 0.80001654 2.80143287 1 P 0 ;0,1,2=178,3=90.000000
L 0.80001654 2.80143287 0.7995 2.80488356 1 P 0 ;0,1,2=178,3=90.000000
L 0.7995 2.80488356 0.80001654 2.8079503 1 P 0 ;0,1,2=178,3=90.000000
L 0.80001654 2.8079503 0.80259931 2.81101703 1 P 0 ;0,1,2=178,3=90.000000
L 0.80259931 2.81101703 0.80569961 2.81293327 1 P 0 ;0,1,2=178,3=90.000000
L 0.80569961 2.81293327 0.8087999 2.81331654 1 P 0 ;0,1,2=178,3=90.000000
L 0.8087999 2.81331654 0.81241575 2.81255 1 P 0 ;0,1,2=178,3=90.000000
L 0.81241575 2.81255 0.81499951 2.80986654 1 P 0 ;0,1,2=178,3=90.000000
L 0.81499951 2.80986654 0.81603356 2.80718307 1 P 0 ;0,1,2=178,3=90.000000
L 0.81603356 2.80718307 0.81603356 2.80373307 1 P 0 ;0,1,2=178,3=90.000000
L 0.81603356 2.80718307 0.81758317 2.80948327 1 P 0 ;0,1,2=178,3=90.000000
L 0.81758317 2.80948327 0.82016594 2.8114002 1 P 0 ;0,1,2=178,3=90.000000
L 0.82016594 2.8114002 0.82326624 2.81216673 1 P 0 ;0,1,2=178,3=90.000000
L 0.82326624 2.81216673 0.82636654 2.8114002 1 P 0 ;0,1,2=178,3=90.000000
L 0.82636654 2.8114002 0.82894931 2.80948327 1 P 0 ;0,1,2=178,3=90.000000
L 0.82894931 2.80948327 0.8305 2.80603327 1 P 0 ;0,1,2=178,3=90.000000
L 0.8305 2.80603327 0.82998337 2.80258337 1 P 0 ;0,1,2=178,3=90.000000
L 0.82998337 2.80258337 0.82791624 2.79913337 1 P 0 ;0,1,2=178,3=90.000000
L 0.7995 2.8401 0.8305 2.8401 1 P 0 ;0,1,2=178,3=90.000000
L 0.8305 2.8401 0.80828327 2.82591624 1 P 0 ;0,1,2=178,3=90.000000
L 0.80828327 2.82591624 0.80828327 2.84508366 1 P 0 ;0,1,2=178,3=90.000000
L 0.80569961 2.85806663 0.80208278 2.86036614 1 P 0 ;0,1,2=178,3=90.000000
L 0.80208278 2.86036614 0.80001654 2.86343287 1 P 0 ;0,1,2=178,3=90.000000
L 0.80001654 2.86343287 0.7995 2.86688356 1 P 0 ;0,1,2=178,3=90.000000
L 0.7995 2.86688356 0.80001654 2.8699503 1 P 0 ;0,1,2=178,3=90.000000
L 0.80001654 2.8699503 0.80259931 2.87301703 1 P 0 ;0,1,2=178,3=90.000000
L 0.80259931 2.87301703 0.80569961 2.87493327 1 P 0 ;0,1,2=178,3=90.000000
L 0.80569961 2.87493327 0.8087999 2.87531654 1 P 0 ;0,1,2=178,3=90.000000
L 0.8087999 2.87531654 0.81241575 2.87455 1 P 0 ;0,1,2=178,3=90.000000
L 0.81241575 2.87455 0.81499951 2.87186654 1 P 0 ;0,1,2=178,3=90.000000
L 0.81499951 2.87186654 0.81603356 2.86918307 1 P 0 ;0,1,2=178,3=90.000000
L 0.81603356 2.86918307 0.81603356 2.86573307 1 P 0 ;0,1,2=178,3=90.000000
L 0.81603356 2.86918307 0.81758317 2.87148327 1 P 0 ;0,1,2=178,3=90.000000
L 0.81758317 2.87148327 0.82016594 2.8734002 1 P 0 ;0,1,2=178,3=90.000000
L 0.82016594 2.8734002 0.82326624 2.87416673 1 P 0 ;0,1,2=178,3=90.000000
L 0.82326624 2.87416673 0.82636654 2.8734002 1 P 0 ;0,1,2=178,3=90.000000
L 0.82636654 2.8734002 0.82894931 2.87148327 1 P 0 ;0,1,2=178,3=90.000000
L 0.82894931 2.87148327 0.8305 2.86803327 1 P 0 ;0,1,2=178,3=90.000000
L 0.8305 2.86803327 0.82998337 2.86458337 1 P 0 ;0,1,2=178,3=90.000000
L 0.82998337 2.86458337 0.82791624 2.86113337 1 P 0 ;0,1,2=178,3=90.000000
L 1.401 3.873 1.491 3.873 1 P 0 
L 1.491 3.873 1.491 3.829 1 P 0 
L 1.491 3.829 1.401 3.829 1 P 0 
L 1.401 3.829 1.401 3.873 1 P 0 
L 1.33366683 3.8095 1.33366683 3.8405 1 P 0 ;0,1,2=179,3=0.000000
L 1.33366683 3.8405 1.32408346 3.8405 1 P 0 ;0,1,2=179,3=0.000000
L 1.32408346 3.8405 1.32101673 3.83894931 1 P 0 ;0,1,2=179,3=0.000000
L 1.32101673 3.83894931 1.3190998 3.83688307 1 P 0 ;0,1,2=179,3=0.000000
L 1.3190998 3.83688307 1.31833327 3.8327497 1 P 0 ;0,1,2=179,3=0.000000
L 1.31833327 3.8327497 1.3190998 3.82861634 1 P 0 ;0,1,2=179,3=0.000000
L 1.3190998 3.82861634 1.3214 3.82603356 1 P 0 ;0,1,2=179,3=0.000000
L 1.3214 3.82603356 1.32408346 3.82448287 1 P 0 ;0,1,2=179,3=0.000000
L 1.32408346 3.82448287 1.33366683 3.82448287 1 P 0 ;0,1,2=179,3=0.000000
L 1.32408346 3.82448287 1.31833327 3.8095 1 P 0 ;0,1,2=179,3=0.000000
L 1.2904 3.8095 1.2904 3.8405 1 P 0 ;0,1,2=179,3=0.000000
L 1.2904 3.8405 1.30458376 3.81828327 1 P 0 ;0,1,2=179,3=0.000000
L 1.30458376 3.81828327 1.28541634 3.81828327 1 P 0 ;0,1,2=179,3=0.000000
L 1.26476693 3.8095 1.26400039 3.81621614 1 P 0 ;0,1,2=179,3=0.000000
L 1.26400039 3.81621614 1.2628499 3.82189921 1 P 0 ;0,1,2=179,3=0.000000
L 1.2628499 3.82189921 1.26131693 3.82706663 1 P 0 ;0,1,2=179,3=0.000000
L 1.26131693 3.82706663 1.2594 3.8327497 1 P 0 ;0,1,2=179,3=0.000000
L 1.2594 3.8327497 1.25633327 3.8405 1 P 0 ;0,1,2=179,3=0.000000
L 1.25633327 3.8405 1.27166683 3.8405 1 P 0 ;0,1,2=179,3=0.000000
L 1.606 3.798 1.606 3.754 1 P 0 
L 1.606 3.754 1.516 3.754 1 P 0 
L 1.516 3.754 1.516 3.798 1 P 0 
L 1.516 3.798 1.606 3.798 1 P 0 
L 1.61866683 3.7145 1.61866683 3.7455 1 P 0 ;0,1,2=180,3=0.000000
L 1.61866683 3.7455 1.60908346 3.7455 1 P 0 ;0,1,2=180,3=0.000000
L 1.60908346 3.7455 1.60601673 3.74394931 1 P 0 ;0,1,2=180,3=0.000000
L 1.60601673 3.74394931 1.6040998 3.74188307 1 P 0 ;0,1,2=180,3=0.000000
L 1.6040998 3.74188307 1.60333327 3.7377497 1 P 0 ;0,1,2=180,3=0.000000
L 1.60333327 3.7377497 1.6040998 3.73361634 1 P 0 ;0,1,2=180,3=0.000000
L 1.6040998 3.73361634 1.6064 3.73103356 1 P 0 ;0,1,2=180,3=0.000000
L 1.6064 3.73103356 1.60908346 3.72948287 1 P 0 ;0,1,2=180,3=0.000000
L 1.60908346 3.72948287 1.61866683 3.72948287 1 P 0 ;0,1,2=180,3=0.000000
L 1.60908346 3.72948287 1.60333327 3.7145 1 P 0 ;0,1,2=180,3=0.000000
L 1.5754 3.7145 1.5754 3.7455 1 P 0 ;0,1,2=180,3=0.000000
L 1.5754 3.7455 1.58958376 3.72328327 1 P 0 ;0,1,2=180,3=0.000000
L 1.58958376 3.72328327 1.57041634 3.72328327 1 P 0 ;0,1,2=180,3=0.000000
L 1.55551713 3.71811585 1.55283366 3.71553307 1 P 0 ;0,1,2=180,3=0.000000
L 1.55283366 3.71553307 1.54976693 3.7145 1 P 0 ;0,1,2=180,3=0.000000
L 1.54976693 3.7145 1.5467002 3.71553307 1 P 0 ;0,1,2=180,3=0.000000
L 1.5467002 3.71553307 1.54401673 3.71863238 1 P 0 ;0,1,2=180,3=0.000000
L 1.54401673 3.71863238 1.5420998 3.72328327 1 P 0 ;0,1,2=180,3=0.000000
L 1.5420998 3.72328327 1.54133327 3.72793327 1 P 0 ;0,1,2=180,3=0.000000
L 1.54133327 3.72793327 1.54133327 3.73361634 1 P 0 ;0,1,2=180,3=0.000000
L 1.54133327 3.73361634 1.5420998 3.73826624 1 P 0 ;0,1,2=180,3=0.000000
L 1.5420998 3.73826624 1.54401673 3.7423997 1 P 0 ;0,1,2=180,3=0.000000
L 1.54401673 3.7423997 1.54631693 3.74446683 1 P 0 ;0,1,2=180,3=0.000000
L 1.54631693 3.74446683 1.54900039 3.7455 1 P 0 ;0,1,2=180,3=0.000000
L 1.54900039 3.7455 1.55206713 3.74446683 1 P 0 ;0,1,2=180,3=0.000000
L 1.55206713 3.74446683 1.55436663 3.7423997 1 P 0 ;0,1,2=180,3=0.000000
L 1.55436663 3.7423997 1.5559003 3.7393003 1 P 0 ;0,1,2=180,3=0.000000
L 1.5559003 3.7393003 1.55666683 3.73516594 1 P 0 ;0,1,2=180,3=0.000000
L 1.55666683 3.73516594 1.5559003 3.7315501 1 P 0 ;0,1,2=180,3=0.000000
L 1.5559003 3.7315501 1.55398337 3.72793327 1 P 0 ;0,1,2=180,3=0.000000
L 1.55398337 3.72793327 1.55168317 3.72586604 1 P 0 ;0,1,2=180,3=0.000000
L 1.55168317 3.72586604 1.54900039 3.72534951 1 P 0 ;0,1,2=180,3=0.000000
L 1.54900039 3.72534951 1.54593366 3.72638268 1 P 0 ;0,1,2=180,3=0.000000
L 1.54593366 3.72638268 1.54363346 3.72896634 1 P 0 ;0,1,2=180,3=0.000000
L 1.54363346 3.72896634 1.54133327 3.73361634 1 P 0 ;0,1,2=180,3=0.000000
L 3.605 4.108 3.515 4.108 1 P 0 
L 3.515 4.108 3.515 4.152 1 P 0 
L 3.515 4.152 3.605 4.152 1 P 0 
L 3.605 4.152 3.605 4.108 1 P 0 
L 3.60366683 4.2295 3.60366683 4.2605 1 P 0 ;0,1,2=181,3=0.000000
L 3.60366683 4.2605 3.59408346 4.2605 1 P 0 ;0,1,2=181,3=0.000000
L 3.59408346 4.2605 3.59101673 4.25894931 1 P 0 ;0,1,2=181,3=0.000000
L 3.59101673 4.25894931 3.5890998 4.25688307 1 P 0 ;0,1,2=181,3=0.000000
L 3.5890998 4.25688307 3.58833327 4.2527497 1 P 0 ;0,1,2=181,3=0.000000
L 3.58833327 4.2527497 3.5890998 4.24861634 1 P 0 ;0,1,2=181,3=0.000000
L 3.5890998 4.24861634 3.5914 4.24603356 1 P 0 ;0,1,2=181,3=0.000000
L 3.5914 4.24603356 3.59408346 4.24448287 1 P 0 ;0,1,2=181,3=0.000000
L 3.59408346 4.24448287 3.60366683 4.24448287 1 P 0 ;0,1,2=181,3=0.000000
L 3.59408346 4.24448287 3.58833327 4.2295 1 P 0 ;0,1,2=181,3=0.000000
L 3.57343337 4.23414892 3.57113386 4.23156614 1 P 0 ;0,1,2=181,3=0.000000
L 3.57113386 4.23156614 3.56845039 4.23001654 1 P 0 ;0,1,2=181,3=0.000000
L 3.56845039 4.23001654 3.56500039 4.2295 1 P 0 ;0,1,2=181,3=0.000000
L 3.56500039 4.2295 3.5615497 4.23053307 1 P 0 ;0,1,2=181,3=0.000000
L 3.5615497 4.23053307 3.55886693 4.23259931 1 P 0 ;0,1,2=181,3=0.000000
L 3.55886693 4.23259931 3.55695 4.23621614 1 P 0 ;0,1,2=181,3=0.000000
L 3.55695 4.23621614 3.55656673 4.24034951 1 P 0 ;0,1,2=181,3=0.000000
L 3.55656673 4.24034951 3.55733327 4.24448287 1 P 0 ;0,1,2=181,3=0.000000
L 3.55733327 4.24448287 3.5592502 4.24706663 1 P 0 ;0,1,2=181,3=0.000000
L 3.5592502 4.24706663 3.56193366 4.24913287 1 P 0 ;0,1,2=181,3=0.000000
L 3.56193366 4.24913287 3.56461644 4.24964941 1 P 0 ;0,1,2=181,3=0.000000
L 3.56461644 4.24964941 3.5672999 4.24913287 1 P 0 ;0,1,2=181,3=0.000000
L 3.5672999 4.24913287 3.5707499 4.24706663 1 P 0 ;0,1,2=181,3=0.000000
L 3.5707499 4.24706663 3.5696001 4.2605 1 P 0 ;0,1,2=181,3=0.000000
L 3.5696001 4.2605 3.5592502 4.2605 1 P 0 ;0,1,2=181,3=0.000000
L 3.53400039 4.2295 3.53400039 4.2605 1 P 0 ;0,1,2=181,3=0.000000
L 3.53400039 4.2605 3.5386001 4.2543003 1 P 0 ;0,1,2=181,3=0.000000
L 3.5386001 4.2295 3.52940069 4.2295 1 P 0 ;0,1,2=181,3=0.000000
L 0.973 3.63 1.017 3.63 1 P 0 
L 1.017 3.63 1.017 3.54 1 P 0 
L 1.017 3.54 0.973 3.54 1 P 0 
L 0.973 3.54 0.973 3.63 1 P 0 
L 0.7795 3.62083317 0.8105 3.62083317 1 P 0 ;0,1,2=182,3=90.000000
L 0.8105 3.62083317 0.8105 3.63041654 1 P 0 ;0,1,2=182,3=90.000000
L 0.8105 3.63041654 0.80894931 3.63348327 1 P 0 ;0,1,2=182,3=90.000000
L 0.80894931 3.63348327 0.80688307 3.6354002 1 P 0 ;0,1,2=182,3=90.000000
L 0.80688307 3.6354002 0.8027497 3.63616673 1 P 0 ;0,1,2=182,3=90.000000
L 0.8027497 3.63616673 0.79861634 3.6354002 1 P 0 ;0,1,2=182,3=90.000000
L 0.79861634 3.6354002 0.79603356 3.6331 1 P 0 ;0,1,2=182,3=90.000000
L 0.79603356 3.6331 0.79448287 3.63041654 1 P 0 ;0,1,2=182,3=90.000000
L 0.79448287 3.63041654 0.79448287 3.62083317 1 P 0 ;0,1,2=182,3=90.000000
L 0.79448287 3.63041654 0.7795 3.63616673 1 P 0 ;0,1,2=182,3=90.000000
L 0.7795 3.65949961 0.8105 3.65949961 1 P 0 ;0,1,2=182,3=90.000000
L 0.8105 3.65949961 0.8043003 3.6548999 1 P 0 ;0,1,2=182,3=90.000000
L 0.7795 3.6548999 0.7795 3.66409931 1 P 0 ;0,1,2=182,3=90.000000
L 0.78569961 3.68206663 0.78208278 3.68436614 1 P 0 ;0,1,2=182,3=90.000000
L 0.78208278 3.68436614 0.78001654 3.68743287 1 P 0 ;0,1,2=182,3=90.000000
L 0.78001654 3.68743287 0.7795 3.69088356 1 P 0 ;0,1,2=182,3=90.000000
L 0.7795 3.69088356 0.78001654 3.6939503 1 P 0 ;0,1,2=182,3=90.000000
L 0.78001654 3.6939503 0.78259931 3.69701703 1 P 0 ;0,1,2=182,3=90.000000
L 0.78259931 3.69701703 0.78569961 3.69893327 1 P 0 ;0,1,2=182,3=90.000000
L 0.78569961 3.69893327 0.7887999 3.69931654 1 P 0 ;0,1,2=182,3=90.000000
L 0.7887999 3.69931654 0.79241575 3.69855 1 P 0 ;0,1,2=182,3=90.000000
L 0.79241575 3.69855 0.79499951 3.69586654 1 P 0 ;0,1,2=182,3=90.000000
L 0.79499951 3.69586654 0.79603356 3.69318307 1 P 0 ;0,1,2=182,3=90.000000
L 0.79603356 3.69318307 0.79603356 3.68973307 1 P 0 ;0,1,2=182,3=90.000000
L 0.79603356 3.69318307 0.79758317 3.69548327 1 P 0 ;0,1,2=182,3=90.000000
L 0.79758317 3.69548327 0.80016594 3.6974002 1 P 0 ;0,1,2=182,3=90.000000
L 0.80016594 3.6974002 0.80326624 3.69816673 1 P 0 ;0,1,2=182,3=90.000000
L 0.80326624 3.69816673 0.80636654 3.6974002 1 P 0 ;0,1,2=182,3=90.000000
L 0.80636654 3.6974002 0.80894931 3.69548327 1 P 0 ;0,1,2=182,3=90.000000
L 0.80894931 3.69548327 0.8105 3.69203327 1 P 0 ;0,1,2=182,3=90.000000
L 0.8105 3.69203327 0.80998337 3.68858337 1 P 0 ;0,1,2=182,3=90.000000
L 0.80998337 3.68858337 0.80791624 3.68513337 1 P 0 ;0,1,2=182,3=90.000000
L 0.8105 3.72149961 0.80946683 3.71843287 1 P 0 ;0,1,2=182,3=90.000000
L 0.80946683 3.71843287 0.80688307 3.71613337 1 P 0 ;0,1,2=182,3=90.000000
L 0.80688307 3.71613337 0.80378376 3.7145997 1 P 0 ;0,1,2=182,3=90.000000
L 0.80378376 3.7145997 0.79964941 3.7134499 1 P 0 ;0,1,2=182,3=90.000000
L 0.79964941 3.7134499 0.79499951 3.71306663 1 P 0 ;0,1,2=182,3=90.000000
L 0.79499951 3.71306663 0.79034951 3.7134499 1 P 0 ;0,1,2=182,3=90.000000
L 0.79034951 3.7134499 0.78621614 3.7145997 1 P 0 ;0,1,2=182,3=90.000000
L 0.78621614 3.7145997 0.78311585 3.71613337 1 P 0 ;0,1,2=182,3=90.000000
L 0.78311585 3.71613337 0.78053307 3.71843287 1 P 0 ;0,1,2=182,3=90.000000
L 0.78053307 3.71843287 0.7795 3.72149961 1 P 0 ;0,1,2=182,3=90.000000
L 0.7795 3.72149961 0.78053307 3.72456634 1 P 0 ;0,1,2=182,3=90.000000
L 0.78053307 3.72456634 0.78311585 3.72686654 1 P 0 ;0,1,2=182,3=90.000000
L 0.78311585 3.72686654 0.78621614 3.7284002 1 P 0 ;0,1,2=182,3=90.000000
L 0.78621614 3.7284002 0.79034951 3.72955 1 P 0 ;0,1,2=182,3=90.000000
L 0.79034951 3.72955 0.79499951 3.72993327 1 P 0 ;0,1,2=182,3=90.000000
L 0.79499951 3.72993327 0.79964941 3.72955 1 P 0 ;0,1,2=182,3=90.000000
L 0.79964941 3.72955 0.80378376 3.7284002 1 P 0 ;0,1,2=182,3=90.000000
L 0.80378376 3.7284002 0.80688307 3.72686654 1 P 0 ;0,1,2=182,3=90.000000
L 0.80688307 3.72686654 0.80946683 3.72456634 1 P 0 ;0,1,2=182,3=90.000000
L 0.80946683 3.72456634 0.8105 3.72149961 1 P 0 ;0,1,2=182,3=90.000000
L 5.443 2.39 5.487 2.39 1 P 0 
L 5.487 2.39 5.487 2.3 1 P 0 
L 5.487 2.3 5.443 2.3 1 P 0 
L 5.443 2.3 5.443 2.39 1 P 0 
L 5.4495 2.41583317 5.4805 2.41583317 1 P 0 ;0,1,2=183,3=90.000000
L 5.4805 2.41583317 5.4805 2.42541654 1 P 0 ;0,1,2=183,3=90.000000
L 5.4805 2.42541654 5.47894931 2.42848327 1 P 0 ;0,1,2=183,3=90.000000
L 5.47894931 2.42848327 5.47688307 2.4304002 1 P 0 ;0,1,2=183,3=90.000000
L 5.47688307 2.4304002 5.4727497 2.43116673 1 P 0 ;0,1,2=183,3=90.000000
L 5.4727497 2.43116673 5.46861634 2.4304002 1 P 0 ;0,1,2=183,3=90.000000
L 5.46861634 2.4304002 5.46603356 2.4281 1 P 0 ;0,1,2=183,3=90.000000
L 5.46603356 2.4281 5.46448287 2.42541654 1 P 0 ;0,1,2=183,3=90.000000
L 5.46448287 2.42541654 5.46448287 2.41583317 1 P 0 ;0,1,2=183,3=90.000000
L 5.46448287 2.42541654 5.4495 2.43116673 1 P 0 ;0,1,2=183,3=90.000000
L 5.47533346 2.44721644 5.47843278 2.44951663 1 P 0 ;0,1,2=183,3=90.000000
L 5.47843278 2.44951663 5.47998337 2.4522001 1 P 0 ;0,1,2=183,3=90.000000
L 5.47998337 2.4522001 5.4805 2.45526683 1 P 0 ;0,1,2=183,3=90.000000
L 5.4805 2.45526683 5.47946683 2.4591 1 P 0 ;0,1,2=183,3=90.000000
L 5.47946683 2.4591 5.47688307 2.46178346 1 P 0 ;0,1,2=183,3=90.000000
L 5.47688307 2.46178346 5.47378376 2.46255 1 P 0 ;0,1,2=183,3=90.000000
L 5.47378376 2.46255 5.47068258 2.46216673 1 P 0 ;0,1,2=183,3=90.000000
L 5.47068258 2.46216673 5.4680998 2.46063307 1 P 0 ;0,1,2=183,3=90.000000
L 5.4680998 2.46063307 5.46293327 2.45296663 1 P 0 ;0,1,2=183,3=90.000000
L 5.46293327 2.45296663 5.45931644 2.44951663 1 P 0 ;0,1,2=183,3=90.000000
L 5.45931644 2.44951663 5.45414892 2.44721644 1 P 0 ;0,1,2=183,3=90.000000
L 5.45414892 2.44721644 5.4495 2.4464499 1 P 0 ;0,1,2=183,3=90.000000
L 5.4495 2.4464499 5.4495 2.46255 1 P 0 ;0,1,2=183,3=90.000000
L 5.4495 2.4901 5.4805 2.4901 1 P 0 ;0,1,2=183,3=90.000000
L 5.4805 2.4901 5.45828327 2.47591624 1 P 0 ;0,1,2=183,3=90.000000
L 5.45828327 2.47591624 5.45828327 2.49508366 1 P 0 ;0,1,2=183,3=90.000000
L 5.4495 2.51573307 5.45621614 2.51649961 1 P 0 ;0,1,2=183,3=90.000000
L 5.45621614 2.51649961 5.46189921 2.5176501 1 P 0 ;0,1,2=183,3=90.000000
L 5.46189921 2.5176501 5.46706663 2.51918307 1 P 0 ;0,1,2=183,3=90.000000
L 5.46706663 2.51918307 5.4727497 2.5211 1 P 0 ;0,1,2=183,3=90.000000
L 5.4727497 2.5211 5.4805 2.52416673 1 P 0 ;0,1,2=183,3=90.000000
L 5.4805 2.52416673 5.4805 2.50883317 1 P 0 ;0,1,2=183,3=90.000000
L 4.39 2.997 4.39 2.953 1 P 0 
L 4.3 2.997 4.39 2.997 1 P 0 
L 4.39 2.953 4.3 2.953 1 P 0 
L 4.3 2.953 4.3 2.997 1 P 0 
L 4.31916683 3.0145 4.31916683 3.0455 1 P 0 ;0,1,2=184,3=0.000000
L 4.31916683 3.0455 4.30958346 3.0455 1 P 0 ;0,1,2=184,3=0.000000
L 4.30958346 3.0455 4.30651673 3.04394931 1 P 0 ;0,1,2=184,3=0.000000
L 4.30651673 3.04394931 4.3045998 3.04188307 1 P 0 ;0,1,2=184,3=0.000000
L 4.3045998 3.04188307 4.30383327 3.0377497 1 P 0 ;0,1,2=184,3=0.000000
L 4.30383327 3.0377497 4.3045998 3.03361634 1 P 0 ;0,1,2=184,3=0.000000
L 4.3045998 3.03361634 4.3069 3.03103356 1 P 0 ;0,1,2=184,3=0.000000
L 4.3069 3.03103356 4.30958346 3.02948287 1 P 0 ;0,1,2=184,3=0.000000
L 4.30958346 3.02948287 4.31916683 3.02948287 1 P 0 ;0,1,2=184,3=0.000000
L 4.30958346 3.02948287 4.30383327 3.0145 1 P 0 ;0,1,2=184,3=0.000000
L 4.28778356 3.04033346 4.28548337 3.04343278 1 P 0 ;0,1,2=184,3=0.000000
L 4.28548337 3.04343278 4.2827999 3.04498337 1 P 0 ;0,1,2=184,3=0.000000
L 4.2827999 3.04498337 4.27973317 3.0455 1 P 0 ;0,1,2=184,3=0.000000
L 4.27973317 3.0455 4.2759 3.04446683 1 P 0 ;0,1,2=184,3=0.000000
L 4.2759 3.04446683 4.27321654 3.04188307 1 P 0 ;0,1,2=184,3=0.000000
L 4.27321654 3.04188307 4.27245 3.03878376 1 P 0 ;0,1,2=184,3=0.000000
L 4.27245 3.03878376 4.27283327 3.03568258 1 P 0 ;0,1,2=184,3=0.000000
L 4.27283327 3.03568258 4.27436693 3.0330998 1 P 0 ;0,1,2=184,3=0.000000
L 4.27436693 3.0330998 4.28203337 3.02793327 1 P 0 ;0,1,2=184,3=0.000000
L 4.28203337 3.02793327 4.28548337 3.02431644 1 P 0 ;0,1,2=184,3=0.000000
L 4.28548337 3.02431644 4.28778356 3.01914892 1 P 0 ;0,1,2=184,3=0.000000
L 4.28778356 3.01914892 4.2885501 3.0145 1 P 0 ;0,1,2=184,3=0.000000
L 4.2885501 3.0145 4.27245 3.0145 1 P 0 ;0,1,2=184,3=0.000000
L 4.25601713 3.01811585 4.25333366 3.01553307 1 P 0 ;0,1,2=184,3=0.000000
L 4.25333366 3.01553307 4.25026693 3.0145 1 P 0 ;0,1,2=184,3=0.000000
L 4.25026693 3.0145 4.2472002 3.01553307 1 P 0 ;0,1,2=184,3=0.000000
L 4.2472002 3.01553307 4.24451673 3.01863238 1 P 0 ;0,1,2=184,3=0.000000
L 4.24451673 3.01863238 4.2425998 3.02328327 1 P 0 ;0,1,2=184,3=0.000000
L 4.2425998 3.02328327 4.24183327 3.02793327 1 P 0 ;0,1,2=184,3=0.000000
L 4.24183327 3.02793327 4.24183327 3.03361634 1 P 0 ;0,1,2=184,3=0.000000
L 4.24183327 3.03361634 4.2425998 3.03826624 1 P 0 ;0,1,2=184,3=0.000000
L 4.2425998 3.03826624 4.24451673 3.0423997 1 P 0 ;0,1,2=184,3=0.000000
L 4.24451673 3.0423997 4.24681693 3.04446683 1 P 0 ;0,1,2=184,3=0.000000
L 4.24681693 3.04446683 4.24950039 3.0455 1 P 0 ;0,1,2=184,3=0.000000
L 4.24950039 3.0455 4.25256713 3.04446683 1 P 0 ;0,1,2=184,3=0.000000
L 4.25256713 3.04446683 4.25486663 3.0423997 1 P 0 ;0,1,2=184,3=0.000000
L 4.25486663 3.0423997 4.2564003 3.0393003 1 P 0 ;0,1,2=184,3=0.000000
L 4.2564003 3.0393003 4.25716683 3.03516594 1 P 0 ;0,1,2=184,3=0.000000
L 4.25716683 3.03516594 4.2564003 3.0315501 1 P 0 ;0,1,2=184,3=0.000000
L 4.2564003 3.0315501 4.25448337 3.02793327 1 P 0 ;0,1,2=184,3=0.000000
L 4.25448337 3.02793327 4.25218317 3.02586604 1 P 0 ;0,1,2=184,3=0.000000
L 4.25218317 3.02586604 4.24950039 3.02534951 1 P 0 ;0,1,2=184,3=0.000000
L 4.24950039 3.02534951 4.24643366 3.02638268 1 P 0 ;0,1,2=184,3=0.000000
L 4.24643366 3.02638268 4.24413346 3.02896634 1 P 0 ;0,1,2=184,3=0.000000
L 4.24413346 3.02896634 4.24183327 3.03361634 1 P 0 ;0,1,2=184,3=0.000000
L 4.22693337 3.01914892 4.22463386 3.01656614 1 P 0 ;0,1,2=184,3=0.000000
L 4.22463386 3.01656614 4.22195039 3.01501654 1 P 0 ;0,1,2=184,3=0.000000
L 4.22195039 3.01501654 4.21850039 3.0145 1 P 0 ;0,1,2=184,3=0.000000
L 4.21850039 3.0145 4.2150497 3.01553307 1 P 0 ;0,1,2=184,3=0.000000
L 4.2150497 3.01553307 4.21236693 3.01759931 1 P 0 ;0,1,2=184,3=0.000000
L 4.21236693 3.01759931 4.21045 3.02121614 1 P 0 ;0,1,2=184,3=0.000000
L 4.21045 3.02121614 4.21006673 3.02534951 1 P 0 ;0,1,2=184,3=0.000000
L 4.21006673 3.02534951 4.21083327 3.02948287 1 P 0 ;0,1,2=184,3=0.000000
L 4.21083327 3.02948287 4.2127502 3.03206663 1 P 0 ;0,1,2=184,3=0.000000
L 4.2127502 3.03206663 4.21543366 3.03413287 1 P 0 ;0,1,2=184,3=0.000000
L 4.21543366 3.03413287 4.21811644 3.03464941 1 P 0 ;0,1,2=184,3=0.000000
L 4.21811644 3.03464941 4.2207999 3.03413287 1 P 0 ;0,1,2=184,3=0.000000
L 4.2207999 3.03413287 4.2242499 3.03206663 1 P 0 ;0,1,2=184,3=0.000000
L 4.2242499 3.03206663 4.2231001 3.0455 1 P 0 ;0,1,2=184,3=0.000000
L 4.2231001 3.0455 4.2127502 3.0455 1 P 0 ;0,1,2=184,3=0.000000
L 4.392 1.145 4.392 1.055 1 P 0 
L 4.348 1.145 4.392 1.145 1 P 0 
L 4.392 1.055 4.348 1.055 1 P 0 
L 4.348 1.055 4.348 1.145 1 P 0 
L 4.3545 0.94083317 4.3855 0.94083317 1 P 0 ;0,1,2=185,3=90.000000
L 4.3855 0.94083317 4.3855 0.95041654 1 P 0 ;0,1,2=185,3=90.000000
L 4.3855 0.95041654 4.38394931 0.95348327 1 P 0 ;0,1,2=185,3=90.000000
L 4.38394931 0.95348327 4.38188307 0.9554002 1 P 0 ;0,1,2=185,3=90.000000
L 4.38188307 0.9554002 4.3777497 0.95616673 1 P 0 ;0,1,2=185,3=90.000000
L 4.3777497 0.95616673 4.37361634 0.9554002 1 P 0 ;0,1,2=185,3=90.000000
L 4.37361634 0.9554002 4.37103356 0.9531 1 P 0 ;0,1,2=185,3=90.000000
L 4.37103356 0.9531 4.36948287 0.95041654 1 P 0 ;0,1,2=185,3=90.000000
L 4.36948287 0.95041654 4.36948287 0.94083317 1 P 0 ;0,1,2=185,3=90.000000
L 4.36948287 0.95041654 4.3545 0.95616673 1 P 0 ;0,1,2=185,3=90.000000
L 4.36069961 0.97106663 4.35708278 0.97336614 1 P 0 ;0,1,2=185,3=90.000000
L 4.35708278 0.97336614 4.35501654 0.97643287 1 P 0 ;0,1,2=185,3=90.000000
L 4.35501654 0.97643287 4.3545 0.97988356 1 P 0 ;0,1,2=185,3=90.000000
L 4.3545 0.97988356 4.35501654 0.9829503 1 P 0 ;0,1,2=185,3=90.000000
L 4.35501654 0.9829503 4.35759931 0.98601703 1 P 0 ;0,1,2=185,3=90.000000
L 4.35759931 0.98601703 4.36069961 0.98793327 1 P 0 ;0,1,2=185,3=90.000000
L 4.36069961 0.98793327 4.3637999 0.98831654 1 P 0 ;0,1,2=185,3=90.000000
L 4.3637999 0.98831654 4.36741575 0.98755 1 P 0 ;0,1,2=185,3=90.000000
L 4.36741575 0.98755 4.36999951 0.98486654 1 P 0 ;0,1,2=185,3=90.000000
L 4.36999951 0.98486654 4.37103356 0.98218307 1 P 0 ;0,1,2=185,3=90.000000
L 4.37103356 0.98218307 4.37103356 0.97873307 1 P 0 ;0,1,2=185,3=90.000000
L 4.37103356 0.98218307 4.37258317 0.98448327 1 P 0 ;0,1,2=185,3=90.000000
L 4.37258317 0.98448327 4.37516594 0.9864002 1 P 0 ;0,1,2=185,3=90.000000
L 4.37516594 0.9864002 4.37826624 0.98716673 1 P 0 ;0,1,2=185,3=90.000000
L 4.37826624 0.98716673 4.38136654 0.9864002 1 P 0 ;0,1,2=185,3=90.000000
L 4.38136654 0.9864002 4.38394931 0.98448327 1 P 0 ;0,1,2=185,3=90.000000
L 4.38394931 0.98448327 4.3855 0.98103327 1 P 0 ;0,1,2=185,3=90.000000
L 4.3855 0.98103327 4.38498337 0.97758337 1 P 0 ;0,1,2=185,3=90.000000
L 4.38498337 0.97758337 4.38291624 0.97413337 1 P 0 ;0,1,2=185,3=90.000000
L 4.35914892 1.00206663 4.35656614 1.00436614 1 P 0 ;0,1,2=185,3=90.000000
L 4.35656614 1.00436614 4.35501654 1.00704961 1 P 0 ;0,1,2=185,3=90.000000
L 4.35501654 1.00704961 4.3545 1.01049961 1 P 0 ;0,1,2=185,3=90.000000
L 4.3545 1.01049961 4.35553307 1.0139503 1 P 0 ;0,1,2=185,3=90.000000
L 4.35553307 1.0139503 4.35759931 1.01663307 1 P 0 ;0,1,2=185,3=90.000000
L 4.35759931 1.01663307 4.36121614 1.01855 1 P 0 ;0,1,2=185,3=90.000000
L 4.36121614 1.01855 4.36534951 1.01893327 1 P 0 ;0,1,2=185,3=90.000000
L 4.36534951 1.01893327 4.36948287 1.01816673 1 P 0 ;0,1,2=185,3=90.000000
L 4.36948287 1.01816673 4.37206663 1.0162498 1 P 0 ;0,1,2=185,3=90.000000
L 4.37206663 1.0162498 4.37413287 1.01356634 1 P 0 ;0,1,2=185,3=90.000000
L 4.37413287 1.01356634 4.37464941 1.01088356 1 P 0 ;0,1,2=185,3=90.000000
L 4.37464941 1.01088356 4.37413287 1.0082001 1 P 0 ;0,1,2=185,3=90.000000
L 4.37413287 1.0082001 4.37206663 1.0047501 1 P 0 ;0,1,2=185,3=90.000000
L 4.37206663 1.0047501 4.3855 1.0058999 1 P 0 ;0,1,2=185,3=90.000000
L 4.3855 1.0058999 4.3855 1.0162498 1 P 0 ;0,1,2=185,3=90.000000
L 4.35914892 1.03306663 4.35656614 1.03536614 1 P 0 ;0,1,2=185,3=90.000000
L 4.35656614 1.03536614 4.35501654 1.03804961 1 P 0 ;0,1,2=185,3=90.000000
L 4.35501654 1.03804961 4.3545 1.04149961 1 P 0 ;0,1,2=185,3=90.000000
L 4.3545 1.04149961 4.35553307 1.0449503 1 P 0 ;0,1,2=185,3=90.000000
L 4.35553307 1.0449503 4.35759931 1.04763307 1 P 0 ;0,1,2=185,3=90.000000
L 4.35759931 1.04763307 4.36121614 1.04955 1 P 0 ;0,1,2=185,3=90.000000
L 4.36121614 1.04955 4.36534951 1.04993327 1 P 0 ;0,1,2=185,3=90.000000
L 4.36534951 1.04993327 4.36948287 1.04916673 1 P 0 ;0,1,2=185,3=90.000000
L 4.36948287 1.04916673 4.37206663 1.0472498 1 P 0 ;0,1,2=185,3=90.000000
L 4.37206663 1.0472498 4.37413287 1.04456634 1 P 0 ;0,1,2=185,3=90.000000
L 4.37413287 1.04456634 4.37464941 1.04188356 1 P 0 ;0,1,2=185,3=90.000000
L 4.37464941 1.04188356 4.37413287 1.0392001 1 P 0 ;0,1,2=185,3=90.000000
L 4.37413287 1.0392001 4.37206663 1.0357501 1 P 0 ;0,1,2=185,3=90.000000
L 4.37206663 1.0357501 4.3855 1.0368999 1 P 0 ;0,1,2=185,3=90.000000
L 4.3855 1.0368999 4.3855 1.0472498 1 P 0 ;0,1,2=185,3=90.000000
L 4.393 1.145 4.437 1.145 1 P 0 
L 4.437 1.145 4.437 1.055 1 P 0 
L 4.437 1.055 4.393 1.055 1 P 0 
L 4.393 1.055 4.393 1.145 1 P 0 
L 4.3945 0.94083317 4.4255 0.94083317 1 P 0 ;0,1,2=186,3=90.000000
L 4.4255 0.94083317 4.4255 0.95041654 1 P 0 ;0,1,2=186,3=90.000000
L 4.4255 0.95041654 4.42394931 0.95348327 1 P 0 ;0,1,2=186,3=90.000000
L 4.42394931 0.95348327 4.42188307 0.9554002 1 P 0 ;0,1,2=186,3=90.000000
L 4.42188307 0.9554002 4.4177497 0.95616673 1 P 0 ;0,1,2=186,3=90.000000
L 4.4177497 0.95616673 4.41361634 0.9554002 1 P 0 ;0,1,2=186,3=90.000000
L 4.41361634 0.9554002 4.41103356 0.9531 1 P 0 ;0,1,2=186,3=90.000000
L 4.41103356 0.9531 4.40948287 0.95041654 1 P 0 ;0,1,2=186,3=90.000000
L 4.40948287 0.95041654 4.40948287 0.94083317 1 P 0 ;0,1,2=186,3=90.000000
L 4.40948287 0.95041654 4.3945 0.95616673 1 P 0 ;0,1,2=186,3=90.000000
L 4.40069961 0.97106663 4.39708278 0.97336614 1 P 0 ;0,1,2=186,3=90.000000
L 4.39708278 0.97336614 4.39501654 0.97643287 1 P 0 ;0,1,2=186,3=90.000000
L 4.39501654 0.97643287 4.3945 0.97988356 1 P 0 ;0,1,2=186,3=90.000000
L 4.3945 0.97988356 4.39501654 0.9829503 1 P 0 ;0,1,2=186,3=90.000000
L 4.39501654 0.9829503 4.39759931 0.98601703 1 P 0 ;0,1,2=186,3=90.000000
L 4.39759931 0.98601703 4.40069961 0.98793327 1 P 0 ;0,1,2=186,3=90.000000
L 4.40069961 0.98793327 4.4037999 0.98831654 1 P 0 ;0,1,2=186,3=90.000000
L 4.4037999 0.98831654 4.40741575 0.98755 1 P 0 ;0,1,2=186,3=90.000000
L 4.40741575 0.98755 4.40999951 0.98486654 1 P 0 ;0,1,2=186,3=90.000000
L 4.40999951 0.98486654 4.41103356 0.98218307 1 P 0 ;0,1,2=186,3=90.000000
L 4.41103356 0.98218307 4.41103356 0.97873307 1 P 0 ;0,1,2=186,3=90.000000
L 4.41103356 0.98218307 4.41258317 0.98448327 1 P 0 ;0,1,2=186,3=90.000000
L 4.41258317 0.98448327 4.41516594 0.9864002 1 P 0 ;0,1,2=186,3=90.000000
L 4.41516594 0.9864002 4.41826624 0.98716673 1 P 0 ;0,1,2=186,3=90.000000
L 4.41826624 0.98716673 4.42136654 0.9864002 1 P 0 ;0,1,2=186,3=90.000000
L 4.42136654 0.9864002 4.42394931 0.98448327 1 P 0 ;0,1,2=186,3=90.000000
L 4.42394931 0.98448327 4.4255 0.98103327 1 P 0 ;0,1,2=186,3=90.000000
L 4.4255 0.98103327 4.42498337 0.97758337 1 P 0 ;0,1,2=186,3=90.000000
L 4.42498337 0.97758337 4.42291624 0.97413337 1 P 0 ;0,1,2=186,3=90.000000
L 4.39914892 1.00206663 4.39656614 1.00436614 1 P 0 ;0,1,2=186,3=90.000000
L 4.39656614 1.00436614 4.39501654 1.00704961 1 P 0 ;0,1,2=186,3=90.000000
L 4.39501654 1.00704961 4.3945 1.01049961 1 P 0 ;0,1,2=186,3=90.000000
L 4.3945 1.01049961 4.39553307 1.0139503 1 P 0 ;0,1,2=186,3=90.000000
L 4.39553307 1.0139503 4.39759931 1.01663307 1 P 0 ;0,1,2=186,3=90.000000
L 4.39759931 1.01663307 4.40121614 1.01855 1 P 0 ;0,1,2=186,3=90.000000
L 4.40121614 1.01855 4.40534951 1.01893327 1 P 0 ;0,1,2=186,3=90.000000
L 4.40534951 1.01893327 4.40948287 1.01816673 1 P 0 ;0,1,2=186,3=90.000000
L 4.40948287 1.01816673 4.41206663 1.0162498 1 P 0 ;0,1,2=186,3=90.000000
L 4.41206663 1.0162498 4.41413287 1.01356634 1 P 0 ;0,1,2=186,3=90.000000
L 4.41413287 1.01356634 4.41464941 1.01088356 1 P 0 ;0,1,2=186,3=90.000000
L 4.41464941 1.01088356 4.41413287 1.0082001 1 P 0 ;0,1,2=186,3=90.000000
L 4.41413287 1.0082001 4.41206663 1.0047501 1 P 0 ;0,1,2=186,3=90.000000
L 4.41206663 1.0047501 4.4255 1.0058999 1 P 0 ;0,1,2=186,3=90.000000
L 4.4255 1.0058999 4.4255 1.0162498 1 P 0 ;0,1,2=186,3=90.000000
L 4.3945 1.04149961 4.39501654 1.04418307 1 P 0 ;0,1,2=186,3=90.000000
L 4.39501654 1.04418307 4.39656614 1.0472498 1 P 0 ;0,1,2=186,3=90.000000
L 4.39656614 1.0472498 4.39914892 1.04916673 1 P 0 ;0,1,2=186,3=90.000000
L 4.39914892 1.04916673 4.40276673 1.04993327 1 P 0 ;0,1,2=186,3=90.000000
L 4.40276673 1.04993327 4.40638268 1.04916673 1 P 0 ;0,1,2=186,3=90.000000
L 4.40638268 1.04916673 4.40948287 1.04686654 1 P 0 ;0,1,2=186,3=90.000000
L 4.40948287 1.04686654 4.41103356 1.04341654 1 P 0 ;0,1,2=186,3=90.000000
L 4.41103356 1.04341654 4.41103356 1.03958337 1 P 0 ;0,1,2=186,3=90.000000
L 4.41103356 1.03958337 4.41206663 1.03728317 1 P 0 ;0,1,2=186,3=90.000000
L 4.41206663 1.03728317 4.41464941 1.03536614 1 P 0 ;0,1,2=186,3=90.000000
L 4.41464941 1.03536614 4.41826624 1.0345997 1 P 0 ;0,1,2=186,3=90.000000
L 4.41826624 1.0345997 4.42188307 1.0357501 1 P 0 ;0,1,2=186,3=90.000000
L 4.42188307 1.0357501 4.42446683 1.03843287 1 P 0 ;0,1,2=186,3=90.000000
L 4.42446683 1.03843287 4.4255 1.04149961 1 P 0 ;0,1,2=186,3=90.000000
L 4.4255 1.04149961 4.42446683 1.04456634 1 P 0 ;0,1,2=186,3=90.000000
L 4.42446683 1.04456634 4.42188307 1.0472498 1 P 0 ;0,1,2=186,3=90.000000
L 4.42188307 1.0472498 4.41826624 1.0484002 1 P 0 ;0,1,2=186,3=90.000000
L 4.41826624 1.0484002 4.41464941 1.04763307 1 P 0 ;0,1,2=186,3=90.000000
L 4.41464941 1.04763307 4.41206663 1.04571673 1 P 0 ;0,1,2=186,3=90.000000
L 4.41206663 1.04571673 4.41103356 1.04341654 1 P 0 ;0,1,2=186,3=90.000000
L 4.41103356 1.04341654 4.41103356 1.03958337 1 P 0 ;0,1,2=186,3=90.000000
L 4.41103356 1.03958337 4.40948287 1.03613337 1 P 0 ;0,1,2=186,3=90.000000
L 4.40948287 1.03613337 4.40638268 1.03383317 1 P 0 ;0,1,2=186,3=90.000000
L 4.40638268 1.03383317 4.40276673 1.03306663 1 P 0 ;0,1,2=186,3=90.000000
L 4.40276673 1.03306663 4.39914892 1.03383317 1 P 0 ;0,1,2=186,3=90.000000
L 4.39914892 1.03383317 4.39656614 1.0357501 1 P 0 ;0,1,2=186,3=90.000000
L 4.39656614 1.0357501 4.39501654 1.03881683 1 P 0 ;0,1,2=186,3=90.000000
L 4.39501654 1.03881683 4.3945 1.04149961 1 P 0 ;0,1,2=186,3=90.000000
L 0.855 0.977 0.855 0.887 1 P 0 
L 0.811 0.977 0.855 0.977 1 P 0 
L 0.855 0.887 0.811 0.887 1 P 0 
L 0.811 0.887 0.811 0.977 1 P 0 
L 0.8245 1.03083317 0.8555 1.03083317 1 P 0 ;0,1,2=187,3=90.000000
L 0.8555 1.03083317 0.8555 1.04041654 1 P 0 ;0,1,2=187,3=90.000000
L 0.8555 1.04041654 0.85394931 1.04348327 1 P 0 ;0,1,2=187,3=90.000000
L 0.85394931 1.04348327 0.85188307 1.0454002 1 P 0 ;0,1,2=187,3=90.000000
L 0.85188307 1.0454002 0.8477497 1.04616673 1 P 0 ;0,1,2=187,3=90.000000
L 0.8477497 1.04616673 0.84361634 1.0454002 1 P 0 ;0,1,2=187,3=90.000000
L 0.84361634 1.0454002 0.84103356 1.0431 1 P 0 ;0,1,2=187,3=90.000000
L 0.84103356 1.0431 0.83948287 1.04041654 1 P 0 ;0,1,2=187,3=90.000000
L 0.83948287 1.04041654 0.83948287 1.03083317 1 P 0 ;0,1,2=187,3=90.000000
L 0.83948287 1.04041654 0.8245 1.04616673 1 P 0 ;0,1,2=187,3=90.000000
L 0.8245 1.06949961 0.8555 1.06949961 1 P 0 ;0,1,2=187,3=90.000000
L 0.8555 1.06949961 0.8493003 1.0648999 1 P 0 ;0,1,2=187,3=90.000000
L 0.8245 1.0648999 0.8245 1.07409931 1 P 0 ;0,1,2=187,3=90.000000
L 0.83741575 1.09321644 0.84103356 1.0958999 1 P 0 ;0,1,2=187,3=90.000000
L 0.84103356 1.0958999 0.8430998 1.0982001 1 P 0 ;0,1,2=187,3=90.000000
L 0.8430998 1.0982001 0.84413287 1.10126683 1 P 0 ;0,1,2=187,3=90.000000
L 0.84413287 1.10126683 0.8430998 1.1039503 1 P 0 ;0,1,2=187,3=90.000000
L 0.8430998 1.1039503 0.84103356 1.10586654 1 P 0 ;0,1,2=187,3=90.000000
L 0.84103356 1.10586654 0.83793327 1.1074002 1 P 0 ;0,1,2=187,3=90.000000
L 0.83793327 1.1074002 0.83431644 1.10778346 1 P 0 ;0,1,2=187,3=90.000000
L 0.83431644 1.10778346 0.83121614 1.1074002 1 P 0 ;0,1,2=187,3=90.000000
L 0.83121614 1.1074002 0.82811585 1.10586654 1 P 0 ;0,1,2=187,3=90.000000
L 0.82811585 1.10586654 0.82553307 1.10356634 1 P 0 ;0,1,2=187,3=90.000000
L 0.82553307 1.10356634 0.8245 1.10088356 1 P 0 ;0,1,2=187,3=90.000000
L 0.8245 1.10088356 0.82553307 1.09781683 1 P 0 ;0,1,2=187,3=90.000000
L 0.82553307 1.09781683 0.82863238 1.09513337 1 P 0 ;0,1,2=187,3=90.000000
L 0.82863238 1.09513337 0.83328327 1.0935997 1 P 0 ;0,1,2=187,3=90.000000
L 0.83328327 1.0935997 0.8384498 1.09321644 1 P 0 ;0,1,2=187,3=90.000000
L 0.8384498 1.09321644 0.84516594 1.09398287 1 P 0 ;0,1,2=187,3=90.000000
L 0.84516594 1.09398287 0.84878376 1.09513337 1 P 0 ;0,1,2=187,3=90.000000
L 0.84878376 1.09513337 0.8523997 1.09704961 1 P 0 ;0,1,2=187,3=90.000000
L 0.8523997 1.09704961 0.85498337 1.09973307 1 P 0 ;0,1,2=187,3=90.000000
L 0.85498337 1.09973307 0.8555 1.10241654 1 P 0 ;0,1,2=187,3=90.000000
L 0.8555 1.10241654 0.85446683 1.1051 1 P 0 ;0,1,2=187,3=90.000000
L 0.85446683 1.1051 0.85188307 1.10701703 1 P 0 ;0,1,2=187,3=90.000000
L 0.8245 1.13149961 0.8555 1.13149961 1 P 0 ;0,1,2=187,3=90.000000
L 0.8555 1.13149961 0.8493003 1.1268999 1 P 0 ;0,1,2=187,3=90.000000
L 0.8245 1.1268999 0.8245 1.13609931 1 P 0 ;0,1,2=187,3=90.000000
L 0.676 0.977 0.72 0.977 1 P 0 
L 0.72 0.977 0.72 0.887 1 P 0 
L 0.72 0.887 0.676 0.887 1 P 0 
L 0.676 0.887 0.676 0.977 1 P 0 
L 0.6395 0.93083317 0.6705 0.93083317 1 P 0 ;0,1,2=188,3=90.000000
L 0.6705 0.93083317 0.6705 0.94041654 1 P 0 ;0,1,2=188,3=90.000000
L 0.6705 0.94041654 0.66894931 0.94348327 1 P 0 ;0,1,2=188,3=90.000000
L 0.66894931 0.94348327 0.66688307 0.9454002 1 P 0 ;0,1,2=188,3=90.000000
L 0.66688307 0.9454002 0.6627497 0.94616673 1 P 0 ;0,1,2=188,3=90.000000
L 0.6627497 0.94616673 0.65861634 0.9454002 1 P 0 ;0,1,2=188,3=90.000000
L 0.65861634 0.9454002 0.65603356 0.9431 1 P 0 ;0,1,2=188,3=90.000000
L 0.65603356 0.9431 0.65448287 0.94041654 1 P 0 ;0,1,2=188,3=90.000000
L 0.65448287 0.94041654 0.65448287 0.93083317 1 P 0 ;0,1,2=188,3=90.000000
L 0.65448287 0.94041654 0.6395 0.94616673 1 P 0 ;0,1,2=188,3=90.000000
L 0.6395 0.96949961 0.6705 0.96949961 1 P 0 ;0,1,2=188,3=90.000000
L 0.6705 0.96949961 0.6643003 0.9648999 1 P 0 ;0,1,2=188,3=90.000000
L 0.6395 0.9648999 0.6395 0.97409931 1 P 0 ;0,1,2=188,3=90.000000
L 0.65241575 0.99321644 0.65603356 0.9958999 1 P 0 ;0,1,2=188,3=90.000000
L 0.65603356 0.9958999 0.6580998 0.9982001 1 P 0 ;0,1,2=188,3=90.000000
L 0.6580998 0.9982001 0.65913287 1.00126683 1 P 0 ;0,1,2=188,3=90.000000
L 0.65913287 1.00126683 0.6580998 1.0039503 1 P 0 ;0,1,2=188,3=90.000000
L 0.6580998 1.0039503 0.65603356 1.00586654 1 P 0 ;0,1,2=188,3=90.000000
L 0.65603356 1.00586654 0.65293327 1.0074002 1 P 0 ;0,1,2=188,3=90.000000
L 0.65293327 1.0074002 0.64931644 1.00778346 1 P 0 ;0,1,2=188,3=90.000000
L 0.64931644 1.00778346 0.64621614 1.0074002 1 P 0 ;0,1,2=188,3=90.000000
L 0.64621614 1.0074002 0.64311585 1.00586654 1 P 0 ;0,1,2=188,3=90.000000
L 0.64311585 1.00586654 0.64053307 1.00356634 1 P 0 ;0,1,2=188,3=90.000000
L 0.64053307 1.00356634 0.6395 1.00088356 1 P 0 ;0,1,2=188,3=90.000000
L 0.6395 1.00088356 0.64053307 0.99781683 1 P 0 ;0,1,2=188,3=90.000000
L 0.64053307 0.99781683 0.64363238 0.99513337 1 P 0 ;0,1,2=188,3=90.000000
L 0.64363238 0.99513337 0.64828327 0.9935997 1 P 0 ;0,1,2=188,3=90.000000
L 0.64828327 0.9935997 0.6534498 0.99321644 1 P 0 ;0,1,2=188,3=90.000000
L 0.6534498 0.99321644 0.66016594 0.99398287 1 P 0 ;0,1,2=188,3=90.000000
L 0.66016594 0.99398287 0.66378376 0.99513337 1 P 0 ;0,1,2=188,3=90.000000
L 0.66378376 0.99513337 0.6673997 0.99704961 1 P 0 ;0,1,2=188,3=90.000000
L 0.6673997 0.99704961 0.66998337 0.99973307 1 P 0 ;0,1,2=188,3=90.000000
L 0.66998337 0.99973307 0.6705 1.00241654 1 P 0 ;0,1,2=188,3=90.000000
L 0.6705 1.00241654 0.66946683 1.0051 1 P 0 ;0,1,2=188,3=90.000000
L 0.66946683 1.0051 0.66688307 1.00701703 1 P 0 ;0,1,2=188,3=90.000000
L 0.64569961 1.02306663 0.64208278 1.02536614 1 P 0 ;0,1,2=188,3=90.000000
L 0.64208278 1.02536614 0.64001654 1.02843287 1 P 0 ;0,1,2=188,3=90.000000
L 0.64001654 1.02843287 0.6395 1.03188356 1 P 0 ;0,1,2=188,3=90.000000
L 0.6395 1.03188356 0.64001654 1.0349503 1 P 0 ;0,1,2=188,3=90.000000
L 0.64001654 1.0349503 0.64259931 1.03801703 1 P 0 ;0,1,2=188,3=90.000000
L 0.64259931 1.03801703 0.64569961 1.03993327 1 P 0 ;0,1,2=188,3=90.000000
L 0.64569961 1.03993327 0.6487999 1.04031654 1 P 0 ;0,1,2=188,3=90.000000
L 0.6487999 1.04031654 0.65241575 1.03955 1 P 0 ;0,1,2=188,3=90.000000
L 0.65241575 1.03955 0.65499951 1.03686654 1 P 0 ;0,1,2=188,3=90.000000
L 0.65499951 1.03686654 0.65603356 1.03418307 1 P 0 ;0,1,2=188,3=90.000000
L 0.65603356 1.03418307 0.65603356 1.03073307 1 P 0 ;0,1,2=188,3=90.000000
L 0.65603356 1.03418307 0.65758317 1.03648327 1 P 0 ;0,1,2=188,3=90.000000
L 0.65758317 1.03648327 0.66016594 1.0384002 1 P 0 ;0,1,2=188,3=90.000000
L 0.66016594 1.0384002 0.66326624 1.03916673 1 P 0 ;0,1,2=188,3=90.000000
L 0.66326624 1.03916673 0.66636654 1.0384002 1 P 0 ;0,1,2=188,3=90.000000
L 0.66636654 1.0384002 0.66894931 1.03648327 1 P 0 ;0,1,2=188,3=90.000000
L 0.66894931 1.03648327 0.6705 1.03303327 1 P 0 ;0,1,2=188,3=90.000000
L 0.6705 1.03303327 0.66998337 1.02958337 1 P 0 ;0,1,2=188,3=90.000000
L 0.66998337 1.02958337 0.66791624 1.02613337 1 P 0 ;0,1,2=188,3=90.000000
L 3.897 2.576 3.941 2.576 1 P 0 
L 3.941 2.576 3.941 2.486 1 P 0 
L 3.941 2.486 3.897 2.486 1 P 0 
L 3.897 2.486 3.897 2.576 1 P 0 
L 3.9095 2.61083317 3.9405 2.61083317 1 P 0 ;0,1,2=189,3=90.000000
L 3.9405 2.61083317 3.9405 2.62041654 1 P 0 ;0,1,2=189,3=90.000000
L 3.9405 2.62041654 3.93894931 2.62348327 1 P 0 ;0,1,2=189,3=90.000000
L 3.93894931 2.62348327 3.93688307 2.6254002 1 P 0 ;0,1,2=189,3=90.000000
L 3.93688307 2.6254002 3.9327497 2.62616673 1 P 0 ;0,1,2=189,3=90.000000
L 3.9327497 2.62616673 3.92861634 2.6254002 1 P 0 ;0,1,2=189,3=90.000000
L 3.92861634 2.6254002 3.92603356 2.6231 1 P 0 ;0,1,2=189,3=90.000000
L 3.92603356 2.6231 3.92448287 2.62041654 1 P 0 ;0,1,2=189,3=90.000000
L 3.92448287 2.62041654 3.92448287 2.61083317 1 P 0 ;0,1,2=189,3=90.000000
L 3.92448287 2.62041654 3.9095 2.62616673 1 P 0 ;0,1,2=189,3=90.000000
L 3.9095 2.64949961 3.9405 2.64949961 1 P 0 ;0,1,2=189,3=90.000000
L 3.9405 2.64949961 3.9343003 2.6448999 1 P 0 ;0,1,2=189,3=90.000000
L 3.9095 2.6448999 3.9095 2.65409931 1 P 0 ;0,1,2=189,3=90.000000
L 3.9095 2.67973307 3.91621614 2.68049961 1 P 0 ;0,1,2=189,3=90.000000
L 3.91621614 2.68049961 3.92189921 2.6816501 1 P 0 ;0,1,2=189,3=90.000000
L 3.92189921 2.6816501 3.92706663 2.68318307 1 P 0 ;0,1,2=189,3=90.000000
L 3.92706663 2.68318307 3.9327497 2.6851 1 P 0 ;0,1,2=189,3=90.000000
L 3.9327497 2.6851 3.9405 2.68816673 1 P 0 ;0,1,2=189,3=90.000000
L 3.9405 2.68816673 3.9405 2.67283317 1 P 0 ;0,1,2=189,3=90.000000
L 3.91569961 2.70306663 3.91208278 2.70536614 1 P 0 ;0,1,2=189,3=90.000000
L 3.91208278 2.70536614 3.91001654 2.70843287 1 P 0 ;0,1,2=189,3=90.000000
L 3.91001654 2.70843287 3.9095 2.71188356 1 P 0 ;0,1,2=189,3=90.000000
L 3.9095 2.71188356 3.91001654 2.7149503 1 P 0 ;0,1,2=189,3=90.000000
L 3.91001654 2.7149503 3.91259931 2.71801703 1 P 0 ;0,1,2=189,3=90.000000
L 3.91259931 2.71801703 3.91569961 2.71993327 1 P 0 ;0,1,2=189,3=90.000000
L 3.91569961 2.71993327 3.9187999 2.72031654 1 P 0 ;0,1,2=189,3=90.000000
L 3.9187999 2.72031654 3.92241575 2.71955 1 P 0 ;0,1,2=189,3=90.000000
L 3.92241575 2.71955 3.92499951 2.71686654 1 P 0 ;0,1,2=189,3=90.000000
L 3.92499951 2.71686654 3.92603356 2.71418307 1 P 0 ;0,1,2=189,3=90.000000
L 3.92603356 2.71418307 3.92603356 2.71073307 1 P 0 ;0,1,2=189,3=90.000000
L 3.92603356 2.71418307 3.92758317 2.71648327 1 P 0 ;0,1,2=189,3=90.000000
L 3.92758317 2.71648327 3.93016594 2.7184002 1 P 0 ;0,1,2=189,3=90.000000
L 3.93016594 2.7184002 3.93326624 2.71916673 1 P 0 ;0,1,2=189,3=90.000000
L 3.93326624 2.71916673 3.93636654 2.7184002 1 P 0 ;0,1,2=189,3=90.000000
L 3.93636654 2.7184002 3.93894931 2.71648327 1 P 0 ;0,1,2=189,3=90.000000
L 3.93894931 2.71648327 3.9405 2.71303327 1 P 0 ;0,1,2=189,3=90.000000
L 3.9405 2.71303327 3.93998337 2.70958337 1 P 0 ;0,1,2=189,3=90.000000
L 3.93998337 2.70958337 3.93791624 2.70613337 1 P 0 ;0,1,2=189,3=90.000000
L 0.508 0.631 0.508 0.721 1 P 0 
L 0.508 0.721 0.552 0.721 1 P 0 
L 0.552 0.721 0.552 0.631 1 P 0 
L 0.552 0.631 0.508 0.631 1 P 0 
L 0.5275 0.72666654 0.5525 0.72666654 1 P 0 ;0,1,2=190,3=90.000000
L 0.5525 0.72666654 0.5525 0.73333327 1 P 0 ;0,1,2=190,3=90.000000
L 0.5525 0.73333327 0.55124941 0.73546663 1 P 0 ;0,1,2=190,3=90.000000
L 0.55124941 0.73546663 0.54958317 0.7368001 1 P 0 ;0,1,2=190,3=90.000000
L 0.54958317 0.7368001 0.5462498 0.73733337 1 P 0 ;0,1,2=190,3=90.000000
L 0.5462498 0.73733337 0.54291634 0.7368001 1 P 0 ;0,1,2=190,3=90.000000
L 0.54291634 0.7368001 0.54083346 0.7352 1 P 0 ;0,1,2=190,3=90.000000
L 0.54083346 0.7352 0.53958297 0.73333327 1 P 0 ;0,1,2=190,3=90.000000
L 0.53958297 0.73333327 0.53958297 0.72666654 1 P 0 ;0,1,2=190,3=90.000000
L 0.53958297 0.73333327 0.5275 0.73733337 1 P 0 ;0,1,2=190,3=90.000000
L 0.5275 0.7539997 0.5525 0.7539997 1 P 0 ;0,1,2=190,3=90.000000
L 0.5525 0.7539997 0.5475003 0.7507999 1 P 0 ;0,1,2=190,3=90.000000
L 0.5275 0.7507999 0.5275 0.75719951 1 P 0 ;0,1,2=190,3=90.000000
L 0.54833337 0.77093317 0.55083287 0.77253327 1 P 0 ;0,1,2=190,3=90.000000
L 0.55083287 0.77253327 0.55208337 0.7744 1 P 0 ;0,1,2=190,3=90.000000
L 0.55208337 0.7744 0.5525 0.77653337 1 P 0 ;0,1,2=190,3=90.000000
L 0.5525 0.77653337 0.55166683 0.7792 1 P 0 ;0,1,2=190,3=90.000000
L 0.55166683 0.7792 0.54958317 0.78106673 1 P 0 ;0,1,2=190,3=90.000000
L 0.54958317 0.78106673 0.54708366 0.7816 1 P 0 ;0,1,2=190,3=90.000000
L 0.54708366 0.7816 0.54458268 0.78133337 1 P 0 ;0,1,2=190,3=90.000000
L 0.54458268 0.78133337 0.5424998 0.78026644 1 P 0 ;0,1,2=190,3=90.000000
L 0.5424998 0.78026644 0.53833327 0.77493327 1 P 0 ;0,1,2=190,3=90.000000
L 0.53833327 0.77493327 0.53541644 0.77253327 1 P 0 ;0,1,2=190,3=90.000000
L 0.53541644 0.77253327 0.53124911 0.77093317 1 P 0 ;0,1,2=190,3=90.000000
L 0.53124911 0.77093317 0.5275 0.7703999 1 P 0 ;0,1,2=190,3=90.000000
L 0.5275 0.7703999 0.5275 0.7816 1 P 0 ;0,1,2=190,3=90.000000
L 0.53249961 0.79213327 0.52958287 0.79373297 1 P 0 ;0,1,2=190,3=90.000000
L 0.52958287 0.79373297 0.52791654 0.79586634 1 P 0 ;0,1,2=190,3=90.000000
L 0.52791654 0.79586634 0.5275 0.79826683 1 P 0 ;0,1,2=190,3=90.000000
L 0.5275 0.79826683 0.52791654 0.8004002 1 P 0 ;0,1,2=190,3=90.000000
L 0.52791654 0.8004002 0.52999941 0.80253356 1 P 0 ;0,1,2=190,3=90.000000
L 0.52999941 0.80253356 0.53249961 0.80386663 1 P 0 ;0,1,2=190,3=90.000000
L 0.53249961 0.80386663 0.5349999 0.80413317 1 P 0 ;0,1,2=190,3=90.000000
L 0.5349999 0.80413317 0.53791594 0.8036 1 P 0 ;0,1,2=190,3=90.000000
L 0.53791594 0.8036 0.53999961 0.80173327 1 P 0 ;0,1,2=190,3=90.000000
L 0.53999961 0.80173327 0.54083346 0.79986644 1 P 0 ;0,1,2=190,3=90.000000
L 0.54083346 0.79986644 0.54083346 0.79746654 1 P 0 ;0,1,2=190,3=90.000000
L 0.54083346 0.79986644 0.54208327 0.80146663 1 P 0 ;0,1,2=190,3=90.000000
L 0.54208327 0.80146663 0.54416614 0.8028001 1 P 0 ;0,1,2=190,3=90.000000
L 0.54416614 0.8028001 0.54666634 0.80333337 1 P 0 ;0,1,2=190,3=90.000000
L 0.54666634 0.80333337 0.54916654 0.8028001 1 P 0 ;0,1,2=190,3=90.000000
L 0.54916654 0.8028001 0.55124941 0.80146663 1 P 0 ;0,1,2=190,3=90.000000
L 0.55124941 0.80146663 0.5525 0.79906663 1 P 0 ;0,1,2=190,3=90.000000
L 0.5525 0.79906663 0.55208337 0.79666663 1 P 0 ;0,1,2=190,3=90.000000
L 0.55208337 0.79666663 0.55041634 0.79426663 1 P 0 ;0,1,2=190,3=90.000000
L 5.776 2.39 5.776 2.3 1 P 0 
L 5.732 2.39 5.776 2.39 1 P 0 
L 5.776 2.3 5.732 2.3 1 P 0 
L 5.732 2.3 5.732 2.39 1 P 0 
L 5.8495 2.32583317 5.8805 2.32583317 1 P 0 ;0,1,2=191,3=90.000000
L 5.8805 2.32583317 5.8805 2.33541654 1 P 0 ;0,1,2=191,3=90.000000
L 5.8805 2.33541654 5.87894931 2.33848327 1 P 0 ;0,1,2=191,3=90.000000
L 5.87894931 2.33848327 5.87688307 2.3404002 1 P 0 ;0,1,2=191,3=90.000000
L 5.87688307 2.3404002 5.8727497 2.34116673 1 P 0 ;0,1,2=191,3=90.000000
L 5.8727497 2.34116673 5.86861634 2.3404002 1 P 0 ;0,1,2=191,3=90.000000
L 5.86861634 2.3404002 5.86603356 2.3381 1 P 0 ;0,1,2=191,3=90.000000
L 5.86603356 2.3381 5.86448287 2.33541654 1 P 0 ;0,1,2=191,3=90.000000
L 5.86448287 2.33541654 5.86448287 2.32583317 1 P 0 ;0,1,2=191,3=90.000000
L 5.86448287 2.33541654 5.8495 2.34116673 1 P 0 ;0,1,2=191,3=90.000000
L 5.87533346 2.35721644 5.87843278 2.35951663 1 P 0 ;0,1,2=191,3=90.000000
L 5.87843278 2.35951663 5.87998337 2.3622001 1 P 0 ;0,1,2=191,3=90.000000
L 5.87998337 2.3622001 5.8805 2.36526683 1 P 0 ;0,1,2=191,3=90.000000
L 5.8805 2.36526683 5.87946683 2.3691 1 P 0 ;0,1,2=191,3=90.000000
L 5.87946683 2.3691 5.87688307 2.37178346 1 P 0 ;0,1,2=191,3=90.000000
L 5.87688307 2.37178346 5.87378376 2.37255 1 P 0 ;0,1,2=191,3=90.000000
L 5.87378376 2.37255 5.87068258 2.37216673 1 P 0 ;0,1,2=191,3=90.000000
L 5.87068258 2.37216673 5.8680998 2.37063307 1 P 0 ;0,1,2=191,3=90.000000
L 5.8680998 2.37063307 5.86293327 2.36296663 1 P 0 ;0,1,2=191,3=90.000000
L 5.86293327 2.36296663 5.85931644 2.35951663 1 P 0 ;0,1,2=191,3=90.000000
L 5.85931644 2.35951663 5.85414892 2.35721644 1 P 0 ;0,1,2=191,3=90.000000
L 5.85414892 2.35721644 5.8495 2.3564499 1 P 0 ;0,1,2=191,3=90.000000
L 5.8495 2.3564499 5.8495 2.37255 1 P 0 ;0,1,2=191,3=90.000000
L 5.85414892 2.38706663 5.85156614 2.38936614 1 P 0 ;0,1,2=191,3=90.000000
L 5.85156614 2.38936614 5.85001654 2.39204961 1 P 0 ;0,1,2=191,3=90.000000
L 5.85001654 2.39204961 5.8495 2.39549961 1 P 0 ;0,1,2=191,3=90.000000
L 5.8495 2.39549961 5.85053307 2.3989503 1 P 0 ;0,1,2=191,3=90.000000
L 5.85053307 2.3989503 5.85259931 2.40163307 1 P 0 ;0,1,2=191,3=90.000000
L 5.85259931 2.40163307 5.85621614 2.40355 1 P 0 ;0,1,2=191,3=90.000000
L 5.85621614 2.40355 5.86034951 2.40393327 1 P 0 ;0,1,2=191,3=90.000000
L 5.86034951 2.40393327 5.86448287 2.40316673 1 P 0 ;0,1,2=191,3=90.000000
L 5.86448287 2.40316673 5.86706663 2.4012498 1 P 0 ;0,1,2=191,3=90.000000
L 5.86706663 2.4012498 5.86913287 2.39856634 1 P 0 ;0,1,2=191,3=90.000000
L 5.86913287 2.39856634 5.86964941 2.39588356 1 P 0 ;0,1,2=191,3=90.000000
L 5.86964941 2.39588356 5.86913287 2.3932001 1 P 0 ;0,1,2=191,3=90.000000
L 5.86913287 2.3932001 5.86706663 2.3897501 1 P 0 ;0,1,2=191,3=90.000000
L 5.86706663 2.3897501 5.8805 2.3908999 1 P 0 ;0,1,2=191,3=90.000000
L 5.8805 2.3908999 5.8805 2.4012498 1 P 0 ;0,1,2=191,3=90.000000
L 5.8495 2.42649961 5.8805 2.42649961 1 P 0 ;0,1,2=191,3=90.000000
L 5.8805 2.42649961 5.8743003 2.4218999 1 P 0 ;0,1,2=191,3=90.000000
L 5.8495 2.4218999 5.8495 2.43109931 1 P 0 ;0,1,2=191,3=90.000000
L 0.742 1.621 0.742 1.577 1 P 0 
L 0.652 1.621 0.742 1.621 1 P 0 
L 0.742 1.577 0.652 1.577 1 P 0 
L 0.652 1.577 0.652 1.621 1 P 0 
L 0.73416683 1.6295 0.73416683 1.6605 1 P 0 ;0,1,2=192,3=0.000000
L 0.73416683 1.6605 0.72458346 1.6605 1 P 0 ;0,1,2=192,3=0.000000
L 0.72458346 1.6605 0.72151673 1.65894931 1 P 0 ;0,1,2=192,3=0.000000
L 0.72151673 1.65894931 0.7195998 1.65688307 1 P 0 ;0,1,2=192,3=0.000000
L 0.7195998 1.65688307 0.71883327 1.6527497 1 P 0 ;0,1,2=192,3=0.000000
L 0.71883327 1.6527497 0.7195998 1.64861634 1 P 0 ;0,1,2=192,3=0.000000
L 0.7195998 1.64861634 0.7219 1.64603356 1 P 0 ;0,1,2=192,3=0.000000
L 0.7219 1.64603356 0.72458346 1.64448287 1 P 0 ;0,1,2=192,3=0.000000
L 0.72458346 1.64448287 0.73416683 1.64448287 1 P 0 ;0,1,2=192,3=0.000000
L 0.72458346 1.64448287 0.71883327 1.6295 1 P 0 ;0,1,2=192,3=0.000000
L 0.69550039 1.6295 0.69550039 1.6605 1 P 0 ;0,1,2=192,3=0.000000
L 0.69550039 1.6605 0.7001001 1.6543003 1 P 0 ;0,1,2=192,3=0.000000
L 0.7001001 1.6295 0.69090069 1.6295 1 P 0 ;0,1,2=192,3=0.000000
L 0.6599 1.6295 0.6599 1.6605 1 P 0 ;0,1,2=192,3=0.000000
L 0.6599 1.6605 0.67408376 1.63828327 1 P 0 ;0,1,2=192,3=0.000000
L 0.67408376 1.63828327 0.65491634 1.63828327 1 P 0 ;0,1,2=192,3=0.000000
L 0.6289 1.6295 0.6289 1.6605 1 P 0 ;0,1,2=192,3=0.000000
L 0.6289 1.6605 0.64308376 1.63828327 1 P 0 ;0,1,2=192,3=0.000000
L 0.64308376 1.63828327 0.62391634 1.63828327 1 P 0 ;0,1,2=192,3=0.000000
L 0.874 1.571 0.874 1.527 1 P 0 
L 0.874 1.527 0.784 1.527 1 P 0 
L 0.784 1.527 0.784 1.571 1 P 0 
L 0.784 1.571 0.874 1.571 1 P 0 
L 0.86916683 1.3495 0.86916683 1.3805 1 P 0 ;0,1,2=193,3=0.000000
L 0.86916683 1.3805 0.85958346 1.3805 1 P 0 ;0,1,2=193,3=0.000000
L 0.85958346 1.3805 0.85651673 1.37894931 1 P 0 ;0,1,2=193,3=0.000000
L 0.85651673 1.37894931 0.8545998 1.37688307 1 P 0 ;0,1,2=193,3=0.000000
L 0.8545998 1.37688307 0.85383327 1.3727497 1 P 0 ;0,1,2=193,3=0.000000
L 0.85383327 1.3727497 0.8545998 1.36861634 1 P 0 ;0,1,2=193,3=0.000000
L 0.8545998 1.36861634 0.8569 1.36603356 1 P 0 ;0,1,2=193,3=0.000000
L 0.8569 1.36603356 0.85958346 1.36448287 1 P 0 ;0,1,2=193,3=0.000000
L 0.85958346 1.36448287 0.86916683 1.36448287 1 P 0 ;0,1,2=193,3=0.000000
L 0.85958346 1.36448287 0.85383327 1.3495 1 P 0 ;0,1,2=193,3=0.000000
L 0.83050039 1.3495 0.83050039 1.3805 1 P 0 ;0,1,2=193,3=0.000000
L 0.83050039 1.3805 0.8351001 1.3743003 1 P 0 ;0,1,2=193,3=0.000000
L 0.8351001 1.3495 0.82590069 1.3495 1 P 0 ;0,1,2=193,3=0.000000
L 0.7949 1.3495 0.7949 1.3805 1 P 0 ;0,1,2=193,3=0.000000
L 0.7949 1.3805 0.80908376 1.35828327 1 P 0 ;0,1,2=193,3=0.000000
L 0.80908376 1.35828327 0.78991634 1.35828327 1 P 0 ;0,1,2=193,3=0.000000
L 0.76850039 1.3495 0.76581693 1.35001654 1 P 0 ;0,1,2=193,3=0.000000
L 0.76581693 1.35001654 0.7627502 1.35156614 1 P 0 ;0,1,2=193,3=0.000000
L 0.7627502 1.35156614 0.76083327 1.35414892 1 P 0 ;0,1,2=193,3=0.000000
L 0.76083327 1.35414892 0.76006673 1.35776673 1 P 0 ;0,1,2=193,3=0.000000
L 0.76006673 1.35776673 0.76083327 1.36138268 1 P 0 ;0,1,2=193,3=0.000000
L 0.76083327 1.36138268 0.76313346 1.36448287 1 P 0 ;0,1,2=193,3=0.000000
L 0.76313346 1.36448287 0.76658346 1.36603356 1 P 0 ;0,1,2=193,3=0.000000
L 0.76658346 1.36603356 0.77041663 1.36603356 1 P 0 ;0,1,2=193,3=0.000000
L 0.77041663 1.36603356 0.77271683 1.36706663 1 P 0 ;0,1,2=193,3=0.000000
L 0.77271683 1.36706663 0.77463386 1.36964941 1 P 0 ;0,1,2=193,3=0.000000
L 0.77463386 1.36964941 0.7754003 1.37326624 1 P 0 ;0,1,2=193,3=0.000000
L 0.7754003 1.37326624 0.7742499 1.37688307 1 P 0 ;0,1,2=193,3=0.000000
L 0.7742499 1.37688307 0.77156713 1.37946683 1 P 0 ;0,1,2=193,3=0.000000
L 0.77156713 1.37946683 0.76850039 1.3805 1 P 0 ;0,1,2=193,3=0.000000
L 0.76850039 1.3805 0.76543366 1.37946683 1 P 0 ;0,1,2=193,3=0.000000
L 0.76543366 1.37946683 0.7627502 1.37688307 1 P 0 ;0,1,2=193,3=0.000000
L 0.7627502 1.37688307 0.7615998 1.37326624 1 P 0 ;0,1,2=193,3=0.000000
L 0.7615998 1.37326624 0.76236693 1.36964941 1 P 0 ;0,1,2=193,3=0.000000
L 0.76236693 1.36964941 0.76428327 1.36706663 1 P 0 ;0,1,2=193,3=0.000000
L 0.76428327 1.36706663 0.76658346 1.36603356 1 P 0 ;0,1,2=193,3=0.000000
L 0.76658346 1.36603356 0.77041663 1.36603356 1 P 0 ;0,1,2=193,3=0.000000
L 0.77041663 1.36603356 0.77386663 1.36448287 1 P 0 ;0,1,2=193,3=0.000000
L 0.77386663 1.36448287 0.77616683 1.36138268 1 P 0 ;0,1,2=193,3=0.000000
L 0.77616683 1.36138268 0.77693337 1.35776673 1 P 0 ;0,1,2=193,3=0.000000
L 0.77693337 1.35776673 0.77616683 1.35414892 1 P 0 ;0,1,2=193,3=0.000000
L 0.77616683 1.35414892 0.7742499 1.35156614 1 P 0 ;0,1,2=193,3=0.000000
L 0.7742499 1.35156614 0.77118317 1.35001654 1 P 0 ;0,1,2=193,3=0.000000
L 0.77118317 1.35001654 0.76850039 1.3495 1 P 0 ;0,1,2=193,3=0.000000
L 0.74 1.517 0.74 1.473 1 P 0 
L 0.65 1.517 0.74 1.517 1 P 0 
L 0.74 1.473 0.65 1.473 1 P 0 
L 0.65 1.473 0.65 1.517 1 P 0 
L 0.73366683 1.3895 0.73366683 1.4205 1 P 0 ;0,1,2=194,3=0.000000
L 0.73366683 1.4205 0.72408346 1.4205 1 P 0 ;0,1,2=194,3=0.000000
L 0.72408346 1.4205 0.72101673 1.41894931 1 P 0 ;0,1,2=194,3=0.000000
L 0.72101673 1.41894931 0.7190998 1.41688307 1 P 0 ;0,1,2=194,3=0.000000
L 0.7190998 1.41688307 0.71833327 1.4127497 1 P 0 ;0,1,2=194,3=0.000000
L 0.71833327 1.4127497 0.7190998 1.40861634 1 P 0 ;0,1,2=194,3=0.000000
L 0.7190998 1.40861634 0.7214 1.40603356 1 P 0 ;0,1,2=194,3=0.000000
L 0.7214 1.40603356 0.72408346 1.40448287 1 P 0 ;0,1,2=194,3=0.000000
L 0.72408346 1.40448287 0.73366683 1.40448287 1 P 0 ;0,1,2=194,3=0.000000
L 0.72408346 1.40448287 0.71833327 1.3895 1 P 0 ;0,1,2=194,3=0.000000
L 0.70343337 1.39414892 0.70113386 1.39156614 1 P 0 ;0,1,2=194,3=0.000000
L 0.70113386 1.39156614 0.69845039 1.39001654 1 P 0 ;0,1,2=194,3=0.000000
L 0.69845039 1.39001654 0.69500039 1.3895 1 P 0 ;0,1,2=194,3=0.000000
L 0.69500039 1.3895 0.6915497 1.39053307 1 P 0 ;0,1,2=194,3=0.000000
L 0.6915497 1.39053307 0.68886693 1.39259931 1 P 0 ;0,1,2=194,3=0.000000
L 0.68886693 1.39259931 0.68695 1.39621614 1 P 0 ;0,1,2=194,3=0.000000
L 0.68695 1.39621614 0.68656673 1.40034951 1 P 0 ;0,1,2=194,3=0.000000
L 0.68656673 1.40034951 0.68733327 1.40448287 1 P 0 ;0,1,2=194,3=0.000000
L 0.68733327 1.40448287 0.6892502 1.40706663 1 P 0 ;0,1,2=194,3=0.000000
L 0.6892502 1.40706663 0.69193366 1.40913287 1 P 0 ;0,1,2=194,3=0.000000
L 0.69193366 1.40913287 0.69461644 1.40964941 1 P 0 ;0,1,2=194,3=0.000000
L 0.69461644 1.40964941 0.6972999 1.40913287 1 P 0 ;0,1,2=194,3=0.000000
L 0.6972999 1.40913287 0.7007499 1.40706663 1 P 0 ;0,1,2=194,3=0.000000
L 0.7007499 1.40706663 0.6996001 1.4205 1 P 0 ;0,1,2=194,3=0.000000
L 0.6996001 1.4205 0.6892502 1.4205 1 P 0 ;0,1,2=194,3=0.000000
L 0.67051713 1.39311585 0.66783366 1.39053307 1 P 0 ;0,1,2=194,3=0.000000
L 0.66783366 1.39053307 0.66476693 1.3895 1 P 0 ;0,1,2=194,3=0.000000
L 0.66476693 1.3895 0.6617002 1.39053307 1 P 0 ;0,1,2=194,3=0.000000
L 0.6617002 1.39053307 0.65901673 1.39363238 1 P 0 ;0,1,2=194,3=0.000000
L 0.65901673 1.39363238 0.6570998 1.39828327 1 P 0 ;0,1,2=194,3=0.000000
L 0.6570998 1.39828327 0.65633327 1.40293327 1 P 0 ;0,1,2=194,3=0.000000
L 0.65633327 1.40293327 0.65633327 1.40861634 1 P 0 ;0,1,2=194,3=0.000000
L 0.65633327 1.40861634 0.6570998 1.41326624 1 P 0 ;0,1,2=194,3=0.000000
L 0.6570998 1.41326624 0.65901673 1.4173997 1 P 0 ;0,1,2=194,3=0.000000
L 0.65901673 1.4173997 0.66131693 1.41946683 1 P 0 ;0,1,2=194,3=0.000000
L 0.66131693 1.41946683 0.66400039 1.4205 1 P 0 ;0,1,2=194,3=0.000000
L 0.66400039 1.4205 0.66706713 1.41946683 1 P 0 ;0,1,2=194,3=0.000000
L 0.66706713 1.41946683 0.66936663 1.4173997 1 P 0 ;0,1,2=194,3=0.000000
L 0.66936663 1.4173997 0.6709003 1.4143003 1 P 0 ;0,1,2=194,3=0.000000
L 0.6709003 1.4143003 0.67166683 1.41016594 1 P 0 ;0,1,2=194,3=0.000000
L 0.67166683 1.41016594 0.6709003 1.4065501 1 P 0 ;0,1,2=194,3=0.000000
L 0.6709003 1.4065501 0.66898337 1.40293327 1 P 0 ;0,1,2=194,3=0.000000
L 0.66898337 1.40293327 0.66668317 1.40086604 1 P 0 ;0,1,2=194,3=0.000000
L 0.66668317 1.40086604 0.66400039 1.40034951 1 P 0 ;0,1,2=194,3=0.000000
L 0.66400039 1.40034951 0.66093366 1.40138268 1 P 0 ;0,1,2=194,3=0.000000
L 0.66093366 1.40138268 0.65863346 1.40396634 1 P 0 ;0,1,2=194,3=0.000000
L 0.65863346 1.40396634 0.65633327 1.40861634 1 P 0 ;0,1,2=194,3=0.000000
L 0.87 1.522 0.87 1.478 1 P 0 
L 0.87 1.478 0.78 1.478 1 P 0 
L 0.78 1.478 0.78 1.522 1 P 0 
L 0.78 1.522 0.87 1.522 1 P 0 
L 0.86866683 1.3095 0.86866683 1.3405 1 P 0 ;0,1,2=195,3=0.000000
L 0.86866683 1.3405 0.85908346 1.3405 1 P 0 ;0,1,2=195,3=0.000000
L 0.85908346 1.3405 0.85601673 1.33894931 1 P 0 ;0,1,2=195,3=0.000000
L 0.85601673 1.33894931 0.8540998 1.33688307 1 P 0 ;0,1,2=195,3=0.000000
L 0.8540998 1.33688307 0.85333327 1.3327497 1 P 0 ;0,1,2=195,3=0.000000
L 0.85333327 1.3327497 0.8540998 1.32861634 1 P 0 ;0,1,2=195,3=0.000000
L 0.8540998 1.32861634 0.8564 1.32603356 1 P 0 ;0,1,2=195,3=0.000000
L 0.8564 1.32603356 0.85908346 1.32448287 1 P 0 ;0,1,2=195,3=0.000000
L 0.85908346 1.32448287 0.86866683 1.32448287 1 P 0 ;0,1,2=195,3=0.000000
L 0.85908346 1.32448287 0.85333327 1.3095 1 P 0 ;0,1,2=195,3=0.000000
L 0.83728356 1.33533346 0.83498337 1.33843278 1 P 0 ;0,1,2=195,3=0.000000
L 0.83498337 1.33843278 0.8322999 1.33998337 1 P 0 ;0,1,2=195,3=0.000000
L 0.8322999 1.33998337 0.82923317 1.3405 1 P 0 ;0,1,2=195,3=0.000000
L 0.82923317 1.3405 0.8254 1.33946683 1 P 0 ;0,1,2=195,3=0.000000
L 0.8254 1.33946683 0.82271654 1.33688307 1 P 0 ;0,1,2=195,3=0.000000
L 0.82271654 1.33688307 0.82195 1.33378376 1 P 0 ;0,1,2=195,3=0.000000
L 0.82195 1.33378376 0.82233327 1.33068258 1 P 0 ;0,1,2=195,3=0.000000
L 0.82233327 1.33068258 0.82386693 1.3280998 1 P 0 ;0,1,2=195,3=0.000000
L 0.82386693 1.3280998 0.83153337 1.32293327 1 P 0 ;0,1,2=195,3=0.000000
L 0.83153337 1.32293327 0.83498337 1.31931644 1 P 0 ;0,1,2=195,3=0.000000
L 0.83498337 1.31931644 0.83728356 1.31414892 1 P 0 ;0,1,2=195,3=0.000000
L 0.83728356 1.31414892 0.8380501 1.3095 1 P 0 ;0,1,2=195,3=0.000000
L 0.8380501 1.3095 0.82195 1.3095 1 P 0 ;0,1,2=195,3=0.000000
L 0.79976693 1.3095 0.79900039 1.31621614 1 P 0 ;0,1,2=195,3=0.000000
L 0.79900039 1.31621614 0.7978499 1.32189921 1 P 0 ;0,1,2=195,3=0.000000
L 0.7978499 1.32189921 0.79631693 1.32706663 1 P 0 ;0,1,2=195,3=0.000000
L 0.79631693 1.32706663 0.7944 1.3327497 1 P 0 ;0,1,2=195,3=0.000000
L 0.7944 1.3327497 0.79133327 1.3405 1 P 0 ;0,1,2=195,3=0.000000
L 0.79133327 1.3405 0.80666683 1.3405 1 P 0 ;0,1,2=195,3=0.000000
L 0.765 2.893 0.675 2.893 1 P 0 
L 0.675 2.893 0.675 2.937 1 P 0 
L 0.675 2.937 0.765 2.937 1 P 0 
L 0.765 2.937 0.765 2.893 1 P 0 
L 0.77416683 2.7695 0.77416683 2.8005 1 P 0 ;0,1,2=196,3=0.000000
L 0.77416683 2.8005 0.76458346 2.8005 1 P 0 ;0,1,2=196,3=0.000000
L 0.76458346 2.8005 0.76151673 2.79894931 1 P 0 ;0,1,2=196,3=0.000000
L 0.76151673 2.79894931 0.7595998 2.79688307 1 P 0 ;0,1,2=196,3=0.000000
L 0.7595998 2.79688307 0.75883327 2.7927497 1 P 0 ;0,1,2=196,3=0.000000
L 0.75883327 2.7927497 0.7595998 2.78861634 1 P 0 ;0,1,2=196,3=0.000000
L 0.7595998 2.78861634 0.7619 2.78603356 1 P 0 ;0,1,2=196,3=0.000000
L 0.7619 2.78603356 0.76458346 2.78448287 1 P 0 ;0,1,2=196,3=0.000000
L 0.76458346 2.78448287 0.77416683 2.78448287 1 P 0 ;0,1,2=196,3=0.000000
L 0.76458346 2.78448287 0.75883327 2.7695 1 P 0 ;0,1,2=196,3=0.000000
L 0.74393337 2.77569961 0.74163386 2.77208278 1 P 0 ;0,1,2=196,3=0.000000
L 0.74163386 2.77208278 0.73856713 2.77001654 1 P 0 ;0,1,2=196,3=0.000000
L 0.73856713 2.77001654 0.73511644 2.7695 1 P 0 ;0,1,2=196,3=0.000000
L 0.73511644 2.7695 0.7320497 2.77001654 1 P 0 ;0,1,2=196,3=0.000000
L 0.7320497 2.77001654 0.72898297 2.77259931 1 P 0 ;0,1,2=196,3=0.000000
L 0.72898297 2.77259931 0.72706673 2.77569961 1 P 0 ;0,1,2=196,3=0.000000
L 0.72706673 2.77569961 0.72668346 2.7787999 1 P 0 ;0,1,2=196,3=0.000000
L 0.72668346 2.7787999 0.72745 2.78241575 1 P 0 ;0,1,2=196,3=0.000000
L 0.72745 2.78241575 0.73013346 2.78499951 1 P 0 ;0,1,2=196,3=0.000000
L 0.73013346 2.78499951 0.73281693 2.78603356 1 P 0 ;0,1,2=196,3=0.000000
L 0.73281693 2.78603356 0.73626693 2.78603356 1 P 0 ;0,1,2=196,3=0.000000
L 0.73281693 2.78603356 0.73051673 2.78758317 1 P 0 ;0,1,2=196,3=0.000000
L 0.73051673 2.78758317 0.7285998 2.79016594 1 P 0 ;0,1,2=196,3=0.000000
L 0.7285998 2.79016594 0.72783327 2.79326624 1 P 0 ;0,1,2=196,3=0.000000
L 0.72783327 2.79326624 0.7285998 2.79636654 1 P 0 ;0,1,2=196,3=0.000000
L 0.7285998 2.79636654 0.73051673 2.79894931 1 P 0 ;0,1,2=196,3=0.000000
L 0.73051673 2.79894931 0.73396673 2.8005 1 P 0 ;0,1,2=196,3=0.000000
L 0.73396673 2.8005 0.73741663 2.79998337 1 P 0 ;0,1,2=196,3=0.000000
L 0.73741663 2.79998337 0.74086663 2.79791624 1 P 0 ;0,1,2=196,3=0.000000
L 0.6999 2.7695 0.6999 2.8005 1 P 0 ;0,1,2=196,3=0.000000
L 0.6999 2.8005 0.71408376 2.77828327 1 P 0 ;0,1,2=196,3=0.000000
L 0.71408376 2.77828327 0.69491634 2.77828327 1 P 0 ;0,1,2=196,3=0.000000
L 0.67350039 2.8005 0.67656713 2.79946683 1 P 0 ;0,1,2=196,3=0.000000
L 0.67656713 2.79946683 0.67886663 2.79688307 1 P 0 ;0,1,2=196,3=0.000000
L 0.67886663 2.79688307 0.6804003 2.79378376 1 P 0 ;0,1,2=196,3=0.000000
L 0.6804003 2.79378376 0.6815501 2.78964941 1 P 0 ;0,1,2=196,3=0.000000
L 0.6815501 2.78964941 0.68193337 2.78499951 1 P 0 ;0,1,2=196,3=0.000000
L 0.68193337 2.78499951 0.6815501 2.78034951 1 P 0 ;0,1,2=196,3=0.000000
L 0.6815501 2.78034951 0.6804003 2.77621614 1 P 0 ;0,1,2=196,3=0.000000
L 0.6804003 2.77621614 0.67886663 2.77311585 1 P 0 ;0,1,2=196,3=0.000000
L 0.67886663 2.77311585 0.67656713 2.77053307 1 P 0 ;0,1,2=196,3=0.000000
L 0.67656713 2.77053307 0.67350039 2.7695 1 P 0 ;0,1,2=196,3=0.000000
L 0.67350039 2.7695 0.67043366 2.77053307 1 P 0 ;0,1,2=196,3=0.000000
L 0.67043366 2.77053307 0.66813346 2.77311585 1 P 0 ;0,1,2=196,3=0.000000
L 0.66813346 2.77311585 0.6665998 2.77621614 1 P 0 ;0,1,2=196,3=0.000000
L 0.6665998 2.77621614 0.66545 2.78034951 1 P 0 ;0,1,2=196,3=0.000000
L 0.66545 2.78034951 0.66506673 2.78499951 1 P 0 ;0,1,2=196,3=0.000000
L 0.66506673 2.78499951 0.66545 2.78964941 1 P 0 ;0,1,2=196,3=0.000000
L 0.66545 2.78964941 0.6665998 2.79378376 1 P 0 ;0,1,2=196,3=0.000000
L 0.6665998 2.79378376 0.66813346 2.79688307 1 P 0 ;0,1,2=196,3=0.000000
L 0.66813346 2.79688307 0.67043366 2.79946683 1 P 0 ;0,1,2=196,3=0.000000
L 0.67043366 2.79946683 0.67350039 2.8005 1 P 0 ;0,1,2=196,3=0.000000
L 0.682 3.08 0.682 2.99 1 P 0 
L 0.638 3.08 0.682 3.08 1 P 0 
L 0.682 2.99 0.638 2.99 1 P 0 
L 0.638 2.99 0.638 3.08 1 P 0 
L 0.7695 2.93583317 0.8005 2.93583317 1 P 0 ;0,1,2=197,3=90.000000
L 0.8005 2.93583317 0.8005 2.94541654 1 P 0 ;0,1,2=197,3=90.000000
L 0.8005 2.94541654 0.79894931 2.94848327 1 P 0 ;0,1,2=197,3=90.000000
L 0.79894931 2.94848327 0.79688307 2.9504002 1 P 0 ;0,1,2=197,3=90.000000
L 0.79688307 2.9504002 0.7927497 2.95116673 1 P 0 ;0,1,2=197,3=90.000000
L 0.7927497 2.95116673 0.78861634 2.9504002 1 P 0 ;0,1,2=197,3=90.000000
L 0.78861634 2.9504002 0.78603356 2.9481 1 P 0 ;0,1,2=197,3=90.000000
L 0.78603356 2.9481 0.78448287 2.94541654 1 P 0 ;0,1,2=197,3=90.000000
L 0.78448287 2.94541654 0.78448287 2.93583317 1 P 0 ;0,1,2=197,3=90.000000
L 0.78448287 2.94541654 0.7695 2.95116673 1 P 0 ;0,1,2=197,3=90.000000
L 0.77569961 2.96606663 0.77208278 2.96836614 1 P 0 ;0,1,2=197,3=90.000000
L 0.77208278 2.96836614 0.77001654 2.97143287 1 P 0 ;0,1,2=197,3=90.000000
L 0.77001654 2.97143287 0.7695 2.97488356 1 P 0 ;0,1,2=197,3=90.000000
L 0.7695 2.97488356 0.77001654 2.9779503 1 P 0 ;0,1,2=197,3=90.000000
L 0.77001654 2.9779503 0.77259931 2.98101703 1 P 0 ;0,1,2=197,3=90.000000
L 0.77259931 2.98101703 0.77569961 2.98293327 1 P 0 ;0,1,2=197,3=90.000000
L 0.77569961 2.98293327 0.7787999 2.98331654 1 P 0 ;0,1,2=197,3=90.000000
L 0.7787999 2.98331654 0.78241575 2.98255 1 P 0 ;0,1,2=197,3=90.000000
L 0.78241575 2.98255 0.78499951 2.97986654 1 P 0 ;0,1,2=197,3=90.000000
L 0.78499951 2.97986654 0.78603356 2.97718307 1 P 0 ;0,1,2=197,3=90.000000
L 0.78603356 2.97718307 0.78603356 2.97373307 1 P 0 ;0,1,2=197,3=90.000000
L 0.78603356 2.97718307 0.78758317 2.97948327 1 P 0 ;0,1,2=197,3=90.000000
L 0.78758317 2.97948327 0.79016594 2.9814002 1 P 0 ;0,1,2=197,3=90.000000
L 0.79016594 2.9814002 0.79326624 2.98216673 1 P 0 ;0,1,2=197,3=90.000000
L 0.79326624 2.98216673 0.79636654 2.9814002 1 P 0 ;0,1,2=197,3=90.000000
L 0.79636654 2.9814002 0.79894931 2.97948327 1 P 0 ;0,1,2=197,3=90.000000
L 0.79894931 2.97948327 0.8005 2.97603327 1 P 0 ;0,1,2=197,3=90.000000
L 0.8005 2.97603327 0.79998337 2.97258337 1 P 0 ;0,1,2=197,3=90.000000
L 0.79998337 2.97258337 0.79791624 2.96913337 1 P 0 ;0,1,2=197,3=90.000000
L 0.77569961 2.99706663 0.77208278 2.99936614 1 P 0 ;0,1,2=197,3=90.000000
L 0.77208278 2.99936614 0.77001654 3.00243287 1 P 0 ;0,1,2=197,3=90.000000
L 0.77001654 3.00243287 0.7695 3.00588356 1 P 0 ;0,1,2=197,3=90.000000
L 0.7695 3.00588356 0.77001654 3.0089503 1 P 0 ;0,1,2=197,3=90.000000
L 0.77001654 3.0089503 0.77259931 3.01201703 1 P 0 ;0,1,2=197,3=90.000000
L 0.77259931 3.01201703 0.77569961 3.01393327 1 P 0 ;0,1,2=197,3=90.000000
L 0.77569961 3.01393327 0.7787999 3.01431654 1 P 0 ;0,1,2=197,3=90.000000
L 0.7787999 3.01431654 0.78241575 3.01355 1 P 0 ;0,1,2=197,3=90.000000
L 0.78241575 3.01355 0.78499951 3.01086654 1 P 0 ;0,1,2=197,3=90.000000
L 0.78499951 3.01086654 0.78603356 3.00818307 1 P 0 ;0,1,2=197,3=90.000000
L 0.78603356 3.00818307 0.78603356 3.00473307 1 P 0 ;0,1,2=197,3=90.000000
L 0.78603356 3.00818307 0.78758317 3.01048327 1 P 0 ;0,1,2=197,3=90.000000
L 0.78758317 3.01048327 0.79016594 3.0124002 1 P 0 ;0,1,2=197,3=90.000000
L 0.79016594 3.0124002 0.79326624 3.01316673 1 P 0 ;0,1,2=197,3=90.000000
L 0.79326624 3.01316673 0.79636654 3.0124002 1 P 0 ;0,1,2=197,3=90.000000
L 0.79636654 3.0124002 0.79894931 3.01048327 1 P 0 ;0,1,2=197,3=90.000000
L 0.79894931 3.01048327 0.8005 3.00703327 1 P 0 ;0,1,2=197,3=90.000000
L 0.8005 3.00703327 0.79998337 3.00358337 1 P 0 ;0,1,2=197,3=90.000000
L 0.79998337 3.00358337 0.79791624 3.00013337 1 P 0 ;0,1,2=197,3=90.000000
L 0.79533346 3.02921644 0.79843278 3.03151663 1 P 0 ;0,1,2=197,3=90.000000
L 0.79843278 3.03151663 0.79998337 3.0342001 1 P 0 ;0,1,2=197,3=90.000000
L 0.79998337 3.0342001 0.8005 3.03726683 1 P 0 ;0,1,2=197,3=90.000000
L 0.8005 3.03726683 0.79946683 3.0411 1 P 0 ;0,1,2=197,3=90.000000
L 0.79946683 3.0411 0.79688307 3.04378346 1 P 0 ;0,1,2=197,3=90.000000
L 0.79688307 3.04378346 0.79378376 3.04455 1 P 0 ;0,1,2=197,3=90.000000
L 0.79378376 3.04455 0.79068258 3.04416673 1 P 0 ;0,1,2=197,3=90.000000
L 0.79068258 3.04416673 0.7880998 3.04263307 1 P 0 ;0,1,2=197,3=90.000000
L 0.7880998 3.04263307 0.78293327 3.03496663 1 P 0 ;0,1,2=197,3=90.000000
L 0.78293327 3.03496663 0.77931644 3.03151663 1 P 0 ;0,1,2=197,3=90.000000
L 0.77931644 3.03151663 0.77414892 3.02921644 1 P 0 ;0,1,2=197,3=90.000000
L 0.77414892 3.02921644 0.7695 3.0284499 1 P 0 ;0,1,2=197,3=90.000000
L 0.7695 3.0284499 0.7695 3.04455 1 P 0 ;0,1,2=197,3=90.000000
L 0.599 0.721 0.599 0.631 1 P 0 
L 0.599 0.631 0.555 0.631 1 P 0 
L 0.555 0.631 0.555 0.721 1 P 0 
L 0.555 0.721 0.599 0.721 1 P 0 
L 0.5625 0.72666654 0.5875 0.72666654 1 P 0 ;0,1,2=198,3=90.000000
L 0.5875 0.72666654 0.5875 0.73333327 1 P 0 ;0,1,2=198,3=90.000000
L 0.5875 0.73333327 0.58624941 0.73546663 1 P 0 ;0,1,2=198,3=90.000000
L 0.58624941 0.73546663 0.58458317 0.7368001 1 P 0 ;0,1,2=198,3=90.000000
L 0.58458317 0.7368001 0.5812498 0.73733337 1 P 0 ;0,1,2=198,3=90.000000
L 0.5812498 0.73733337 0.57791634 0.7368001 1 P 0 ;0,1,2=198,3=90.000000
L 0.57791634 0.7368001 0.57583346 0.7352 1 P 0 ;0,1,2=198,3=90.000000
L 0.57583346 0.7352 0.57458297 0.73333327 1 P 0 ;0,1,2=198,3=90.000000
L 0.57458297 0.73333327 0.57458297 0.72666654 1 P 0 ;0,1,2=198,3=90.000000
L 0.57458297 0.73333327 0.5625 0.73733337 1 P 0 ;0,1,2=198,3=90.000000
L 0.56749961 0.74813327 0.56458287 0.74973297 1 P 0 ;0,1,2=198,3=90.000000
L 0.56458287 0.74973297 0.56291654 0.75186634 1 P 0 ;0,1,2=198,3=90.000000
L 0.56291654 0.75186634 0.5625 0.75426683 1 P 0 ;0,1,2=198,3=90.000000
L 0.5625 0.75426683 0.56291654 0.7564002 1 P 0 ;0,1,2=198,3=90.000000
L 0.56291654 0.7564002 0.56499941 0.75853356 1 P 0 ;0,1,2=198,3=90.000000
L 0.56499941 0.75853356 0.56749961 0.75986663 1 P 0 ;0,1,2=198,3=90.000000
L 0.56749961 0.75986663 0.5699999 0.76013317 1 P 0 ;0,1,2=198,3=90.000000
L 0.5699999 0.76013317 0.57291594 0.7596 1 P 0 ;0,1,2=198,3=90.000000
L 0.57291594 0.7596 0.57499961 0.75773327 1 P 0 ;0,1,2=198,3=90.000000
L 0.57499961 0.75773327 0.57583346 0.75586644 1 P 0 ;0,1,2=198,3=90.000000
L 0.57583346 0.75586644 0.57583346 0.75346654 1 P 0 ;0,1,2=198,3=90.000000
L 0.57583346 0.75586644 0.57708327 0.75746663 1 P 0 ;0,1,2=198,3=90.000000
L 0.57708327 0.75746663 0.57916614 0.7588001 1 P 0 ;0,1,2=198,3=90.000000
L 0.57916614 0.7588001 0.58166634 0.75933337 1 P 0 ;0,1,2=198,3=90.000000
L 0.58166634 0.75933337 0.58416654 0.7588001 1 P 0 ;0,1,2=198,3=90.000000
L 0.58416654 0.7588001 0.58624941 0.75746663 1 P 0 ;0,1,2=198,3=90.000000
L 0.58624941 0.75746663 0.5875 0.75506663 1 P 0 ;0,1,2=198,3=90.000000
L 0.5875 0.75506663 0.58708337 0.75266663 1 P 0 ;0,1,2=198,3=90.000000
L 0.58708337 0.75266663 0.58541634 0.75026663 1 P 0 ;0,1,2=198,3=90.000000
L 0.5625 0.77546654 0.56791624 0.7759997 1 P 0 ;0,1,2=198,3=90.000000
L 0.56791624 0.7759997 0.57249931 0.7768 1 P 0 ;0,1,2=198,3=90.000000
L 0.57249931 0.7768 0.57666663 0.77786644 1 P 0 ;0,1,2=198,3=90.000000
L 0.57666663 0.77786644 0.5812498 0.7792 1 P 0 ;0,1,2=198,3=90.000000
L 0.5812498 0.7792 0.5875 0.78133337 1 P 0 ;0,1,2=198,3=90.000000
L 0.5875 0.78133337 0.5875 0.77066654 1 P 0 ;0,1,2=198,3=90.000000
L 0.56541604 0.79346634 0.56333307 0.79533317 1 P 0 ;0,1,2=198,3=90.000000
L 0.56333307 0.79533317 0.5625 0.79746654 1 P 0 ;0,1,2=198,3=90.000000
L 0.5625 0.79746654 0.56333307 0.7995999 1 P 0 ;0,1,2=198,3=90.000000
L 0.56333307 0.7995999 0.56583258 0.80146663 1 P 0 ;0,1,2=198,3=90.000000
L 0.56583258 0.80146663 0.56958327 0.8028001 1 P 0 ;0,1,2=198,3=90.000000
L 0.56958327 0.8028001 0.57333327 0.80333337 1 P 0 ;0,1,2=198,3=90.000000
L 0.57333327 0.80333337 0.57791634 0.80333337 1 P 0 ;0,1,2=198,3=90.000000
L 0.57791634 0.80333337 0.58166634 0.8028001 1 P 0 ;0,1,2=198,3=90.000000
L 0.58166634 0.8028001 0.5849997 0.80146663 1 P 0 ;0,1,2=198,3=90.000000
L 0.5849997 0.80146663 0.58666683 0.79986644 1 P 0 ;0,1,2=198,3=90.000000
L 0.58666683 0.79986644 0.5875 0.7979997 1 P 0 ;0,1,2=198,3=90.000000
L 0.5875 0.7979997 0.58666683 0.79586634 1 P 0 ;0,1,2=198,3=90.000000
L 0.58666683 0.79586634 0.5849997 0.79426663 1 P 0 ;0,1,2=198,3=90.000000
L 0.5849997 0.79426663 0.5825003 0.7931998 1 P 0 ;0,1,2=198,3=90.000000
L 0.5825003 0.7931998 0.57916614 0.79266654 1 P 0 ;0,1,2=198,3=90.000000
L 0.57916614 0.79266654 0.5762501 0.7931998 1 P 0 ;0,1,2=198,3=90.000000
L 0.5762501 0.7931998 0.57333327 0.79453327 1 P 0 ;0,1,2=198,3=90.000000
L 0.57333327 0.79453327 0.57166614 0.79613346 1 P 0 ;0,1,2=198,3=90.000000
L 0.57166614 0.79613346 0.57124961 0.7979997 1 P 0 ;0,1,2=198,3=90.000000
L 0.57124961 0.7979997 0.57208278 0.80013307 1 P 0 ;0,1,2=198,3=90.000000
L 0.57208278 0.80013307 0.57416644 0.80173327 1 P 0 ;0,1,2=198,3=90.000000
L 0.57416644 0.80173327 0.57791634 0.80333337 1 P 0 ;0,1,2=198,3=90.000000
L 0.265 2.853 0.175 2.853 1 P 0 
L 0.175 2.853 0.175 2.897 1 P 0 
L 0.175 2.897 0.265 2.897 1 P 0 
L 0.265 2.897 0.265 2.853 1 P 0 
L 0.15916683 2.8845 0.15916683 2.9155 1 P 0 ;0,1,2=199,3=0.000000
L 0.15916683 2.9155 0.14958346 2.9155 1 P 0 ;0,1,2=199,3=0.000000
L 0.14958346 2.9155 0.14651673 2.91394931 1 P 0 ;0,1,2=199,3=0.000000
L 0.14651673 2.91394931 0.1445998 2.91188307 1 P 0 ;0,1,2=199,3=0.000000
L 0.1445998 2.91188307 0.14383327 2.9077497 1 P 0 ;0,1,2=199,3=0.000000
L 0.14383327 2.9077497 0.1445998 2.90361634 1 P 0 ;0,1,2=199,3=0.000000
L 0.1445998 2.90361634 0.1469 2.90103356 1 P 0 ;0,1,2=199,3=0.000000
L 0.1469 2.90103356 0.14958346 2.89948287 1 P 0 ;0,1,2=199,3=0.000000
L 0.14958346 2.89948287 0.15916683 2.89948287 1 P 0 ;0,1,2=199,3=0.000000
L 0.14958346 2.89948287 0.14383327 2.8845 1 P 0 ;0,1,2=199,3=0.000000
L 0.12893337 2.89069961 0.12663386 2.88708278 1 P 0 ;0,1,2=199,3=0.000000
L 0.12663386 2.88708278 0.12356713 2.88501654 1 P 0 ;0,1,2=199,3=0.000000
L 0.12356713 2.88501654 0.12011644 2.8845 1 P 0 ;0,1,2=199,3=0.000000
L 0.12011644 2.8845 0.1170497 2.88501654 1 P 0 ;0,1,2=199,3=0.000000
L 0.1170497 2.88501654 0.11398297 2.88759931 1 P 0 ;0,1,2=199,3=0.000000
L 0.11398297 2.88759931 0.11206673 2.89069961 1 P 0 ;0,1,2=199,3=0.000000
L 0.11206673 2.89069961 0.11168346 2.8937999 1 P 0 ;0,1,2=199,3=0.000000
L 0.11168346 2.8937999 0.11245 2.89741575 1 P 0 ;0,1,2=199,3=0.000000
L 0.11245 2.89741575 0.11513346 2.89999951 1 P 0 ;0,1,2=199,3=0.000000
L 0.11513346 2.89999951 0.11781693 2.90103356 1 P 0 ;0,1,2=199,3=0.000000
L 0.11781693 2.90103356 0.12126693 2.90103356 1 P 0 ;0,1,2=199,3=0.000000
L 0.11781693 2.90103356 0.11551673 2.90258317 1 P 0 ;0,1,2=199,3=0.000000
L 0.11551673 2.90258317 0.1135998 2.90516594 1 P 0 ;0,1,2=199,3=0.000000
L 0.1135998 2.90516594 0.11283327 2.90826624 1 P 0 ;0,1,2=199,3=0.000000
L 0.11283327 2.90826624 0.1135998 2.91136654 1 P 0 ;0,1,2=199,3=0.000000
L 0.1135998 2.91136654 0.11551673 2.91394931 1 P 0 ;0,1,2=199,3=0.000000
L 0.11551673 2.91394931 0.11896673 2.9155 1 P 0 ;0,1,2=199,3=0.000000
L 0.11896673 2.9155 0.12241663 2.91498337 1 P 0 ;0,1,2=199,3=0.000000
L 0.12241663 2.91498337 0.12586663 2.91291624 1 P 0 ;0,1,2=199,3=0.000000
L 0.09793337 2.89069961 0.09563386 2.88708278 1 P 0 ;0,1,2=199,3=0.000000
L 0.09563386 2.88708278 0.09256713 2.88501654 1 P 0 ;0,1,2=199,3=0.000000
L 0.09256713 2.88501654 0.08911644 2.8845 1 P 0 ;0,1,2=199,3=0.000000
L 0.08911644 2.8845 0.0860497 2.88501654 1 P 0 ;0,1,2=199,3=0.000000
L 0.0860497 2.88501654 0.08298297 2.88759931 1 P 0 ;0,1,2=199,3=0.000000
L 0.08298297 2.88759931 0.08106673 2.89069961 1 P 0 ;0,1,2=199,3=0.000000
L 0.08106673 2.89069961 0.08068346 2.8937999 1 P 0 ;0,1,2=199,3=0.000000
L 0.08068346 2.8937999 0.08145 2.89741575 1 P 0 ;0,1,2=199,3=0.000000
L 0.08145 2.89741575 0.08413346 2.89999951 1 P 0 ;0,1,2=199,3=0.000000
L 0.08413346 2.89999951 0.08681693 2.90103356 1 P 0 ;0,1,2=199,3=0.000000
L 0.08681693 2.90103356 0.09026693 2.90103356 1 P 0 ;0,1,2=199,3=0.000000
L 0.08681693 2.90103356 0.08451673 2.90258317 1 P 0 ;0,1,2=199,3=0.000000
L 0.08451673 2.90258317 0.0825998 2.90516594 1 P 0 ;0,1,2=199,3=0.000000
L 0.0825998 2.90516594 0.08183327 2.90826624 1 P 0 ;0,1,2=199,3=0.000000
L 0.08183327 2.90826624 0.0825998 2.91136654 1 P 0 ;0,1,2=199,3=0.000000
L 0.0825998 2.91136654 0.08451673 2.91394931 1 P 0 ;0,1,2=199,3=0.000000
L 0.08451673 2.91394931 0.08796673 2.9155 1 P 0 ;0,1,2=199,3=0.000000
L 0.08796673 2.9155 0.09141663 2.91498337 1 P 0 ;0,1,2=199,3=0.000000
L 0.09141663 2.91498337 0.09486663 2.91291624 1 P 0 ;0,1,2=199,3=0.000000
L 0.06578356 2.89741575 0.0631001 2.90103356 1 P 0 ;0,1,2=199,3=0.000000
L 0.0631001 2.90103356 0.0607999 2.9030998 1 P 0 ;0,1,2=199,3=0.000000
L 0.0607999 2.9030998 0.05773317 2.90413287 1 P 0 ;0,1,2=199,3=0.000000
L 0.05773317 2.90413287 0.0550497 2.9030998 1 P 0 ;0,1,2=199,3=0.000000
L 0.0550497 2.9030998 0.05313346 2.90103356 1 P 0 ;0,1,2=199,3=0.000000
L 0.05313346 2.90103356 0.0515998 2.89793327 1 P 0 ;0,1,2=199,3=0.000000
L 0.0515998 2.89793327 0.05121654 2.89431644 1 P 0 ;0,1,2=199,3=0.000000
L 0.05121654 2.89431644 0.0515998 2.89121614 1 P 0 ;0,1,2=199,3=0.000000
L 0.0515998 2.89121614 0.05313346 2.88811585 1 P 0 ;0,1,2=199,3=0.000000
L 0.05313346 2.88811585 0.05543366 2.88553307 1 P 0 ;0,1,2=199,3=0.000000
L 0.05543366 2.88553307 0.05811644 2.8845 1 P 0 ;0,1,2=199,3=0.000000
L 0.05811644 2.8845 0.06118317 2.88553307 1 P 0 ;0,1,2=199,3=0.000000
L 0.06118317 2.88553307 0.06386663 2.88863238 1 P 0 ;0,1,2=199,3=0.000000
L 0.06386663 2.88863238 0.0654003 2.89328327 1 P 0 ;0,1,2=199,3=0.000000
L 0.0654003 2.89328327 0.06578356 2.8984498 1 P 0 ;0,1,2=199,3=0.000000
L 0.06578356 2.8984498 0.06501713 2.90516594 1 P 0 ;0,1,2=199,3=0.000000
L 0.06501713 2.90516594 0.06386663 2.90878376 1 P 0 ;0,1,2=199,3=0.000000
L 0.06386663 2.90878376 0.06195039 2.9123997 1 P 0 ;0,1,2=199,3=0.000000
L 0.06195039 2.9123997 0.05926693 2.91498337 1 P 0 ;0,1,2=199,3=0.000000
L 0.05926693 2.91498337 0.05658346 2.9155 1 P 0 ;0,1,2=199,3=0.000000
L 0.05658346 2.9155 0.0539 2.91446683 1 P 0 ;0,1,2=199,3=0.000000
L 0.0539 2.91446683 0.05198297 2.91188307 1 P 0 ;0,1,2=199,3=0.000000
L 0.175 2.947 0.265 2.947 1 P 0 
L 0.265 2.947 0.265 2.903 1 P 0 
L 0.265 2.903 0.175 2.903 1 P 0 
L 0.175 2.903 0.175 2.947 1 P 0 
L 0.15916683 2.9245 0.15916683 2.9555 1 P 0 ;0,1,2=200,3=0.000000
L 0.15916683 2.9555 0.14958346 2.9555 1 P 0 ;0,1,2=200,3=0.000000
L 0.14958346 2.9555 0.14651673 2.95394931 1 P 0 ;0,1,2=200,3=0.000000
L 0.14651673 2.95394931 0.1445998 2.95188307 1 P 0 ;0,1,2=200,3=0.000000
L 0.1445998 2.95188307 0.14383327 2.9477497 1 P 0 ;0,1,2=200,3=0.000000
L 0.14383327 2.9477497 0.1445998 2.94361634 1 P 0 ;0,1,2=200,3=0.000000
L 0.1445998 2.94361634 0.1469 2.94103356 1 P 0 ;0,1,2=200,3=0.000000
L 0.1469 2.94103356 0.14958346 2.93948287 1 P 0 ;0,1,2=200,3=0.000000
L 0.14958346 2.93948287 0.15916683 2.93948287 1 P 0 ;0,1,2=200,3=0.000000
L 0.14958346 2.93948287 0.14383327 2.9245 1 P 0 ;0,1,2=200,3=0.000000
L 0.12893337 2.93069961 0.12663386 2.92708278 1 P 0 ;0,1,2=200,3=0.000000
L 0.12663386 2.92708278 0.12356713 2.92501654 1 P 0 ;0,1,2=200,3=0.000000
L 0.12356713 2.92501654 0.12011644 2.9245 1 P 0 ;0,1,2=200,3=0.000000
L 0.12011644 2.9245 0.1170497 2.92501654 1 P 0 ;0,1,2=200,3=0.000000
L 0.1170497 2.92501654 0.11398297 2.92759931 1 P 0 ;0,1,2=200,3=0.000000
L 0.11398297 2.92759931 0.11206673 2.93069961 1 P 0 ;0,1,2=200,3=0.000000
L 0.11206673 2.93069961 0.11168346 2.9337999 1 P 0 ;0,1,2=200,3=0.000000
L 0.11168346 2.9337999 0.11245 2.93741575 1 P 0 ;0,1,2=200,3=0.000000
L 0.11245 2.93741575 0.11513346 2.93999951 1 P 0 ;0,1,2=200,3=0.000000
L 0.11513346 2.93999951 0.11781693 2.94103356 1 P 0 ;0,1,2=200,3=0.000000
L 0.11781693 2.94103356 0.12126693 2.94103356 1 P 0 ;0,1,2=200,3=0.000000
L 0.11781693 2.94103356 0.11551673 2.94258317 1 P 0 ;0,1,2=200,3=0.000000
L 0.11551673 2.94258317 0.1135998 2.94516594 1 P 0 ;0,1,2=200,3=0.000000
L 0.1135998 2.94516594 0.11283327 2.94826624 1 P 0 ;0,1,2=200,3=0.000000
L 0.11283327 2.94826624 0.1135998 2.95136654 1 P 0 ;0,1,2=200,3=0.000000
L 0.1135998 2.95136654 0.11551673 2.95394931 1 P 0 ;0,1,2=200,3=0.000000
L 0.11551673 2.95394931 0.11896673 2.9555 1 P 0 ;0,1,2=200,3=0.000000
L 0.11896673 2.9555 0.12241663 2.95498337 1 P 0 ;0,1,2=200,3=0.000000
L 0.12241663 2.95498337 0.12586663 2.95291624 1 P 0 ;0,1,2=200,3=0.000000
L 0.09793337 2.93069961 0.09563386 2.92708278 1 P 0 ;0,1,2=200,3=0.000000
L 0.09563386 2.92708278 0.09256713 2.92501654 1 P 0 ;0,1,2=200,3=0.000000
L 0.09256713 2.92501654 0.08911644 2.9245 1 P 0 ;0,1,2=200,3=0.000000
L 0.08911644 2.9245 0.0860497 2.92501654 1 P 0 ;0,1,2=200,3=0.000000
L 0.0860497 2.92501654 0.08298297 2.92759931 1 P 0 ;0,1,2=200,3=0.000000
L 0.08298297 2.92759931 0.08106673 2.93069961 1 P 0 ;0,1,2=200,3=0.000000
L 0.08106673 2.93069961 0.08068346 2.9337999 1 P 0 ;0,1,2=200,3=0.000000
L 0.08068346 2.9337999 0.08145 2.93741575 1 P 0 ;0,1,2=200,3=0.000000
L 0.08145 2.93741575 0.08413346 2.93999951 1 P 0 ;0,1,2=200,3=0.000000
L 0.08413346 2.93999951 0.08681693 2.94103356 1 P 0 ;0,1,2=200,3=0.000000
L 0.08681693 2.94103356 0.09026693 2.94103356 1 P 0 ;0,1,2=200,3=0.000000
L 0.08681693 2.94103356 0.08451673 2.94258317 1 P 0 ;0,1,2=200,3=0.000000
L 0.08451673 2.94258317 0.0825998 2.94516594 1 P 0 ;0,1,2=200,3=0.000000
L 0.0825998 2.94516594 0.08183327 2.94826624 1 P 0 ;0,1,2=200,3=0.000000
L 0.08183327 2.94826624 0.0825998 2.95136654 1 P 0 ;0,1,2=200,3=0.000000
L 0.0825998 2.95136654 0.08451673 2.95394931 1 P 0 ;0,1,2=200,3=0.000000
L 0.08451673 2.95394931 0.08796673 2.9555 1 P 0 ;0,1,2=200,3=0.000000
L 0.08796673 2.9555 0.09141663 2.95498337 1 P 0 ;0,1,2=200,3=0.000000
L 0.09141663 2.95498337 0.09486663 2.95291624 1 P 0 ;0,1,2=200,3=0.000000
L 0.06693337 2.92914892 0.06463386 2.92656614 1 P 0 ;0,1,2=200,3=0.000000
L 0.06463386 2.92656614 0.06195039 2.92501654 1 P 0 ;0,1,2=200,3=0.000000
L 0.06195039 2.92501654 0.05850039 2.9245 1 P 0 ;0,1,2=200,3=0.000000
L 0.05850039 2.9245 0.0550497 2.92553307 1 P 0 ;0,1,2=200,3=0.000000
L 0.0550497 2.92553307 0.05236693 2.92759931 1 P 0 ;0,1,2=200,3=0.000000
L 0.05236693 2.92759931 0.05045 2.93121614 1 P 0 ;0,1,2=200,3=0.000000
L 0.05045 2.93121614 0.05006673 2.93534951 1 P 0 ;0,1,2=200,3=0.000000
L 0.05006673 2.93534951 0.05083327 2.93948287 1 P 0 ;0,1,2=200,3=0.000000
L 0.05083327 2.93948287 0.0527502 2.94206663 1 P 0 ;0,1,2=200,3=0.000000
L 0.0527502 2.94206663 0.05543366 2.94413287 1 P 0 ;0,1,2=200,3=0.000000
L 0.05543366 2.94413287 0.05811644 2.94464941 1 P 0 ;0,1,2=200,3=0.000000
L 0.05811644 2.94464941 0.0607999 2.94413287 1 P 0 ;0,1,2=200,3=0.000000
L 0.0607999 2.94413287 0.0642499 2.94206663 1 P 0 ;0,1,2=200,3=0.000000
L 0.0642499 2.94206663 0.0631001 2.9555 1 P 0 ;0,1,2=200,3=0.000000
L 0.0631001 2.9555 0.0527502 2.9555 1 P 0 ;0,1,2=200,3=0.000000
L 0.268 2.895 0.312 2.895 1 P 0 
L 0.312 2.895 0.312 2.805 1 P 0 
L 0.312 2.805 0.268 2.805 1 P 0 
L 0.268 2.805 0.268 2.895 1 P 0 
L 0.3845 2.78083317 0.4155 2.78083317 1 P 0 ;0,1,2=201,3=90.000000
L 0.4155 2.78083317 0.4155 2.79041654 1 P 0 ;0,1,2=201,3=90.000000
L 0.4155 2.79041654 0.41394931 2.79348327 1 P 0 ;0,1,2=201,3=90.000000
L 0.41394931 2.79348327 0.41188307 2.7954002 1 P 0 ;0,1,2=201,3=90.000000
L 0.41188307 2.7954002 0.4077497 2.79616673 1 P 0 ;0,1,2=201,3=90.000000
L 0.4077497 2.79616673 0.40361634 2.7954002 1 P 0 ;0,1,2=201,3=90.000000
L 0.40361634 2.7954002 0.40103356 2.7931 1 P 0 ;0,1,2=201,3=90.000000
L 0.40103356 2.7931 0.39948287 2.79041654 1 P 0 ;0,1,2=201,3=90.000000
L 0.39948287 2.79041654 0.39948287 2.78083317 1 P 0 ;0,1,2=201,3=90.000000
L 0.39948287 2.79041654 0.3845 2.79616673 1 P 0 ;0,1,2=201,3=90.000000
L 0.39069961 2.81106663 0.38708278 2.81336614 1 P 0 ;0,1,2=201,3=90.000000
L 0.38708278 2.81336614 0.38501654 2.81643287 1 P 0 ;0,1,2=201,3=90.000000
L 0.38501654 2.81643287 0.3845 2.81988356 1 P 0 ;0,1,2=201,3=90.000000
L 0.3845 2.81988356 0.38501654 2.8229503 1 P 0 ;0,1,2=201,3=90.000000
L 0.38501654 2.8229503 0.38759931 2.82601703 1 P 0 ;0,1,2=201,3=90.000000
L 0.38759931 2.82601703 0.39069961 2.82793327 1 P 0 ;0,1,2=201,3=90.000000
L 0.39069961 2.82793327 0.3937999 2.82831654 1 P 0 ;0,1,2=201,3=90.000000
L 0.3937999 2.82831654 0.39741575 2.82755 1 P 0 ;0,1,2=201,3=90.000000
L 0.39741575 2.82755 0.39999951 2.82486654 1 P 0 ;0,1,2=201,3=90.000000
L 0.39999951 2.82486654 0.40103356 2.82218307 1 P 0 ;0,1,2=201,3=90.000000
L 0.40103356 2.82218307 0.40103356 2.81873307 1 P 0 ;0,1,2=201,3=90.000000
L 0.40103356 2.82218307 0.40258317 2.82448327 1 P 0 ;0,1,2=201,3=90.000000
L 0.40258317 2.82448327 0.40516594 2.8264002 1 P 0 ;0,1,2=201,3=90.000000
L 0.40516594 2.8264002 0.40826624 2.82716673 1 P 0 ;0,1,2=201,3=90.000000
L 0.40826624 2.82716673 0.41136654 2.8264002 1 P 0 ;0,1,2=201,3=90.000000
L 0.41136654 2.8264002 0.41394931 2.82448327 1 P 0 ;0,1,2=201,3=90.000000
L 0.41394931 2.82448327 0.4155 2.82103327 1 P 0 ;0,1,2=201,3=90.000000
L 0.4155 2.82103327 0.41498337 2.81758337 1 P 0 ;0,1,2=201,3=90.000000
L 0.41498337 2.81758337 0.41291624 2.81413337 1 P 0 ;0,1,2=201,3=90.000000
L 0.39069961 2.84206663 0.38708278 2.84436614 1 P 0 ;0,1,2=201,3=90.000000
L 0.38708278 2.84436614 0.38501654 2.84743287 1 P 0 ;0,1,2=201,3=90.000000
L 0.38501654 2.84743287 0.3845 2.85088356 1 P 0 ;0,1,2=201,3=90.000000
L 0.3845 2.85088356 0.38501654 2.8539503 1 P 0 ;0,1,2=201,3=90.000000
L 0.38501654 2.8539503 0.38759931 2.85701703 1 P 0 ;0,1,2=201,3=90.000000
L 0.38759931 2.85701703 0.39069961 2.85893327 1 P 0 ;0,1,2=201,3=90.000000
L 0.39069961 2.85893327 0.3937999 2.85931654 1 P 0 ;0,1,2=201,3=90.000000
L 0.3937999 2.85931654 0.39741575 2.85855 1 P 0 ;0,1,2=201,3=90.000000
L 0.39741575 2.85855 0.39999951 2.85586654 1 P 0 ;0,1,2=201,3=90.000000
L 0.39999951 2.85586654 0.40103356 2.85318307 1 P 0 ;0,1,2=201,3=90.000000
L 0.40103356 2.85318307 0.40103356 2.84973307 1 P 0 ;0,1,2=201,3=90.000000
L 0.40103356 2.85318307 0.40258317 2.85548327 1 P 0 ;0,1,2=201,3=90.000000
L 0.40258317 2.85548327 0.40516594 2.8574002 1 P 0 ;0,1,2=201,3=90.000000
L 0.40516594 2.8574002 0.40826624 2.85816673 1 P 0 ;0,1,2=201,3=90.000000
L 0.40826624 2.85816673 0.41136654 2.8574002 1 P 0 ;0,1,2=201,3=90.000000
L 0.41136654 2.8574002 0.41394931 2.85548327 1 P 0 ;0,1,2=201,3=90.000000
L 0.41394931 2.85548327 0.4155 2.85203327 1 P 0 ;0,1,2=201,3=90.000000
L 0.4155 2.85203327 0.41498337 2.84858337 1 P 0 ;0,1,2=201,3=90.000000
L 0.41498337 2.84858337 0.41291624 2.84513337 1 P 0 ;0,1,2=201,3=90.000000
L 0.3845 2.8861 0.4155 2.8861 1 P 0 ;0,1,2=201,3=90.000000
L 0.4155 2.8861 0.39328327 2.87191624 1 P 0 ;0,1,2=201,3=90.000000
L 0.39328327 2.87191624 0.39328327 2.89108366 1 P 0 ;0,1,2=201,3=90.000000
L 0.357 2.895 0.357 2.805 1 P 0 
L 0.313 2.895 0.357 2.895 1 P 0 
L 0.313 2.805 0.313 2.895 1 P 0 
L 0.357 2.805 0.313 2.805 1 P 0 
L 0.4245 2.78083317 0.4555 2.78083317 1 P 0 ;0,1,2=202,3=90.000000
L 0.4555 2.78083317 0.4555 2.79041654 1 P 0 ;0,1,2=202,3=90.000000
L 0.4555 2.79041654 0.45394931 2.79348327 1 P 0 ;0,1,2=202,3=90.000000
L 0.45394931 2.79348327 0.45188307 2.7954002 1 P 0 ;0,1,2=202,3=90.000000
L 0.45188307 2.7954002 0.4477497 2.79616673 1 P 0 ;0,1,2=202,3=90.000000
L 0.4477497 2.79616673 0.44361634 2.7954002 1 P 0 ;0,1,2=202,3=90.000000
L 0.44361634 2.7954002 0.44103356 2.7931 1 P 0 ;0,1,2=202,3=90.000000
L 0.44103356 2.7931 0.43948287 2.79041654 1 P 0 ;0,1,2=202,3=90.000000
L 0.43948287 2.79041654 0.43948287 2.78083317 1 P 0 ;0,1,2=202,3=90.000000
L 0.43948287 2.79041654 0.4245 2.79616673 1 P 0 ;0,1,2=202,3=90.000000
L 0.43069961 2.81106663 0.42708278 2.81336614 1 P 0 ;0,1,2=202,3=90.000000
L 0.42708278 2.81336614 0.42501654 2.81643287 1 P 0 ;0,1,2=202,3=90.000000
L 0.42501654 2.81643287 0.4245 2.81988356 1 P 0 ;0,1,2=202,3=90.000000
L 0.4245 2.81988356 0.42501654 2.8229503 1 P 0 ;0,1,2=202,3=90.000000
L 0.42501654 2.8229503 0.42759931 2.82601703 1 P 0 ;0,1,2=202,3=90.000000
L 0.42759931 2.82601703 0.43069961 2.82793327 1 P 0 ;0,1,2=202,3=90.000000
L 0.43069961 2.82793327 0.4337999 2.82831654 1 P 0 ;0,1,2=202,3=90.000000
L 0.4337999 2.82831654 0.43741575 2.82755 1 P 0 ;0,1,2=202,3=90.000000
L 0.43741575 2.82755 0.43999951 2.82486654 1 P 0 ;0,1,2=202,3=90.000000
L 0.43999951 2.82486654 0.44103356 2.82218307 1 P 0 ;0,1,2=202,3=90.000000
L 0.44103356 2.82218307 0.44103356 2.81873307 1 P 0 ;0,1,2=202,3=90.000000
L 0.44103356 2.82218307 0.44258317 2.82448327 1 P 0 ;0,1,2=202,3=90.000000
L 0.44258317 2.82448327 0.44516594 2.8264002 1 P 0 ;0,1,2=202,3=90.000000
L 0.44516594 2.8264002 0.44826624 2.82716673 1 P 0 ;0,1,2=202,3=90.000000
L 0.44826624 2.82716673 0.45136654 2.8264002 1 P 0 ;0,1,2=202,3=90.000000
L 0.45136654 2.8264002 0.45394931 2.82448327 1 P 0 ;0,1,2=202,3=90.000000
L 0.45394931 2.82448327 0.4555 2.82103327 1 P 0 ;0,1,2=202,3=90.000000
L 0.4555 2.82103327 0.45498337 2.81758337 1 P 0 ;0,1,2=202,3=90.000000
L 0.45498337 2.81758337 0.45291624 2.81413337 1 P 0 ;0,1,2=202,3=90.000000
L 0.43069961 2.84206663 0.42708278 2.84436614 1 P 0 ;0,1,2=202,3=90.000000
L 0.42708278 2.84436614 0.42501654 2.84743287 1 P 0 ;0,1,2=202,3=90.000000
L 0.42501654 2.84743287 0.4245 2.85088356 1 P 0 ;0,1,2=202,3=90.000000
L 0.4245 2.85088356 0.42501654 2.8539503 1 P 0 ;0,1,2=202,3=90.000000
L 0.42501654 2.8539503 0.42759931 2.85701703 1 P 0 ;0,1,2=202,3=90.000000
L 0.42759931 2.85701703 0.43069961 2.85893327 1 P 0 ;0,1,2=202,3=90.000000
L 0.43069961 2.85893327 0.4337999 2.85931654 1 P 0 ;0,1,2=202,3=90.000000
L 0.4337999 2.85931654 0.43741575 2.85855 1 P 0 ;0,1,2=202,3=90.000000
L 0.43741575 2.85855 0.43999951 2.85586654 1 P 0 ;0,1,2=202,3=90.000000
L 0.43999951 2.85586654 0.44103356 2.85318307 1 P 0 ;0,1,2=202,3=90.000000
L 0.44103356 2.85318307 0.44103356 2.84973307 1 P 0 ;0,1,2=202,3=90.000000
L 0.44103356 2.85318307 0.44258317 2.85548327 1 P 0 ;0,1,2=202,3=90.000000
L 0.44258317 2.85548327 0.44516594 2.8574002 1 P 0 ;0,1,2=202,3=90.000000
L 0.44516594 2.8574002 0.44826624 2.85816673 1 P 0 ;0,1,2=202,3=90.000000
L 0.44826624 2.85816673 0.45136654 2.8574002 1 P 0 ;0,1,2=202,3=90.000000
L 0.45136654 2.8574002 0.45394931 2.85548327 1 P 0 ;0,1,2=202,3=90.000000
L 0.45394931 2.85548327 0.4555 2.85203327 1 P 0 ;0,1,2=202,3=90.000000
L 0.4555 2.85203327 0.45498337 2.84858337 1 P 0 ;0,1,2=202,3=90.000000
L 0.45498337 2.84858337 0.45291624 2.84513337 1 P 0 ;0,1,2=202,3=90.000000
L 0.43069961 2.87306663 0.42708278 2.87536614 1 P 0 ;0,1,2=202,3=90.000000
L 0.42708278 2.87536614 0.42501654 2.87843287 1 P 0 ;0,1,2=202,3=90.000000
L 0.42501654 2.87843287 0.4245 2.88188356 1 P 0 ;0,1,2=202,3=90.000000
L 0.4245 2.88188356 0.42501654 2.8849503 1 P 0 ;0,1,2=202,3=90.000000
L 0.42501654 2.8849503 0.42759931 2.88801703 1 P 0 ;0,1,2=202,3=90.000000
L 0.42759931 2.88801703 0.43069961 2.88993327 1 P 0 ;0,1,2=202,3=90.000000
L 0.43069961 2.88993327 0.4337999 2.89031654 1 P 0 ;0,1,2=202,3=90.000000
L 0.4337999 2.89031654 0.43741575 2.88955 1 P 0 ;0,1,2=202,3=90.000000
L 0.43741575 2.88955 0.43999951 2.88686654 1 P 0 ;0,1,2=202,3=90.000000
L 0.43999951 2.88686654 0.44103356 2.88418307 1 P 0 ;0,1,2=202,3=90.000000
L 0.44103356 2.88418307 0.44103356 2.88073307 1 P 0 ;0,1,2=202,3=90.000000
L 0.44103356 2.88418307 0.44258317 2.88648327 1 P 0 ;0,1,2=202,3=90.000000
L 0.44258317 2.88648327 0.44516594 2.8884002 1 P 0 ;0,1,2=202,3=90.000000
L 0.44516594 2.8884002 0.44826624 2.88916673 1 P 0 ;0,1,2=202,3=90.000000
L 0.44826624 2.88916673 0.45136654 2.8884002 1 P 0 ;0,1,2=202,3=90.000000
L 0.45136654 2.8884002 0.45394931 2.88648327 1 P 0 ;0,1,2=202,3=90.000000
L 0.45394931 2.88648327 0.4555 2.88303327 1 P 0 ;0,1,2=202,3=90.000000
L 0.4555 2.88303327 0.45498337 2.87958337 1 P 0 ;0,1,2=202,3=90.000000
L 0.45498337 2.87958337 0.45291624 2.87613337 1 P 0 ;0,1,2=202,3=90.000000
L 0.175 3.047 0.265 3.047 1 P 0 
L 0.265 3.003 0.175 3.003 1 P 0 
L 0.175 3.003 0.175 3.047 1 P 0 
L 0.265 3.047 0.265 3.003 1 P 0 
L 0.15416683 3.0295 0.15416683 3.0605 1 P 0 ;0,1,2=203,3=0.000000
L 0.15416683 3.0605 0.14458346 3.0605 1 P 0 ;0,1,2=203,3=0.000000
L 0.14458346 3.0605 0.14151673 3.05894931 1 P 0 ;0,1,2=203,3=0.000000
L 0.14151673 3.05894931 0.1395998 3.05688307 1 P 0 ;0,1,2=203,3=0.000000
L 0.1395998 3.05688307 0.13883327 3.0527497 1 P 0 ;0,1,2=203,3=0.000000
L 0.13883327 3.0527497 0.1395998 3.04861634 1 P 0 ;0,1,2=203,3=0.000000
L 0.1395998 3.04861634 0.1419 3.04603356 1 P 0 ;0,1,2=203,3=0.000000
L 0.1419 3.04603356 0.14458346 3.04448287 1 P 0 ;0,1,2=203,3=0.000000
L 0.14458346 3.04448287 0.15416683 3.04448287 1 P 0 ;0,1,2=203,3=0.000000
L 0.14458346 3.04448287 0.13883327 3.0295 1 P 0 ;0,1,2=203,3=0.000000
L 0.12393337 3.03569961 0.12163386 3.03208278 1 P 0 ;0,1,2=203,3=0.000000
L 0.12163386 3.03208278 0.11856713 3.03001654 1 P 0 ;0,1,2=203,3=0.000000
L 0.11856713 3.03001654 0.11511644 3.0295 1 P 0 ;0,1,2=203,3=0.000000
L 0.11511644 3.0295 0.1120497 3.03001654 1 P 0 ;0,1,2=203,3=0.000000
L 0.1120497 3.03001654 0.10898297 3.03259931 1 P 0 ;0,1,2=203,3=0.000000
L 0.10898297 3.03259931 0.10706673 3.03569961 1 P 0 ;0,1,2=203,3=0.000000
L 0.10706673 3.03569961 0.10668346 3.0387999 1 P 0 ;0,1,2=203,3=0.000000
L 0.10668346 3.0387999 0.10745 3.04241575 1 P 0 ;0,1,2=203,3=0.000000
L 0.10745 3.04241575 0.11013346 3.04499951 1 P 0 ;0,1,2=203,3=0.000000
L 0.11013346 3.04499951 0.11281693 3.04603356 1 P 0 ;0,1,2=203,3=0.000000
L 0.11281693 3.04603356 0.11626693 3.04603356 1 P 0 ;0,1,2=203,3=0.000000
L 0.11281693 3.04603356 0.11051673 3.04758317 1 P 0 ;0,1,2=203,3=0.000000
L 0.11051673 3.04758317 0.1085998 3.05016594 1 P 0 ;0,1,2=203,3=0.000000
L 0.1085998 3.05016594 0.10783327 3.05326624 1 P 0 ;0,1,2=203,3=0.000000
L 0.10783327 3.05326624 0.1085998 3.05636654 1 P 0 ;0,1,2=203,3=0.000000
L 0.1085998 3.05636654 0.11051673 3.05894931 1 P 0 ;0,1,2=203,3=0.000000
L 0.11051673 3.05894931 0.11396673 3.0605 1 P 0 ;0,1,2=203,3=0.000000
L 0.11396673 3.0605 0.11741663 3.05998337 1 P 0 ;0,1,2=203,3=0.000000
L 0.11741663 3.05998337 0.12086663 3.05791624 1 P 0 ;0,1,2=203,3=0.000000
L 0.09293337 3.03569961 0.09063386 3.03208278 1 P 0 ;0,1,2=203,3=0.000000
L 0.09063386 3.03208278 0.08756713 3.03001654 1 P 0 ;0,1,2=203,3=0.000000
L 0.08756713 3.03001654 0.08411644 3.0295 1 P 0 ;0,1,2=203,3=0.000000
L 0.08411644 3.0295 0.0810497 3.03001654 1 P 0 ;0,1,2=203,3=0.000000
L 0.0810497 3.03001654 0.07798297 3.03259931 1 P 0 ;0,1,2=203,3=0.000000
L 0.07798297 3.03259931 0.07606673 3.03569961 1 P 0 ;0,1,2=203,3=0.000000
L 0.07606673 3.03569961 0.07568346 3.0387999 1 P 0 ;0,1,2=203,3=0.000000
L 0.07568346 3.0387999 0.07645 3.04241575 1 P 0 ;0,1,2=203,3=0.000000
L 0.07645 3.04241575 0.07913346 3.04499951 1 P 0 ;0,1,2=203,3=0.000000
L 0.07913346 3.04499951 0.08181693 3.04603356 1 P 0 ;0,1,2=203,3=0.000000
L 0.08181693 3.04603356 0.08526693 3.04603356 1 P 0 ;0,1,2=203,3=0.000000
L 0.08181693 3.04603356 0.07951673 3.04758317 1 P 0 ;0,1,2=203,3=0.000000
L 0.07951673 3.04758317 0.0775998 3.05016594 1 P 0 ;0,1,2=203,3=0.000000
L 0.0775998 3.05016594 0.07683327 3.05326624 1 P 0 ;0,1,2=203,3=0.000000
L 0.07683327 3.05326624 0.0775998 3.05636654 1 P 0 ;0,1,2=203,3=0.000000
L 0.0775998 3.05636654 0.07951673 3.05894931 1 P 0 ;0,1,2=203,3=0.000000
L 0.07951673 3.05894931 0.08296673 3.0605 1 P 0 ;0,1,2=203,3=0.000000
L 0.08296673 3.0605 0.08641663 3.05998337 1 P 0 ;0,1,2=203,3=0.000000
L 0.08641663 3.05998337 0.08986663 3.05791624 1 P 0 ;0,1,2=203,3=0.000000
L 0.05350039 3.0295 0.05081693 3.03001654 1 P 0 ;0,1,2=203,3=0.000000
L 0.05081693 3.03001654 0.0477502 3.03156614 1 P 0 ;0,1,2=203,3=0.000000
L 0.0477502 3.03156614 0.04583327 3.03414892 1 P 0 ;0,1,2=203,3=0.000000
L 0.04583327 3.03414892 0.04506673 3.03776673 1 P 0 ;0,1,2=203,3=0.000000
L 0.04506673 3.03776673 0.04583327 3.04138268 1 P 0 ;0,1,2=203,3=0.000000
L 0.04583327 3.04138268 0.04813346 3.04448287 1 P 0 ;0,1,2=203,3=0.000000
L 0.04813346 3.04448287 0.05158346 3.04603356 1 P 0 ;0,1,2=203,3=0.000000
L 0.05158346 3.04603356 0.05541663 3.04603356 1 P 0 ;0,1,2=203,3=0.000000
L 0.05541663 3.04603356 0.05771683 3.04706663 1 P 0 ;0,1,2=203,3=0.000000
L 0.05771683 3.04706663 0.05963386 3.04964941 1 P 0 ;0,1,2=203,3=0.000000
L 0.05963386 3.04964941 0.0604003 3.05326624 1 P 0 ;0,1,2=203,3=0.000000
L 0.0604003 3.05326624 0.0592499 3.05688307 1 P 0 ;0,1,2=203,3=0.000000
L 0.0592499 3.05688307 0.05656713 3.05946683 1 P 0 ;0,1,2=203,3=0.000000
L 0.05656713 3.05946683 0.05350039 3.0605 1 P 0 ;0,1,2=203,3=0.000000
L 0.05350039 3.0605 0.05043366 3.05946683 1 P 0 ;0,1,2=203,3=0.000000
L 0.05043366 3.05946683 0.0477502 3.05688307 1 P 0 ;0,1,2=203,3=0.000000
L 0.0477502 3.05688307 0.0465998 3.05326624 1 P 0 ;0,1,2=203,3=0.000000
L 0.0465998 3.05326624 0.04736693 3.04964941 1 P 0 ;0,1,2=203,3=0.000000
L 0.04736693 3.04964941 0.04928327 3.04706663 1 P 0 ;0,1,2=203,3=0.000000
L 0.04928327 3.04706663 0.05158346 3.04603356 1 P 0 ;0,1,2=203,3=0.000000
L 0.05158346 3.04603356 0.05541663 3.04603356 1 P 0 ;0,1,2=203,3=0.000000
L 0.05541663 3.04603356 0.05886663 3.04448287 1 P 0 ;0,1,2=203,3=0.000000
L 0.05886663 3.04448287 0.06116683 3.04138268 1 P 0 ;0,1,2=203,3=0.000000
L 0.06116683 3.04138268 0.06193337 3.03776673 1 P 0 ;0,1,2=203,3=0.000000
L 0.06193337 3.03776673 0.06116683 3.03414892 1 P 0 ;0,1,2=203,3=0.000000
L 0.06116683 3.03414892 0.0592499 3.03156614 1 P 0 ;0,1,2=203,3=0.000000
L 0.0592499 3.03156614 0.05618317 3.03001654 1 P 0 ;0,1,2=203,3=0.000000
L 0.05618317 3.03001654 0.05350039 3.0295 1 P 0 ;0,1,2=203,3=0.000000
L 0.175 2.997 0.265 2.997 1 P 0 
L 0.265 2.997 0.265 2.953 1 P 0 
L 0.265 2.953 0.175 2.953 1 P 0 
L 0.175 2.953 0.175 2.997 1 P 0 
L 0.15416683 2.9845 0.15416683 3.0155 1 P 0 ;0,1,2=204,3=0.000000
L 0.15416683 3.0155 0.14458346 3.0155 1 P 0 ;0,1,2=204,3=0.000000
L 0.14458346 3.0155 0.14151673 3.01394931 1 P 0 ;0,1,2=204,3=0.000000
L 0.14151673 3.01394931 0.1395998 3.01188307 1 P 0 ;0,1,2=204,3=0.000000
L 0.1395998 3.01188307 0.13883327 3.0077497 1 P 0 ;0,1,2=204,3=0.000000
L 0.13883327 3.0077497 0.1395998 3.00361634 1 P 0 ;0,1,2=204,3=0.000000
L 0.1395998 3.00361634 0.1419 3.00103356 1 P 0 ;0,1,2=204,3=0.000000
L 0.1419 3.00103356 0.14458346 2.99948287 1 P 0 ;0,1,2=204,3=0.000000
L 0.14458346 2.99948287 0.15416683 2.99948287 1 P 0 ;0,1,2=204,3=0.000000
L 0.14458346 2.99948287 0.13883327 2.9845 1 P 0 ;0,1,2=204,3=0.000000
L 0.12393337 2.99069961 0.12163386 2.98708278 1 P 0 ;0,1,2=204,3=0.000000
L 0.12163386 2.98708278 0.11856713 2.98501654 1 P 0 ;0,1,2=204,3=0.000000
L 0.11856713 2.98501654 0.11511644 2.9845 1 P 0 ;0,1,2=204,3=0.000000
L 0.11511644 2.9845 0.1120497 2.98501654 1 P 0 ;0,1,2=204,3=0.000000
L 0.1120497 2.98501654 0.10898297 2.98759931 1 P 0 ;0,1,2=204,3=0.000000
L 0.10898297 2.98759931 0.10706673 2.99069961 1 P 0 ;0,1,2=204,3=0.000000
L 0.10706673 2.99069961 0.10668346 2.9937999 1 P 0 ;0,1,2=204,3=0.000000
L 0.10668346 2.9937999 0.10745 2.99741575 1 P 0 ;0,1,2=204,3=0.000000
L 0.10745 2.99741575 0.11013346 2.99999951 1 P 0 ;0,1,2=204,3=0.000000
L 0.11013346 2.99999951 0.11281693 3.00103356 1 P 0 ;0,1,2=204,3=0.000000
L 0.11281693 3.00103356 0.11626693 3.00103356 1 P 0 ;0,1,2=204,3=0.000000
L 0.11281693 3.00103356 0.11051673 3.00258317 1 P 0 ;0,1,2=204,3=0.000000
L 0.11051673 3.00258317 0.1085998 3.00516594 1 P 0 ;0,1,2=204,3=0.000000
L 0.1085998 3.00516594 0.10783327 3.00826624 1 P 0 ;0,1,2=204,3=0.000000
L 0.10783327 3.00826624 0.1085998 3.01136654 1 P 0 ;0,1,2=204,3=0.000000
L 0.1085998 3.01136654 0.11051673 3.01394931 1 P 0 ;0,1,2=204,3=0.000000
L 0.11051673 3.01394931 0.11396673 3.0155 1 P 0 ;0,1,2=204,3=0.000000
L 0.11396673 3.0155 0.11741663 3.01498337 1 P 0 ;0,1,2=204,3=0.000000
L 0.11741663 3.01498337 0.12086663 3.01291624 1 P 0 ;0,1,2=204,3=0.000000
L 0.09293337 2.99069961 0.09063386 2.98708278 1 P 0 ;0,1,2=204,3=0.000000
L 0.09063386 2.98708278 0.08756713 2.98501654 1 P 0 ;0,1,2=204,3=0.000000
L 0.08756713 2.98501654 0.08411644 2.9845 1 P 0 ;0,1,2=204,3=0.000000
L 0.08411644 2.9845 0.0810497 2.98501654 1 P 0 ;0,1,2=204,3=0.000000
L 0.0810497 2.98501654 0.07798297 2.98759931 1 P 0 ;0,1,2=204,3=0.000000
L 0.07798297 2.98759931 0.07606673 2.99069961 1 P 0 ;0,1,2=204,3=0.000000
L 0.07606673 2.99069961 0.07568346 2.9937999 1 P 0 ;0,1,2=204,3=0.000000
L 0.07568346 2.9937999 0.07645 2.99741575 1 P 0 ;0,1,2=204,3=0.000000
L 0.07645 2.99741575 0.07913346 2.99999951 1 P 0 ;0,1,2=204,3=0.000000
L 0.07913346 2.99999951 0.08181693 3.00103356 1 P 0 ;0,1,2=204,3=0.000000
L 0.08181693 3.00103356 0.08526693 3.00103356 1 P 0 ;0,1,2=204,3=0.000000
L 0.08181693 3.00103356 0.07951673 3.00258317 1 P 0 ;0,1,2=204,3=0.000000
L 0.07951673 3.00258317 0.0775998 3.00516594 1 P 0 ;0,1,2=204,3=0.000000
L 0.0775998 3.00516594 0.07683327 3.00826624 1 P 0 ;0,1,2=204,3=0.000000
L 0.07683327 3.00826624 0.0775998 3.01136654 1 P 0 ;0,1,2=204,3=0.000000
L 0.0775998 3.01136654 0.07951673 3.01394931 1 P 0 ;0,1,2=204,3=0.000000
L 0.07951673 3.01394931 0.08296673 3.0155 1 P 0 ;0,1,2=204,3=0.000000
L 0.08296673 3.0155 0.08641663 3.01498337 1 P 0 ;0,1,2=204,3=0.000000
L 0.08641663 3.01498337 0.08986663 3.01291624 1 P 0 ;0,1,2=204,3=0.000000
L 0.05426693 2.9845 0.05350039 2.99121614 1 P 0 ;0,1,2=204,3=0.000000
L 0.05350039 2.99121614 0.0523499 2.99689921 1 P 0 ;0,1,2=204,3=0.000000
L 0.0523499 2.99689921 0.05081693 3.00206663 1 P 0 ;0,1,2=204,3=0.000000
L 0.05081693 3.00206663 0.0489 3.0077497 1 P 0 ;0,1,2=204,3=0.000000
L 0.0489 3.0077497 0.04583327 3.0155 1 P 0 ;0,1,2=204,3=0.000000
L 0.04583327 3.0155 0.06116683 3.0155 1 P 0 ;0,1,2=204,3=0.000000
L 0.777 0.777 0.821 0.777 1 P 0 
L 0.821 0.777 0.821 0.687 1 P 0 
L 0.821 0.687 0.777 0.687 1 P 0 
L 0.777 0.687 0.777 0.777 1 P 0 
L 0.7395 0.70183317 0.7705 0.70183317 1 P 0 ;0,1,2=205,3=90.000000
L 0.7705 0.70183317 0.7705 0.71141654 1 P 0 ;0,1,2=205,3=90.000000
L 0.7705 0.71141654 0.76894931 0.71448327 1 P 0 ;0,1,2=205,3=90.000000
L 0.76894931 0.71448327 0.76688307 0.7164002 1 P 0 ;0,1,2=205,3=90.000000
L 0.76688307 0.7164002 0.7627497 0.71716673 1 P 0 ;0,1,2=205,3=90.000000
L 0.7627497 0.71716673 0.75861634 0.7164002 1 P 0 ;0,1,2=205,3=90.000000
L 0.75861634 0.7164002 0.75603356 0.7141 1 P 0 ;0,1,2=205,3=90.000000
L 0.75603356 0.7141 0.75448287 0.71141654 1 P 0 ;0,1,2=205,3=90.000000
L 0.75448287 0.71141654 0.75448287 0.70183317 1 P 0 ;0,1,2=205,3=90.000000
L 0.75448287 0.71141654 0.7395 0.71716673 1 P 0 ;0,1,2=205,3=90.000000
L 0.76533346 0.73321644 0.76843278 0.73551663 1 P 0 ;0,1,2=205,3=90.000000
L 0.76843278 0.73551663 0.76998337 0.7382001 1 P 0 ;0,1,2=205,3=90.000000
L 0.76998337 0.7382001 0.7705 0.74126683 1 P 0 ;0,1,2=205,3=90.000000
L 0.7705 0.74126683 0.76946683 0.7451 1 P 0 ;0,1,2=205,3=90.000000
L 0.76946683 0.7451 0.76688307 0.74778346 1 P 0 ;0,1,2=205,3=90.000000
L 0.76688307 0.74778346 0.76378376 0.74855 1 P 0 ;0,1,2=205,3=90.000000
L 0.76378376 0.74855 0.76068258 0.74816673 1 P 0 ;0,1,2=205,3=90.000000
L 0.76068258 0.74816673 0.7580998 0.74663307 1 P 0 ;0,1,2=205,3=90.000000
L 0.7580998 0.74663307 0.75293327 0.73896663 1 P 0 ;0,1,2=205,3=90.000000
L 0.75293327 0.73896663 0.74931644 0.73551663 1 P 0 ;0,1,2=205,3=90.000000
L 0.74931644 0.73551663 0.74414892 0.73321644 1 P 0 ;0,1,2=205,3=90.000000
L 0.74414892 0.73321644 0.7395 0.7324499 1 P 0 ;0,1,2=205,3=90.000000
L 0.7395 0.7324499 0.7395 0.74855 1 P 0 ;0,1,2=205,3=90.000000
L 1.3747 0.73 1.3747 0.686 1 P 0 
L 1.3747 0.686 1.2847 0.686 1 P 0 
L 1.2847 0.686 1.2847 0.73 1 P 0 
L 1.2847 0.73 1.3747 0.73 1 P 0 
L 1.50916683 0.6445 1.50916683 0.6755 1 P 0 ;0,1,2=206,3=0.000000
L 1.50916683 0.6755 1.49958346 0.6755 1 P 0 ;0,1,2=206,3=0.000000
L 1.49958346 0.6755 1.49651673 0.67394931 1 P 0 ;0,1,2=206,3=0.000000
L 1.49651673 0.67394931 1.4945998 0.67188307 1 P 0 ;0,1,2=206,3=0.000000
L 1.4945998 0.67188307 1.49383327 0.6677497 1 P 0 ;0,1,2=206,3=0.000000
L 1.49383327 0.6677497 1.4945998 0.66361634 1 P 0 ;0,1,2=206,3=0.000000
L 1.4945998 0.66361634 1.4969 0.66103356 1 P 0 ;0,1,2=206,3=0.000000
L 1.4969 0.66103356 1.49958346 0.65948287 1 P 0 ;0,1,2=206,3=0.000000
L 1.49958346 0.65948287 1.50916683 0.65948287 1 P 0 ;0,1,2=206,3=0.000000
L 1.49958346 0.65948287 1.49383327 0.6445 1 P 0 ;0,1,2=206,3=0.000000
L 1.47050039 0.6445 1.47050039 0.6755 1 P 0 ;0,1,2=206,3=0.000000
L 1.47050039 0.6755 1.4751001 0.6693003 1 P 0 ;0,1,2=206,3=0.000000
L 1.4751001 0.6445 1.46590069 0.6445 1 P 0 ;0,1,2=206,3=0.000000
L 1.44026693 0.6445 1.43950039 0.65121614 1 P 0 ;0,1,2=206,3=0.000000
L 1.43950039 0.65121614 1.4383499 0.65689921 1 P 0 ;0,1,2=206,3=0.000000
L 1.4383499 0.65689921 1.43681693 0.66206663 1 P 0 ;0,1,2=206,3=0.000000
L 1.43681693 0.66206663 1.4349 0.6677497 1 P 0 ;0,1,2=206,3=0.000000
L 1.4349 0.6677497 1.43183327 0.6755 1 P 0 ;0,1,2=206,3=0.000000
L 1.43183327 0.6755 1.44716683 0.6755 1 P 0 ;0,1,2=206,3=0.000000
L 1.41578356 0.65741575 1.4131001 0.66103356 1 P 0 ;0,1,2=206,3=0.000000
L 1.4131001 0.66103356 1.4107999 0.6630998 1 P 0 ;0,1,2=206,3=0.000000
L 1.4107999 0.6630998 1.40773317 0.66413287 1 P 0 ;0,1,2=206,3=0.000000
L 1.40773317 0.66413287 1.4050497 0.6630998 1 P 0 ;0,1,2=206,3=0.000000
L 1.4050497 0.6630998 1.40313346 0.66103356 1 P 0 ;0,1,2=206,3=0.000000
L 1.40313346 0.66103356 1.4015998 0.65793327 1 P 0 ;0,1,2=206,3=0.000000
L 1.4015998 0.65793327 1.40121654 0.65431644 1 P 0 ;0,1,2=206,3=0.000000
L 1.40121654 0.65431644 1.4015998 0.65121614 1 P 0 ;0,1,2=206,3=0.000000
L 1.4015998 0.65121614 1.40313346 0.64811585 1 P 0 ;0,1,2=206,3=0.000000
L 1.40313346 0.64811585 1.40543366 0.64553307 1 P 0 ;0,1,2=206,3=0.000000
L 1.40543366 0.64553307 1.40811644 0.6445 1 P 0 ;0,1,2=206,3=0.000000
L 1.40811644 0.6445 1.41118317 0.64553307 1 P 0 ;0,1,2=206,3=0.000000
L 1.41118317 0.64553307 1.41386663 0.64863238 1 P 0 ;0,1,2=206,3=0.000000
L 1.41386663 0.64863238 1.4154003 0.65328327 1 P 0 ;0,1,2=206,3=0.000000
L 1.4154003 0.65328327 1.41578356 0.6584498 1 P 0 ;0,1,2=206,3=0.000000
L 1.41578356 0.6584498 1.41501713 0.66516594 1 P 0 ;0,1,2=206,3=0.000000
L 1.41501713 0.66516594 1.41386663 0.66878376 1 P 0 ;0,1,2=206,3=0.000000
L 1.41386663 0.66878376 1.41195039 0.6723997 1 P 0 ;0,1,2=206,3=0.000000
L 1.41195039 0.6723997 1.40926693 0.67498337 1 P 0 ;0,1,2=206,3=0.000000
L 1.40926693 0.67498337 1.40658346 0.6755 1 P 0 ;0,1,2=206,3=0.000000
L 1.40658346 0.6755 1.4039 0.67446683 1 P 0 ;0,1,2=206,3=0.000000
L 1.4039 0.67446683 1.40198297 0.67188307 1 P 0 ;0,1,2=206,3=0.000000
L 1.3745 0.68 1.3745 0.636 1 P 0 
L 1.3745 0.636 1.2845 0.636 1 P 0 
L 1.2845 0.636 1.2845 0.68 1 P 0 
L 1.2845 0.68 1.3745 0.68 1 P 0 
L 1.41416683 0.5695 1.41416683 0.6005 1 P 0 ;0,1,2=207,3=0.000000
L 1.41416683 0.6005 1.40458346 0.6005 1 P 0 ;0,1,2=207,3=0.000000
L 1.40458346 0.6005 1.40151673 0.59894931 1 P 0 ;0,1,2=207,3=0.000000
L 1.40151673 0.59894931 1.3995998 0.59688307 1 P 0 ;0,1,2=207,3=0.000000
L 1.3995998 0.59688307 1.39883327 0.5927497 1 P 0 ;0,1,2=207,3=0.000000
L 1.39883327 0.5927497 1.3995998 0.58861634 1 P 0 ;0,1,2=207,3=0.000000
L 1.3995998 0.58861634 1.4019 0.58603356 1 P 0 ;0,1,2=207,3=0.000000
L 1.4019 0.58603356 1.40458346 0.58448287 1 P 0 ;0,1,2=207,3=0.000000
L 1.40458346 0.58448287 1.41416683 0.58448287 1 P 0 ;0,1,2=207,3=0.000000
L 1.40458346 0.58448287 1.39883327 0.5695 1 P 0 ;0,1,2=207,3=0.000000
L 1.37550039 0.5695 1.37550039 0.6005 1 P 0 ;0,1,2=207,3=0.000000
L 1.37550039 0.6005 1.3801001 0.5943003 1 P 0 ;0,1,2=207,3=0.000000
L 1.3801001 0.5695 1.37090069 0.5695 1 P 0 ;0,1,2=207,3=0.000000
L 1.34526693 0.5695 1.34450039 0.57621614 1 P 0 ;0,1,2=207,3=0.000000
L 1.34450039 0.57621614 1.3433499 0.58189921 1 P 0 ;0,1,2=207,3=0.000000
L 1.3433499 0.58189921 1.34181693 0.58706663 1 P 0 ;0,1,2=207,3=0.000000
L 1.34181693 0.58706663 1.3399 0.5927497 1 P 0 ;0,1,2=207,3=0.000000
L 1.3399 0.5927497 1.33683327 0.6005 1 P 0 ;0,1,2=207,3=0.000000
L 1.33683327 0.6005 1.35216683 0.6005 1 P 0 ;0,1,2=207,3=0.000000
L 1.32193337 0.57414892 1.31963386 0.57156614 1 P 0 ;0,1,2=207,3=0.000000
L 1.31963386 0.57156614 1.31695039 0.57001654 1 P 0 ;0,1,2=207,3=0.000000
L 1.31695039 0.57001654 1.31350039 0.5695 1 P 0 ;0,1,2=207,3=0.000000
L 1.31350039 0.5695 1.3100497 0.57053307 1 P 0 ;0,1,2=207,3=0.000000
L 1.3100497 0.57053307 1.30736693 0.57259931 1 P 0 ;0,1,2=207,3=0.000000
L 1.30736693 0.57259931 1.30545 0.57621614 1 P 0 ;0,1,2=207,3=0.000000
L 1.30545 0.57621614 1.30506673 0.58034951 1 P 0 ;0,1,2=207,3=0.000000
L 1.30506673 0.58034951 1.30583327 0.58448287 1 P 0 ;0,1,2=207,3=0.000000
L 1.30583327 0.58448287 1.3077502 0.58706663 1 P 0 ;0,1,2=207,3=0.000000
L 1.3077502 0.58706663 1.31043366 0.58913287 1 P 0 ;0,1,2=207,3=0.000000
L 1.31043366 0.58913287 1.31311644 0.58964941 1 P 0 ;0,1,2=207,3=0.000000
L 1.31311644 0.58964941 1.3157999 0.58913287 1 P 0 ;0,1,2=207,3=0.000000
L 1.3157999 0.58913287 1.3192499 0.58706663 1 P 0 ;0,1,2=207,3=0.000000
L 1.3192499 0.58706663 1.3181001 0.6005 1 P 0 ;0,1,2=207,3=0.000000
L 1.3181001 0.6005 1.3077502 0.6005 1 P 0 ;0,1,2=207,3=0.000000
L 5.786 3.879 5.786 3.835 1 P 0 
L 5.696 3.879 5.786 3.879 1 P 0 
L 5.786 3.835 5.696 3.835 1 P 0 
L 5.696 3.835 5.696 3.879 1 P 0 
L 5.90366683 3.8445 5.90366683 3.8755 1 P 0 ;0,1,2=208,3=0.000000
L 5.90366683 3.8755 5.89408346 3.8755 1 P 0 ;0,1,2=208,3=0.000000
L 5.89408346 3.8755 5.89101673 3.87394931 1 P 0 ;0,1,2=208,3=0.000000
L 5.89101673 3.87394931 5.8890998 3.87188307 1 P 0 ;0,1,2=208,3=0.000000
L 5.8890998 3.87188307 5.88833327 3.8677497 1 P 0 ;0,1,2=208,3=0.000000
L 5.88833327 3.8677497 5.8890998 3.86361634 1 P 0 ;0,1,2=208,3=0.000000
L 5.8890998 3.86361634 5.8914 3.86103356 1 P 0 ;0,1,2=208,3=0.000000
L 5.8914 3.86103356 5.89408346 3.85948287 1 P 0 ;0,1,2=208,3=0.000000
L 5.89408346 3.85948287 5.90366683 3.85948287 1 P 0 ;0,1,2=208,3=0.000000
L 5.89408346 3.85948287 5.88833327 3.8445 1 P 0 ;0,1,2=208,3=0.000000
L 5.86500039 3.8445 5.86500039 3.8755 1 P 0 ;0,1,2=208,3=0.000000
L 5.86500039 3.8755 5.8696001 3.8693003 1 P 0 ;0,1,2=208,3=0.000000
L 5.8696001 3.8445 5.86040069 3.8445 1 P 0 ;0,1,2=208,3=0.000000
L 5.83400039 3.8755 5.83706713 3.87446683 1 P 0 ;0,1,2=208,3=0.000000
L 5.83706713 3.87446683 5.83936663 3.87188307 1 P 0 ;0,1,2=208,3=0.000000
L 5.83936663 3.87188307 5.8409003 3.86878376 1 P 0 ;0,1,2=208,3=0.000000
L 5.8409003 3.86878376 5.8420501 3.86464941 1 P 0 ;0,1,2=208,3=0.000000
L 5.8420501 3.86464941 5.84243337 3.85999951 1 P 0 ;0,1,2=208,3=0.000000
L 5.84243337 3.85999951 5.8420501 3.85534951 1 P 0 ;0,1,2=208,3=0.000000
L 5.8420501 3.85534951 5.8409003 3.85121614 1 P 0 ;0,1,2=208,3=0.000000
L 5.8409003 3.85121614 5.83936663 3.84811585 1 P 0 ;0,1,2=208,3=0.000000
L 5.83936663 3.84811585 5.83706713 3.84553307 1 P 0 ;0,1,2=208,3=0.000000
L 5.83706713 3.84553307 5.83400039 3.8445 1 P 0 ;0,1,2=208,3=0.000000
L 5.83400039 3.8445 5.83093366 3.84553307 1 P 0 ;0,1,2=208,3=0.000000
L 5.83093366 3.84553307 5.82863346 3.84811585 1 P 0 ;0,1,2=208,3=0.000000
L 5.82863346 3.84811585 5.8270998 3.85121614 1 P 0 ;0,1,2=208,3=0.000000
L 5.8270998 3.85121614 5.82595 3.85534951 1 P 0 ;0,1,2=208,3=0.000000
L 5.82595 3.85534951 5.82556673 3.85999951 1 P 0 ;0,1,2=208,3=0.000000
L 5.82556673 3.85999951 5.82595 3.86464941 1 P 0 ;0,1,2=208,3=0.000000
L 5.82595 3.86464941 5.8270998 3.86878376 1 P 0 ;0,1,2=208,3=0.000000
L 5.8270998 3.86878376 5.82863346 3.87188307 1 P 0 ;0,1,2=208,3=0.000000
L 5.82863346 3.87188307 5.83093366 3.87446683 1 P 0 ;0,1,2=208,3=0.000000
L 5.83093366 3.87446683 5.83400039 3.8755 1 P 0 ;0,1,2=208,3=0.000000
L 0.886 2.855 0.93 2.855 1 P 0 
L 0.93 2.855 0.93 2.765 1 P 0 
L 0.93 2.765 0.886 2.765 1 P 0 
L 0.886 2.765 0.886 2.855 1 P 0 
L 0.9345 2.69633317 0.9655 2.69633317 1 P 0 ;0,1,2=209,3=90.000000
L 0.9655 2.69633317 0.9655 2.70591654 1 P 0 ;0,1,2=209,3=90.000000
L 0.9655 2.70591654 0.96394931 2.70898327 1 P 0 ;0,1,2=209,3=90.000000
L 0.96394931 2.70898327 0.96188307 2.7109002 1 P 0 ;0,1,2=209,3=90.000000
L 0.96188307 2.7109002 0.9577497 2.71166673 1 P 0 ;0,1,2=209,3=90.000000
L 0.9577497 2.71166673 0.95361634 2.7109002 1 P 0 ;0,1,2=209,3=90.000000
L 0.95361634 2.7109002 0.95103356 2.7086 1 P 0 ;0,1,2=209,3=90.000000
L 0.95103356 2.7086 0.94948287 2.70591654 1 P 0 ;0,1,2=209,3=90.000000
L 0.94948287 2.70591654 0.94948287 2.69633317 1 P 0 ;0,1,2=209,3=90.000000
L 0.94948287 2.70591654 0.9345 2.71166673 1 P 0 ;0,1,2=209,3=90.000000
L 0.93811585 2.72848287 0.93553307 2.73116634 1 P 0 ;0,1,2=209,3=90.000000
L 0.93553307 2.73116634 0.9345 2.73423307 1 P 0 ;0,1,2=209,3=90.000000
L 0.9345 2.73423307 0.93553307 2.7372998 1 P 0 ;0,1,2=209,3=90.000000
L 0.93553307 2.7372998 0.93863238 2.73998327 1 P 0 ;0,1,2=209,3=90.000000
L 0.93863238 2.73998327 0.94328327 2.7419002 1 P 0 ;0,1,2=209,3=90.000000
L 0.94328327 2.7419002 0.94793327 2.74266673 1 P 0 ;0,1,2=209,3=90.000000
L 0.94793327 2.74266673 0.95361634 2.74266673 1 P 0 ;0,1,2=209,3=90.000000
L 0.95361634 2.74266673 0.95826624 2.7419002 1 P 0 ;0,1,2=209,3=90.000000
L 0.95826624 2.7419002 0.9623997 2.73998327 1 P 0 ;0,1,2=209,3=90.000000
L 0.9623997 2.73998327 0.96446683 2.73768307 1 P 0 ;0,1,2=209,3=90.000000
L 0.96446683 2.73768307 0.9655 2.73499961 1 P 0 ;0,1,2=209,3=90.000000
L 0.9655 2.73499961 0.96446683 2.73193287 1 P 0 ;0,1,2=209,3=90.000000
L 0.96446683 2.73193287 0.9623997 2.72963337 1 P 0 ;0,1,2=209,3=90.000000
L 0.9623997 2.72963337 0.9593003 2.7280997 1 P 0 ;0,1,2=209,3=90.000000
L 0.9593003 2.7280997 0.95516594 2.72733317 1 P 0 ;0,1,2=209,3=90.000000
L 0.95516594 2.72733317 0.9515501 2.7280997 1 P 0 ;0,1,2=209,3=90.000000
L 0.9515501 2.7280997 0.94793327 2.73001663 1 P 0 ;0,1,2=209,3=90.000000
L 0.94793327 2.73001663 0.94586604 2.73231683 1 P 0 ;0,1,2=209,3=90.000000
L 0.94586604 2.73231683 0.94534951 2.73499961 1 P 0 ;0,1,2=209,3=90.000000
L 0.94534951 2.73499961 0.94638268 2.73806634 1 P 0 ;0,1,2=209,3=90.000000
L 0.94638268 2.73806634 0.94896634 2.74036654 1 P 0 ;0,1,2=209,3=90.000000
L 0.94896634 2.74036654 0.95361634 2.74266673 1 P 0 ;0,1,2=209,3=90.000000
L 0.9345 2.76599961 0.9655 2.76599961 1 P 0 ;0,1,2=209,3=90.000000
L 0.9655 2.76599961 0.9593003 2.7613999 1 P 0 ;0,1,2=209,3=90.000000
L 0.9345 2.7613999 0.9345 2.77059931 1 P 0 ;0,1,2=209,3=90.000000
L 0.872 2.468 0.872 2.378 1 P 0 
L 0.828 2.378 0.828 2.468 1 P 0 
L 0.828 2.468 0.872 2.468 1 P 0 
L 0.872 2.378 0.828 2.378 1 P 0 
L 0.8695 2.24583317 0.9005 2.24583317 1 P 0 ;0,1,2=210,3=90.000000
L 0.9005 2.24583317 0.9005 2.25541654 1 P 0 ;0,1,2=210,3=90.000000
L 0.9005 2.25541654 0.89894931 2.25848327 1 P 0 ;0,1,2=210,3=90.000000
L 0.89894931 2.25848327 0.89688307 2.2604002 1 P 0 ;0,1,2=210,3=90.000000
L 0.89688307 2.2604002 0.8927497 2.26116673 1 P 0 ;0,1,2=210,3=90.000000
L 0.8927497 2.26116673 0.88861634 2.2604002 1 P 0 ;0,1,2=210,3=90.000000
L 0.88861634 2.2604002 0.88603356 2.2581 1 P 0 ;0,1,2=210,3=90.000000
L 0.88603356 2.2581 0.88448287 2.25541654 1 P 0 ;0,1,2=210,3=90.000000
L 0.88448287 2.25541654 0.88448287 2.24583317 1 P 0 ;0,1,2=210,3=90.000000
L 0.88448287 2.25541654 0.8695 2.26116673 1 P 0 ;0,1,2=210,3=90.000000
L 0.89533346 2.27721644 0.89843278 2.27951663 1 P 0 ;0,1,2=210,3=90.000000
L 0.89843278 2.27951663 0.89998337 2.2822001 1 P 0 ;0,1,2=210,3=90.000000
L 0.89998337 2.2822001 0.9005 2.28526683 1 P 0 ;0,1,2=210,3=90.000000
L 0.9005 2.28526683 0.89946683 2.2891 1 P 0 ;0,1,2=210,3=90.000000
L 0.89946683 2.2891 0.89688307 2.29178346 1 P 0 ;0,1,2=210,3=90.000000
L 0.89688307 2.29178346 0.89378376 2.29255 1 P 0 ;0,1,2=210,3=90.000000
L 0.89378376 2.29255 0.89068258 2.29216673 1 P 0 ;0,1,2=210,3=90.000000
L 0.89068258 2.29216673 0.8880998 2.29063307 1 P 0 ;0,1,2=210,3=90.000000
L 0.8880998 2.29063307 0.88293327 2.28296663 1 P 0 ;0,1,2=210,3=90.000000
L 0.88293327 2.28296663 0.87931644 2.27951663 1 P 0 ;0,1,2=210,3=90.000000
L 0.87931644 2.27951663 0.87414892 2.27721644 1 P 0 ;0,1,2=210,3=90.000000
L 0.87414892 2.27721644 0.8695 2.2764499 1 P 0 ;0,1,2=210,3=90.000000
L 0.8695 2.2764499 0.8695 2.29255 1 P 0 ;0,1,2=210,3=90.000000
L 0.8695 2.31549961 0.87001654 2.31818307 1 P 0 ;0,1,2=210,3=90.000000
L 0.87001654 2.31818307 0.87156614 2.3212498 1 P 0 ;0,1,2=210,3=90.000000
L 0.87156614 2.3212498 0.87414892 2.32316673 1 P 0 ;0,1,2=210,3=90.000000
L 0.87414892 2.32316673 0.87776673 2.32393327 1 P 0 ;0,1,2=210,3=90.000000
L 0.87776673 2.32393327 0.88138268 2.32316673 1 P 0 ;0,1,2=210,3=90.000000
L 0.88138268 2.32316673 0.88448287 2.32086654 1 P 0 ;0,1,2=210,3=90.000000
L 0.88448287 2.32086654 0.88603356 2.31741654 1 P 0 ;0,1,2=210,3=90.000000
L 0.88603356 2.31741654 0.88603356 2.31358337 1 P 0 ;0,1,2=210,3=90.000000
L 0.88603356 2.31358337 0.88706663 2.31128317 1 P 0 ;0,1,2=210,3=90.000000
L 0.88706663 2.31128317 0.88964941 2.30936614 1 P 0 ;0,1,2=210,3=90.000000
L 0.88964941 2.30936614 0.89326624 2.3085997 1 P 0 ;0,1,2=210,3=90.000000
L 0.89326624 2.3085997 0.89688307 2.3097501 1 P 0 ;0,1,2=210,3=90.000000
L 0.89688307 2.3097501 0.89946683 2.31243287 1 P 0 ;0,1,2=210,3=90.000000
L 0.89946683 2.31243287 0.9005 2.31549961 1 P 0 ;0,1,2=210,3=90.000000
L 0.9005 2.31549961 0.89946683 2.31856634 1 P 0 ;0,1,2=210,3=90.000000
L 0.89946683 2.31856634 0.89688307 2.3212498 1 P 0 ;0,1,2=210,3=90.000000
L 0.89688307 2.3212498 0.89326624 2.3224002 1 P 0 ;0,1,2=210,3=90.000000
L 0.89326624 2.3224002 0.88964941 2.32163307 1 P 0 ;0,1,2=210,3=90.000000
L 0.88964941 2.32163307 0.88706663 2.31971673 1 P 0 ;0,1,2=210,3=90.000000
L 0.88706663 2.31971673 0.88603356 2.31741654 1 P 0 ;0,1,2=210,3=90.000000
L 0.88603356 2.31741654 0.88603356 2.31358337 1 P 0 ;0,1,2=210,3=90.000000
L 0.88603356 2.31358337 0.88448287 2.31013337 1 P 0 ;0,1,2=210,3=90.000000
L 0.88448287 2.31013337 0.88138268 2.30783317 1 P 0 ;0,1,2=210,3=90.000000
L 0.88138268 2.30783317 0.87776673 2.30706663 1 P 0 ;0,1,2=210,3=90.000000
L 0.87776673 2.30706663 0.87414892 2.30783317 1 P 0 ;0,1,2=210,3=90.000000
L 0.87414892 2.30783317 0.87156614 2.3097501 1 P 0 ;0,1,2=210,3=90.000000
L 0.87156614 2.3097501 0.87001654 2.31281683 1 P 0 ;0,1,2=210,3=90.000000
L 0.87001654 2.31281683 0.8695 2.31549961 1 P 0 ;0,1,2=210,3=90.000000
L 0.8695 2.34649961 0.9005 2.34649961 1 P 0 ;0,1,2=210,3=90.000000
L 0.9005 2.34649961 0.8943003 2.3418999 1 P 0 ;0,1,2=210,3=90.000000
L 0.8695 2.3418999 0.8695 2.35109931 1 P 0 ;0,1,2=210,3=90.000000
L 0.874 2.378 0.874 2.468 1 P 0 
L 0.874 2.468 0.918 2.468 1 P 0 
L 0.918 2.468 0.918 2.378 1 P 0 
L 0.918 2.378 0.874 2.378 1 P 0 
L 0.9095 2.24583317 0.9405 2.24583317 1 P 0 ;0,1,2=211,3=90.000000
L 0.9405 2.24583317 0.9405 2.25541654 1 P 0 ;0,1,2=211,3=90.000000
L 0.9405 2.25541654 0.93894931 2.25848327 1 P 0 ;0,1,2=211,3=90.000000
L 0.93894931 2.25848327 0.93688307 2.2604002 1 P 0 ;0,1,2=211,3=90.000000
L 0.93688307 2.2604002 0.9327497 2.26116673 1 P 0 ;0,1,2=211,3=90.000000
L 0.9327497 2.26116673 0.92861634 2.2604002 1 P 0 ;0,1,2=211,3=90.000000
L 0.92861634 2.2604002 0.92603356 2.2581 1 P 0 ;0,1,2=211,3=90.000000
L 0.92603356 2.2581 0.92448287 2.25541654 1 P 0 ;0,1,2=211,3=90.000000
L 0.92448287 2.25541654 0.92448287 2.24583317 1 P 0 ;0,1,2=211,3=90.000000
L 0.92448287 2.25541654 0.9095 2.26116673 1 P 0 ;0,1,2=211,3=90.000000
L 0.91569961 2.27606663 0.91208278 2.27836614 1 P 0 ;0,1,2=211,3=90.000000
L 0.91208278 2.27836614 0.91001654 2.28143287 1 P 0 ;0,1,2=211,3=90.000000
L 0.91001654 2.28143287 0.9095 2.28488356 1 P 0 ;0,1,2=211,3=90.000000
L 0.9095 2.28488356 0.91001654 2.2879503 1 P 0 ;0,1,2=211,3=90.000000
L 0.91001654 2.2879503 0.91259931 2.29101703 1 P 0 ;0,1,2=211,3=90.000000
L 0.91259931 2.29101703 0.91569961 2.29293327 1 P 0 ;0,1,2=211,3=90.000000
L 0.91569961 2.29293327 0.9187999 2.29331654 1 P 0 ;0,1,2=211,3=90.000000
L 0.9187999 2.29331654 0.92241575 2.29255 1 P 0 ;0,1,2=211,3=90.000000
L 0.92241575 2.29255 0.92499951 2.28986654 1 P 0 ;0,1,2=211,3=90.000000
L 0.92499951 2.28986654 0.92603356 2.28718307 1 P 0 ;0,1,2=211,3=90.000000
L 0.92603356 2.28718307 0.92603356 2.28373307 1 P 0 ;0,1,2=211,3=90.000000
L 0.92603356 2.28718307 0.92758317 2.28948327 1 P 0 ;0,1,2=211,3=90.000000
L 0.92758317 2.28948327 0.93016594 2.2914002 1 P 0 ;0,1,2=211,3=90.000000
L 0.93016594 2.2914002 0.93326624 2.29216673 1 P 0 ;0,1,2=211,3=90.000000
L 0.93326624 2.29216673 0.93636654 2.2914002 1 P 0 ;0,1,2=211,3=90.000000
L 0.93636654 2.2914002 0.93894931 2.28948327 1 P 0 ;0,1,2=211,3=90.000000
L 0.93894931 2.28948327 0.9405 2.28603327 1 P 0 ;0,1,2=211,3=90.000000
L 0.9405 2.28603327 0.93998337 2.28258337 1 P 0 ;0,1,2=211,3=90.000000
L 0.93998337 2.28258337 0.93791624 2.27913337 1 P 0 ;0,1,2=211,3=90.000000
L 0.9095 2.31549961 0.9405 2.31549961 1 P 0 ;0,1,2=211,3=90.000000
L 0.9405 2.31549961 0.9343003 2.3108999 1 P 0 ;0,1,2=211,3=90.000000
L 0.9095 2.3108999 0.9095 2.32009931 1 P 0 ;0,1,2=211,3=90.000000
L 0.9095 2.3511 0.9405 2.3511 1 P 0 ;0,1,2=211,3=90.000000
L 0.9405 2.3511 0.91828327 2.33691624 1 P 0 ;0,1,2=211,3=90.000000
L 0.91828327 2.33691624 0.91828327 2.35608366 1 P 0 ;0,1,2=211,3=90.000000
L 1.104 0.74 1.104 0.696 1 P 0 
L 1.104 0.696 1.014 0.696 1 P 0 
L 1.014 0.696 1.014 0.74 1 P 0 
L 1.014 0.74 1.104 0.74 1 P 0 
L 1.10416683 0.6495 1.10416683 0.6805 1 P 0 ;0,1,2=212,3=0.000000
L 1.10416683 0.6805 1.09458346 0.6805 1 P 0 ;0,1,2=212,3=0.000000
L 1.09458346 0.6805 1.09151673 0.67894931 1 P 0 ;0,1,2=212,3=0.000000
L 1.09151673 0.67894931 1.0895998 0.67688307 1 P 0 ;0,1,2=212,3=0.000000
L 1.0895998 0.67688307 1.08883327 0.6727497 1 P 0 ;0,1,2=212,3=0.000000
L 1.08883327 0.6727497 1.0895998 0.66861634 1 P 0 ;0,1,2=212,3=0.000000
L 1.0895998 0.66861634 1.0919 0.66603356 1 P 0 ;0,1,2=212,3=0.000000
L 1.0919 0.66603356 1.09458346 0.66448287 1 P 0 ;0,1,2=212,3=0.000000
L 1.09458346 0.66448287 1.10416683 0.66448287 1 P 0 ;0,1,2=212,3=0.000000
L 1.09458346 0.66448287 1.08883327 0.6495 1 P 0 ;0,1,2=212,3=0.000000
L 1.07393337 0.65569961 1.07163386 0.65208278 1 P 0 ;0,1,2=212,3=0.000000
L 1.07163386 0.65208278 1.06856713 0.65001654 1 P 0 ;0,1,2=212,3=0.000000
L 1.06856713 0.65001654 1.06511644 0.6495 1 P 0 ;0,1,2=212,3=0.000000
L 1.06511644 0.6495 1.0620497 0.65001654 1 P 0 ;0,1,2=212,3=0.000000
L 1.0620497 0.65001654 1.05898297 0.65259931 1 P 0 ;0,1,2=212,3=0.000000
L 1.05898297 0.65259931 1.05706673 0.65569961 1 P 0 ;0,1,2=212,3=0.000000
L 1.05706673 0.65569961 1.05668346 0.6587999 1 P 0 ;0,1,2=212,3=0.000000
L 1.05668346 0.6587999 1.05745 0.66241575 1 P 0 ;0,1,2=212,3=0.000000
L 1.05745 0.66241575 1.06013346 0.66499951 1 P 0 ;0,1,2=212,3=0.000000
L 1.06013346 0.66499951 1.06281693 0.66603356 1 P 0 ;0,1,2=212,3=0.000000
L 1.06281693 0.66603356 1.06626693 0.66603356 1 P 0 ;0,1,2=212,3=0.000000
L 1.06281693 0.66603356 1.06051673 0.66758317 1 P 0 ;0,1,2=212,3=0.000000
L 1.06051673 0.66758317 1.0585998 0.67016594 1 P 0 ;0,1,2=212,3=0.000000
L 1.0585998 0.67016594 1.05783327 0.67326624 1 P 0 ;0,1,2=212,3=0.000000
L 1.05783327 0.67326624 1.0585998 0.67636654 1 P 0 ;0,1,2=212,3=0.000000
L 1.0585998 0.67636654 1.06051673 0.67894931 1 P 0 ;0,1,2=212,3=0.000000
L 1.06051673 0.67894931 1.06396673 0.6805 1 P 0 ;0,1,2=212,3=0.000000
L 1.06396673 0.6805 1.06741663 0.67998337 1 P 0 ;0,1,2=212,3=0.000000
L 1.06741663 0.67998337 1.07086663 0.67791624 1 P 0 ;0,1,2=212,3=0.000000
L 1.0299 0.6495 1.0299 0.6805 1 P 0 ;0,1,2=212,3=0.000000
L 1.0299 0.6805 1.04408376 0.65828327 1 P 0 ;0,1,2=212,3=0.000000
L 1.04408376 0.65828327 1.02491634 0.65828327 1 P 0 ;0,1,2=212,3=0.000000
L 0.9989 0.6495 0.9989 0.6805 1 P 0 ;0,1,2=212,3=0.000000
L 0.9989 0.6805 1.01308376 0.65828327 1 P 0 ;0,1,2=212,3=0.000000
L 1.01308376 0.65828327 0.99391634 0.65828327 1 P 0 ;0,1,2=212,3=0.000000
L 1.2398 0.6807 1.2398 0.6367 1 P 0 
L 1.1498 0.6807 1.2398 0.6807 1 P 0 
L 1.2398 0.6367 1.1498 0.6367 1 P 0 
L 1.1498 0.6367 1.1498 0.6807 1 P 0 
L 1.23466683 0.5945 1.23466683 0.6255 1 P 0 ;0,1,2=213,3=0.000000
L 1.23466683 0.6255 1.22508346 0.6255 1 P 0 ;0,1,2=213,3=0.000000
L 1.22508346 0.6255 1.22201673 0.62394931 1 P 0 ;0,1,2=213,3=0.000000
L 1.22201673 0.62394931 1.2200998 0.62188307 1 P 0 ;0,1,2=213,3=0.000000
L 1.2200998 0.62188307 1.21933327 0.6177497 1 P 0 ;0,1,2=213,3=0.000000
L 1.21933327 0.6177497 1.2200998 0.61361634 1 P 0 ;0,1,2=213,3=0.000000
L 1.2200998 0.61361634 1.2224 0.61103356 1 P 0 ;0,1,2=213,3=0.000000
L 1.2224 0.61103356 1.22508346 0.60948287 1 P 0 ;0,1,2=213,3=0.000000
L 1.22508346 0.60948287 1.23466683 0.60948287 1 P 0 ;0,1,2=213,3=0.000000
L 1.22508346 0.60948287 1.21933327 0.5945 1 P 0 ;0,1,2=213,3=0.000000
L 1.19600039 0.5945 1.19600039 0.6255 1 P 0 ;0,1,2=213,3=0.000000
L 1.19600039 0.6255 1.2006001 0.6193003 1 P 0 ;0,1,2=213,3=0.000000
L 1.2006001 0.5945 1.19140069 0.5945 1 P 0 ;0,1,2=213,3=0.000000
L 1.17151713 0.59811585 1.16883366 0.59553307 1 P 0 ;0,1,2=213,3=0.000000
L 1.16883366 0.59553307 1.16576693 0.5945 1 P 0 ;0,1,2=213,3=0.000000
L 1.16576693 0.5945 1.1627002 0.59553307 1 P 0 ;0,1,2=213,3=0.000000
L 1.1627002 0.59553307 1.16001673 0.59863238 1 P 0 ;0,1,2=213,3=0.000000
L 1.16001673 0.59863238 1.1580998 0.60328327 1 P 0 ;0,1,2=213,3=0.000000
L 1.1580998 0.60328327 1.15733327 0.60793327 1 P 0 ;0,1,2=213,3=0.000000
L 1.15733327 0.60793327 1.15733327 0.61361634 1 P 0 ;0,1,2=213,3=0.000000
L 1.15733327 0.61361634 1.1580998 0.61826624 1 P 0 ;0,1,2=213,3=0.000000
L 1.1580998 0.61826624 1.16001673 0.6223997 1 P 0 ;0,1,2=213,3=0.000000
L 1.16001673 0.6223997 1.16231693 0.62446683 1 P 0 ;0,1,2=213,3=0.000000
L 1.16231693 0.62446683 1.16500039 0.6255 1 P 0 ;0,1,2=213,3=0.000000
L 1.16500039 0.6255 1.16806713 0.62446683 1 P 0 ;0,1,2=213,3=0.000000
L 1.16806713 0.62446683 1.17036663 0.6223997 1 P 0 ;0,1,2=213,3=0.000000
L 1.17036663 0.6223997 1.1719003 0.6193003 1 P 0 ;0,1,2=213,3=0.000000
L 1.1719003 0.6193003 1.17266683 0.61516594 1 P 0 ;0,1,2=213,3=0.000000
L 1.17266683 0.61516594 1.1719003 0.6115501 1 P 0 ;0,1,2=213,3=0.000000
L 1.1719003 0.6115501 1.16998337 0.60793327 1 P 0 ;0,1,2=213,3=0.000000
L 1.16998337 0.60793327 1.16768317 0.60586604 1 P 0 ;0,1,2=213,3=0.000000
L 1.16768317 0.60586604 1.16500039 0.60534951 1 P 0 ;0,1,2=213,3=0.000000
L 1.16500039 0.60534951 1.16193366 0.60638268 1 P 0 ;0,1,2=213,3=0.000000
L 1.16193366 0.60638268 1.15963346 0.60896634 1 P 0 ;0,1,2=213,3=0.000000
L 1.15963346 0.60896634 1.15733327 0.61361634 1 P 0 ;0,1,2=213,3=0.000000
L 1.14051713 0.59811585 1.13783366 0.59553307 1 P 0 ;0,1,2=213,3=0.000000
L 1.13783366 0.59553307 1.13476693 0.5945 1 P 0 ;0,1,2=213,3=0.000000
L 1.13476693 0.5945 1.1317002 0.59553307 1 P 0 ;0,1,2=213,3=0.000000
L 1.1317002 0.59553307 1.12901673 0.59863238 1 P 0 ;0,1,2=213,3=0.000000
L 1.12901673 0.59863238 1.1270998 0.60328327 1 P 0 ;0,1,2=213,3=0.000000
L 1.1270998 0.60328327 1.12633327 0.60793327 1 P 0 ;0,1,2=213,3=0.000000
L 1.12633327 0.60793327 1.12633327 0.61361634 1 P 0 ;0,1,2=213,3=0.000000
L 1.12633327 0.61361634 1.1270998 0.61826624 1 P 0 ;0,1,2=213,3=0.000000
L 1.1270998 0.61826624 1.12901673 0.6223997 1 P 0 ;0,1,2=213,3=0.000000
L 1.12901673 0.6223997 1.13131693 0.62446683 1 P 0 ;0,1,2=213,3=0.000000
L 1.13131693 0.62446683 1.13400039 0.6255 1 P 0 ;0,1,2=213,3=0.000000
L 1.13400039 0.6255 1.13706713 0.62446683 1 P 0 ;0,1,2=213,3=0.000000
L 1.13706713 0.62446683 1.13936663 0.6223997 1 P 0 ;0,1,2=213,3=0.000000
L 1.13936663 0.6223997 1.1409003 0.6193003 1 P 0 ;0,1,2=213,3=0.000000
L 1.1409003 0.6193003 1.14166683 0.61516594 1 P 0 ;0,1,2=213,3=0.000000
L 1.14166683 0.61516594 1.1409003 0.6115501 1 P 0 ;0,1,2=213,3=0.000000
L 1.1409003 0.6115501 1.13898337 0.60793327 1 P 0 ;0,1,2=213,3=0.000000
L 1.13898337 0.60793327 1.13668317 0.60586604 1 P 0 ;0,1,2=213,3=0.000000
L 1.13668317 0.60586604 1.13400039 0.60534951 1 P 0 ;0,1,2=213,3=0.000000
L 1.13400039 0.60534951 1.13093366 0.60638268 1 P 0 ;0,1,2=213,3=0.000000
L 1.13093366 0.60638268 1.12863346 0.60896634 1 P 0 ;0,1,2=213,3=0.000000
L 1.12863346 0.60896634 1.12633327 0.61361634 1 P 0 ;0,1,2=213,3=0.000000
L 1.10300039 0.5945 1.10300039 0.6255 1 P 0 ;0,1,2=213,3=0.000000
L 1.10300039 0.6255 1.1076001 0.6193003 1 P 0 ;0,1,2=213,3=0.000000
L 1.1076001 0.5945 1.09840069 0.5945 1 P 0 ;0,1,2=213,3=0.000000
L 0.693 2.378 0.693 2.468 1 P 0 
L 0.693 2.468 0.737 2.468 1 P 0 
L 0.737 2.468 0.737 2.378 1 P 0 
L 0.737 2.378 0.693 2.378 1 P 0 
L 0.5545 2.35383317 0.5855 2.35383317 1 P 0 ;0,1,2=214,3=90.000000
L 0.5855 2.35383317 0.5855 2.36341654 1 P 0 ;0,1,2=214,3=90.000000
L 0.5855 2.36341654 0.58394931 2.36648327 1 P 0 ;0,1,2=214,3=90.000000
L 0.58394931 2.36648327 0.58188307 2.3684002 1 P 0 ;0,1,2=214,3=90.000000
L 0.58188307 2.3684002 0.5777497 2.36916673 1 P 0 ;0,1,2=214,3=90.000000
L 0.5777497 2.36916673 0.57361634 2.3684002 1 P 0 ;0,1,2=214,3=90.000000
L 0.57361634 2.3684002 0.57103356 2.3661 1 P 0 ;0,1,2=214,3=90.000000
L 0.57103356 2.3661 0.56948287 2.36341654 1 P 0 ;0,1,2=214,3=90.000000
L 0.56948287 2.36341654 0.56948287 2.35383317 1 P 0 ;0,1,2=214,3=90.000000
L 0.56948287 2.36341654 0.5545 2.36916673 1 P 0 ;0,1,2=214,3=90.000000
L 0.58033346 2.38521644 0.58343278 2.38751663 1 P 0 ;0,1,2=214,3=90.000000
L 0.58343278 2.38751663 0.58498337 2.3902001 1 P 0 ;0,1,2=214,3=90.000000
L 0.58498337 2.3902001 0.5855 2.39326683 1 P 0 ;0,1,2=214,3=90.000000
L 0.5855 2.39326683 0.58446683 2.3971 1 P 0 ;0,1,2=214,3=90.000000
L 0.58446683 2.3971 0.58188307 2.39978346 1 P 0 ;0,1,2=214,3=90.000000
L 0.58188307 2.39978346 0.57878376 2.40055 1 P 0 ;0,1,2=214,3=90.000000
L 0.57878376 2.40055 0.57568258 2.40016673 1 P 0 ;0,1,2=214,3=90.000000
L 0.57568258 2.40016673 0.5730998 2.39863307 1 P 0 ;0,1,2=214,3=90.000000
L 0.5730998 2.39863307 0.56793327 2.39096663 1 P 0 ;0,1,2=214,3=90.000000
L 0.56793327 2.39096663 0.56431644 2.38751663 1 P 0 ;0,1,2=214,3=90.000000
L 0.56431644 2.38751663 0.55914892 2.38521644 1 P 0 ;0,1,2=214,3=90.000000
L 0.55914892 2.38521644 0.5545 2.3844499 1 P 0 ;0,1,2=214,3=90.000000
L 0.5545 2.3844499 0.5545 2.40055 1 P 0 ;0,1,2=214,3=90.000000
L 0.5545 2.42349961 0.55501654 2.42618307 1 P 0 ;0,1,2=214,3=90.000000
L 0.55501654 2.42618307 0.55656614 2.4292498 1 P 0 ;0,1,2=214,3=90.000000
L 0.55656614 2.4292498 0.55914892 2.43116673 1 P 0 ;0,1,2=214,3=90.000000
L 0.55914892 2.43116673 0.56276673 2.43193327 1 P 0 ;0,1,2=214,3=90.000000
L 0.56276673 2.43193327 0.56638268 2.43116673 1 P 0 ;0,1,2=214,3=90.000000
L 0.56638268 2.43116673 0.56948287 2.42886654 1 P 0 ;0,1,2=214,3=90.000000
L 0.56948287 2.42886654 0.57103356 2.42541654 1 P 0 ;0,1,2=214,3=90.000000
L 0.57103356 2.42541654 0.57103356 2.42158337 1 P 0 ;0,1,2=214,3=90.000000
L 0.57103356 2.42158337 0.57206663 2.41928317 1 P 0 ;0,1,2=214,3=90.000000
L 0.57206663 2.41928317 0.57464941 2.41736614 1 P 0 ;0,1,2=214,3=90.000000
L 0.57464941 2.41736614 0.57826624 2.4165997 1 P 0 ;0,1,2=214,3=90.000000
L 0.57826624 2.4165997 0.58188307 2.4177501 1 P 0 ;0,1,2=214,3=90.000000
L 0.58188307 2.4177501 0.58446683 2.42043287 1 P 0 ;0,1,2=214,3=90.000000
L 0.58446683 2.42043287 0.5855 2.42349961 1 P 0 ;0,1,2=214,3=90.000000
L 0.5855 2.42349961 0.58446683 2.42656634 1 P 0 ;0,1,2=214,3=90.000000
L 0.58446683 2.42656634 0.58188307 2.4292498 1 P 0 ;0,1,2=214,3=90.000000
L 0.58188307 2.4292498 0.57826624 2.4304002 1 P 0 ;0,1,2=214,3=90.000000
L 0.57826624 2.4304002 0.57464941 2.42963307 1 P 0 ;0,1,2=214,3=90.000000
L 0.57464941 2.42963307 0.57206663 2.42771673 1 P 0 ;0,1,2=214,3=90.000000
L 0.57206663 2.42771673 0.57103356 2.42541654 1 P 0 ;0,1,2=214,3=90.000000
L 0.57103356 2.42541654 0.57103356 2.42158337 1 P 0 ;0,1,2=214,3=90.000000
L 0.57103356 2.42158337 0.56948287 2.41813337 1 P 0 ;0,1,2=214,3=90.000000
L 0.56948287 2.41813337 0.56638268 2.41583317 1 P 0 ;0,1,2=214,3=90.000000
L 0.56638268 2.41583317 0.56276673 2.41506663 1 P 0 ;0,1,2=214,3=90.000000
L 0.56276673 2.41506663 0.55914892 2.41583317 1 P 0 ;0,1,2=214,3=90.000000
L 0.55914892 2.41583317 0.55656614 2.4177501 1 P 0 ;0,1,2=214,3=90.000000
L 0.55656614 2.4177501 0.55501654 2.42081683 1 P 0 ;0,1,2=214,3=90.000000
L 0.55501654 2.42081683 0.5545 2.42349961 1 P 0 ;0,1,2=214,3=90.000000
L 0.58033346 2.44721644 0.58343278 2.44951663 1 P 0 ;0,1,2=214,3=90.000000
L 0.58343278 2.44951663 0.58498337 2.4522001 1 P 0 ;0,1,2=214,3=90.000000
L 0.58498337 2.4522001 0.5855 2.45526683 1 P 0 ;0,1,2=214,3=90.000000
L 0.5855 2.45526683 0.58446683 2.4591 1 P 0 ;0,1,2=214,3=90.000000
L 0.58446683 2.4591 0.58188307 2.46178346 1 P 0 ;0,1,2=214,3=90.000000
L 0.58188307 2.46178346 0.57878376 2.46255 1 P 0 ;0,1,2=214,3=90.000000
L 0.57878376 2.46255 0.57568258 2.46216673 1 P 0 ;0,1,2=214,3=90.000000
L 0.57568258 2.46216673 0.5730998 2.46063307 1 P 0 ;0,1,2=214,3=90.000000
L 0.5730998 2.46063307 0.56793327 2.45296663 1 P 0 ;0,1,2=214,3=90.000000
L 0.56793327 2.45296663 0.56431644 2.44951663 1 P 0 ;0,1,2=214,3=90.000000
L 0.56431644 2.44951663 0.55914892 2.44721644 1 P 0 ;0,1,2=214,3=90.000000
L 0.55914892 2.44721644 0.5545 2.4464499 1 P 0 ;0,1,2=214,3=90.000000
L 0.5545 2.4464499 0.5545 2.46255 1 P 0 ;0,1,2=214,3=90.000000
L 0.827 2.468 0.827 2.378 1 P 0 
L 0.827 2.378 0.783 2.378 1 P 0 
L 0.783 2.378 0.783 2.468 1 P 0 
L 0.783 2.468 0.827 2.468 1 P 0 
L 0.6345 2.35583317 0.6655 2.35583317 1 P 0 ;0,1,2=215,3=90.000000
L 0.6655 2.35583317 0.6655 2.36541654 1 P 0 ;0,1,2=215,3=90.000000
L 0.6655 2.36541654 0.66394931 2.36848327 1 P 0 ;0,1,2=215,3=90.000000
L 0.66394931 2.36848327 0.66188307 2.3704002 1 P 0 ;0,1,2=215,3=90.000000
L 0.66188307 2.3704002 0.6577497 2.37116673 1 P 0 ;0,1,2=215,3=90.000000
L 0.6577497 2.37116673 0.65361634 2.3704002 1 P 0 ;0,1,2=215,3=90.000000
L 0.65361634 2.3704002 0.65103356 2.3681 1 P 0 ;0,1,2=215,3=90.000000
L 0.65103356 2.3681 0.64948287 2.36541654 1 P 0 ;0,1,2=215,3=90.000000
L 0.64948287 2.36541654 0.64948287 2.35583317 1 P 0 ;0,1,2=215,3=90.000000
L 0.64948287 2.36541654 0.6345 2.37116673 1 P 0 ;0,1,2=215,3=90.000000
L 0.64069961 2.38606663 0.63708278 2.38836614 1 P 0 ;0,1,2=215,3=90.000000
L 0.63708278 2.38836614 0.63501654 2.39143287 1 P 0 ;0,1,2=215,3=90.000000
L 0.63501654 2.39143287 0.6345 2.39488356 1 P 0 ;0,1,2=215,3=90.000000
L 0.6345 2.39488356 0.63501654 2.3979503 1 P 0 ;0,1,2=215,3=90.000000
L 0.63501654 2.3979503 0.63759931 2.40101703 1 P 0 ;0,1,2=215,3=90.000000
L 0.63759931 2.40101703 0.64069961 2.40293327 1 P 0 ;0,1,2=215,3=90.000000
L 0.64069961 2.40293327 0.6437999 2.40331654 1 P 0 ;0,1,2=215,3=90.000000
L 0.6437999 2.40331654 0.64741575 2.40255 1 P 0 ;0,1,2=215,3=90.000000
L 0.64741575 2.40255 0.64999951 2.39986654 1 P 0 ;0,1,2=215,3=90.000000
L 0.64999951 2.39986654 0.65103356 2.39718307 1 P 0 ;0,1,2=215,3=90.000000
L 0.65103356 2.39718307 0.65103356 2.39373307 1 P 0 ;0,1,2=215,3=90.000000
L 0.65103356 2.39718307 0.65258317 2.39948327 1 P 0 ;0,1,2=215,3=90.000000
L 0.65258317 2.39948327 0.65516594 2.4014002 1 P 0 ;0,1,2=215,3=90.000000
L 0.65516594 2.4014002 0.65826624 2.40216673 1 P 0 ;0,1,2=215,3=90.000000
L 0.65826624 2.40216673 0.66136654 2.4014002 1 P 0 ;0,1,2=215,3=90.000000
L 0.66136654 2.4014002 0.66394931 2.39948327 1 P 0 ;0,1,2=215,3=90.000000
L 0.66394931 2.39948327 0.6655 2.39603327 1 P 0 ;0,1,2=215,3=90.000000
L 0.6655 2.39603327 0.66498337 2.39258337 1 P 0 ;0,1,2=215,3=90.000000
L 0.66498337 2.39258337 0.66291624 2.38913337 1 P 0 ;0,1,2=215,3=90.000000
L 0.6345 2.42549961 0.6655 2.42549961 1 P 0 ;0,1,2=215,3=90.000000
L 0.6655 2.42549961 0.6593003 2.4208999 1 P 0 ;0,1,2=215,3=90.000000
L 0.6345 2.4208999 0.6345 2.43009931 1 P 0 ;0,1,2=215,3=90.000000
L 0.64741575 2.44921644 0.65103356 2.4518999 1 P 0 ;0,1,2=215,3=90.000000
L 0.65103356 2.4518999 0.6530998 2.4542001 1 P 0 ;0,1,2=215,3=90.000000
L 0.6530998 2.4542001 0.65413287 2.45726683 1 P 0 ;0,1,2=215,3=90.000000
L 0.65413287 2.45726683 0.6530998 2.4599503 1 P 0 ;0,1,2=215,3=90.000000
L 0.6530998 2.4599503 0.65103356 2.46186654 1 P 0 ;0,1,2=215,3=90.000000
L 0.65103356 2.46186654 0.64793327 2.4634002 1 P 0 ;0,1,2=215,3=90.000000
L 0.64793327 2.4634002 0.64431644 2.46378346 1 P 0 ;0,1,2=215,3=90.000000
L 0.64431644 2.46378346 0.64121614 2.4634002 1 P 0 ;0,1,2=215,3=90.000000
L 0.64121614 2.4634002 0.63811585 2.46186654 1 P 0 ;0,1,2=215,3=90.000000
L 0.63811585 2.46186654 0.63553307 2.45956634 1 P 0 ;0,1,2=215,3=90.000000
L 0.63553307 2.45956634 0.6345 2.45688356 1 P 0 ;0,1,2=215,3=90.000000
L 0.6345 2.45688356 0.63553307 2.45381683 1 P 0 ;0,1,2=215,3=90.000000
L 0.63553307 2.45381683 0.63863238 2.45113337 1 P 0 ;0,1,2=215,3=90.000000
L 0.63863238 2.45113337 0.64328327 2.4495997 1 P 0 ;0,1,2=215,3=90.000000
L 0.64328327 2.4495997 0.6484498 2.44921644 1 P 0 ;0,1,2=215,3=90.000000
L 0.6484498 2.44921644 0.65516594 2.44998287 1 P 0 ;0,1,2=215,3=90.000000
L 0.65516594 2.44998287 0.65878376 2.45113337 1 P 0 ;0,1,2=215,3=90.000000
L 0.65878376 2.45113337 0.6623997 2.45304961 1 P 0 ;0,1,2=215,3=90.000000
L 0.6623997 2.45304961 0.66498337 2.45573307 1 P 0 ;0,1,2=215,3=90.000000
L 0.66498337 2.45573307 0.6655 2.45841654 1 P 0 ;0,1,2=215,3=90.000000
L 0.6655 2.45841654 0.66446683 2.4611 1 P 0 ;0,1,2=215,3=90.000000
L 0.66446683 2.4611 0.66188307 2.46301703 1 P 0 ;0,1,2=215,3=90.000000
L 0.782 2.468 0.782 2.378 1 P 0 
L 0.782 2.378 0.738 2.378 1 P 0 
L 0.738 2.378 0.738 2.468 1 P 0 
L 0.738 2.468 0.782 2.468 1 P 0 
L 0.5945 2.35383317 0.6255 2.35383317 1 P 0 ;0,1,2=216,3=90.000000
L 0.6255 2.35383317 0.6255 2.36341654 1 P 0 ;0,1,2=216,3=90.000000
L 0.6255 2.36341654 0.62394931 2.36648327 1 P 0 ;0,1,2=216,3=90.000000
L 0.62394931 2.36648327 0.62188307 2.3684002 1 P 0 ;0,1,2=216,3=90.000000
L 0.62188307 2.3684002 0.6177497 2.36916673 1 P 0 ;0,1,2=216,3=90.000000
L 0.6177497 2.36916673 0.61361634 2.3684002 1 P 0 ;0,1,2=216,3=90.000000
L 0.61361634 2.3684002 0.61103356 2.3661 1 P 0 ;0,1,2=216,3=90.000000
L 0.61103356 2.3661 0.60948287 2.36341654 1 P 0 ;0,1,2=216,3=90.000000
L 0.60948287 2.36341654 0.60948287 2.35383317 1 P 0 ;0,1,2=216,3=90.000000
L 0.60948287 2.36341654 0.5945 2.36916673 1 P 0 ;0,1,2=216,3=90.000000
L 0.60069961 2.38406663 0.59708278 2.38636614 1 P 0 ;0,1,2=216,3=90.000000
L 0.59708278 2.38636614 0.59501654 2.38943287 1 P 0 ;0,1,2=216,3=90.000000
L 0.59501654 2.38943287 0.5945 2.39288356 1 P 0 ;0,1,2=216,3=90.000000
L 0.5945 2.39288356 0.59501654 2.3959503 1 P 0 ;0,1,2=216,3=90.000000
L 0.59501654 2.3959503 0.59759931 2.39901703 1 P 0 ;0,1,2=216,3=90.000000
L 0.59759931 2.39901703 0.60069961 2.40093327 1 P 0 ;0,1,2=216,3=90.000000
L 0.60069961 2.40093327 0.6037999 2.40131654 1 P 0 ;0,1,2=216,3=90.000000
L 0.6037999 2.40131654 0.60741575 2.40055 1 P 0 ;0,1,2=216,3=90.000000
L 0.60741575 2.40055 0.60999951 2.39786654 1 P 0 ;0,1,2=216,3=90.000000
L 0.60999951 2.39786654 0.61103356 2.39518307 1 P 0 ;0,1,2=216,3=90.000000
L 0.61103356 2.39518307 0.61103356 2.39173307 1 P 0 ;0,1,2=216,3=90.000000
L 0.61103356 2.39518307 0.61258317 2.39748327 1 P 0 ;0,1,2=216,3=90.000000
L 0.61258317 2.39748327 0.61516594 2.3994002 1 P 0 ;0,1,2=216,3=90.000000
L 0.61516594 2.3994002 0.61826624 2.40016673 1 P 0 ;0,1,2=216,3=90.000000
L 0.61826624 2.40016673 0.62136654 2.3994002 1 P 0 ;0,1,2=216,3=90.000000
L 0.62136654 2.3994002 0.62394931 2.39748327 1 P 0 ;0,1,2=216,3=90.000000
L 0.62394931 2.39748327 0.6255 2.39403327 1 P 0 ;0,1,2=216,3=90.000000
L 0.6255 2.39403327 0.62498337 2.39058337 1 P 0 ;0,1,2=216,3=90.000000
L 0.62498337 2.39058337 0.62291624 2.38713337 1 P 0 ;0,1,2=216,3=90.000000
L 0.5945 2.42349961 0.6255 2.42349961 1 P 0 ;0,1,2=216,3=90.000000
L 0.6255 2.42349961 0.6193003 2.4188999 1 P 0 ;0,1,2=216,3=90.000000
L 0.5945 2.4188999 0.5945 2.42809931 1 P 0 ;0,1,2=216,3=90.000000
L 0.59914892 2.44606663 0.59656614 2.44836614 1 P 0 ;0,1,2=216,3=90.000000
L 0.59656614 2.44836614 0.59501654 2.45104961 1 P 0 ;0,1,2=216,3=90.000000
L 0.59501654 2.45104961 0.5945 2.45449961 1 P 0 ;0,1,2=216,3=90.000000
L 0.5945 2.45449961 0.59553307 2.4579503 1 P 0 ;0,1,2=216,3=90.000000
L 0.59553307 2.4579503 0.59759931 2.46063307 1 P 0 ;0,1,2=216,3=90.000000
L 0.59759931 2.46063307 0.60121614 2.46255 1 P 0 ;0,1,2=216,3=90.000000
L 0.60121614 2.46255 0.60534951 2.46293327 1 P 0 ;0,1,2=216,3=90.000000
L 0.60534951 2.46293327 0.60948287 2.46216673 1 P 0 ;0,1,2=216,3=90.000000
L 0.60948287 2.46216673 0.61206663 2.4602498 1 P 0 ;0,1,2=216,3=90.000000
L 0.61206663 2.4602498 0.61413287 2.45756634 1 P 0 ;0,1,2=216,3=90.000000
L 0.61413287 2.45756634 0.61464941 2.45488356 1 P 0 ;0,1,2=216,3=90.000000
L 0.61464941 2.45488356 0.61413287 2.4522001 1 P 0 ;0,1,2=216,3=90.000000
L 0.61413287 2.4522001 0.61206663 2.4487501 1 P 0 ;0,1,2=216,3=90.000000
L 0.61206663 2.4487501 0.6255 2.4498999 1 P 0 ;0,1,2=216,3=90.000000
L 0.6255 2.4498999 0.6255 2.4602498 1 P 0 ;0,1,2=216,3=90.000000
L 0.874 1.616 0.874 1.572 1 P 0 
L 0.874 1.572 0.784 1.572 1 P 0 
L 0.784 1.572 0.784 1.616 1 P 0 
L 0.784 1.616 0.874 1.616 1 P 0 
L 0.85266683 1.3885 0.85266683 1.4195 1 P 0 ;0,1,2=217,3=0.000000
L 0.85266683 1.4195 0.84308346 1.4195 1 P 0 ;0,1,2=217,3=0.000000
L 0.84308346 1.4195 0.84001673 1.41794931 1 P 0 ;0,1,2=217,3=0.000000
L 0.84001673 1.41794931 0.8380998 1.41588307 1 P 0 ;0,1,2=217,3=0.000000
L 0.8380998 1.41588307 0.83733327 1.4117497 1 P 0 ;0,1,2=217,3=0.000000
L 0.83733327 1.4117497 0.8380998 1.40761634 1 P 0 ;0,1,2=217,3=0.000000
L 0.8380998 1.40761634 0.8404 1.40503356 1 P 0 ;0,1,2=217,3=0.000000
L 0.8404 1.40503356 0.84308346 1.40348287 1 P 0 ;0,1,2=217,3=0.000000
L 0.84308346 1.40348287 0.85266683 1.40348287 1 P 0 ;0,1,2=217,3=0.000000
L 0.84308346 1.40348287 0.83733327 1.3885 1 P 0 ;0,1,2=217,3=0.000000
L 0.82128356 1.41433346 0.81898337 1.41743278 1 P 0 ;0,1,2=217,3=0.000000
L 0.81898337 1.41743278 0.8162999 1.41898337 1 P 0 ;0,1,2=217,3=0.000000
L 0.8162999 1.41898337 0.81323317 1.4195 1 P 0 ;0,1,2=217,3=0.000000
L 0.81323317 1.4195 0.8094 1.41846683 1 P 0 ;0,1,2=217,3=0.000000
L 0.8094 1.41846683 0.80671654 1.41588307 1 P 0 ;0,1,2=217,3=0.000000
L 0.80671654 1.41588307 0.80595 1.41278376 1 P 0 ;0,1,2=217,3=0.000000
L 0.80595 1.41278376 0.80633327 1.40968258 1 P 0 ;0,1,2=217,3=0.000000
L 0.80633327 1.40968258 0.80786693 1.4070998 1 P 0 ;0,1,2=217,3=0.000000
L 0.80786693 1.4070998 0.81553337 1.40193327 1 P 0 ;0,1,2=217,3=0.000000
L 0.81553337 1.40193327 0.81898337 1.39831644 1 P 0 ;0,1,2=217,3=0.000000
L 0.81898337 1.39831644 0.82128356 1.39314892 1 P 0 ;0,1,2=217,3=0.000000
L 0.82128356 1.39314892 0.8220501 1.3885 1 P 0 ;0,1,2=217,3=0.000000
L 0.8220501 1.3885 0.80595 1.3885 1 P 0 ;0,1,2=217,3=0.000000
L 0.79028356 1.40141575 0.7876001 1.40503356 1 P 0 ;0,1,2=217,3=0.000000
L 0.7876001 1.40503356 0.7852999 1.4070998 1 P 0 ;0,1,2=217,3=0.000000
L 0.7852999 1.4070998 0.78223317 1.40813287 1 P 0 ;0,1,2=217,3=0.000000
L 0.78223317 1.40813287 0.7795497 1.4070998 1 P 0 ;0,1,2=217,3=0.000000
L 0.7795497 1.4070998 0.77763346 1.40503356 1 P 0 ;0,1,2=217,3=0.000000
L 0.77763346 1.40503356 0.7760998 1.40193327 1 P 0 ;0,1,2=217,3=0.000000
L 0.7760998 1.40193327 0.77571654 1.39831644 1 P 0 ;0,1,2=217,3=0.000000
L 0.77571654 1.39831644 0.7760998 1.39521614 1 P 0 ;0,1,2=217,3=0.000000
L 0.7760998 1.39521614 0.77763346 1.39211585 1 P 0 ;0,1,2=217,3=0.000000
L 0.77763346 1.39211585 0.77993366 1.38953307 1 P 0 ;0,1,2=217,3=0.000000
L 0.77993366 1.38953307 0.78261644 1.3885 1 P 0 ;0,1,2=217,3=0.000000
L 0.78261644 1.3885 0.78568317 1.38953307 1 P 0 ;0,1,2=217,3=0.000000
L 0.78568317 1.38953307 0.78836663 1.39263238 1 P 0 ;0,1,2=217,3=0.000000
L 0.78836663 1.39263238 0.7899003 1.39728327 1 P 0 ;0,1,2=217,3=0.000000
L 0.7899003 1.39728327 0.79028356 1.4024498 1 P 0 ;0,1,2=217,3=0.000000
L 0.79028356 1.4024498 0.78951713 1.40916594 1 P 0 ;0,1,2=217,3=0.000000
L 0.78951713 1.40916594 0.78836663 1.41278376 1 P 0 ;0,1,2=217,3=0.000000
L 0.78836663 1.41278376 0.78645039 1.4163997 1 P 0 ;0,1,2=217,3=0.000000
L 0.78645039 1.4163997 0.78376693 1.41898337 1 P 0 ;0,1,2=217,3=0.000000
L 0.78376693 1.41898337 0.78108346 1.4195 1 P 0 ;0,1,2=217,3=0.000000
L 0.78108346 1.4195 0.7784 1.41846683 1 P 0 ;0,1,2=217,3=0.000000
L 0.7784 1.41846683 0.77648297 1.41588307 1 P 0 ;0,1,2=217,3=0.000000
L 0.874 1.661 0.874 1.617 1 P 0 
L 0.784 1.661 0.874 1.661 1 P 0 
L 0.874 1.617 0.784 1.617 1 P 0 
L 0.784 1.617 0.784 1.661 1 P 0 
L 0.86916683 1.4345 0.86916683 1.4655 1 P 0 ;0,1,2=218,3=0.000000
L 0.86916683 1.4655 0.85958346 1.4655 1 P 0 ;0,1,2=218,3=0.000000
L 0.85958346 1.4655 0.85651673 1.46394931 1 P 0 ;0,1,2=218,3=0.000000
L 0.85651673 1.46394931 0.8545998 1.46188307 1 P 0 ;0,1,2=218,3=0.000000
L 0.8545998 1.46188307 0.85383327 1.4577497 1 P 0 ;0,1,2=218,3=0.000000
L 0.85383327 1.4577497 0.8545998 1.45361634 1 P 0 ;0,1,2=218,3=0.000000
L 0.8545998 1.45361634 0.8569 1.45103356 1 P 0 ;0,1,2=218,3=0.000000
L 0.8569 1.45103356 0.85958346 1.44948287 1 P 0 ;0,1,2=218,3=0.000000
L 0.85958346 1.44948287 0.86916683 1.44948287 1 P 0 ;0,1,2=218,3=0.000000
L 0.85958346 1.44948287 0.85383327 1.4345 1 P 0 ;0,1,2=218,3=0.000000
L 0.83050039 1.4345 0.83050039 1.4655 1 P 0 ;0,1,2=218,3=0.000000
L 0.83050039 1.4655 0.8351001 1.4593003 1 P 0 ;0,1,2=218,3=0.000000
L 0.8351001 1.4345 0.82590069 1.4345 1 P 0 ;0,1,2=218,3=0.000000
L 0.7949 1.4345 0.7949 1.4655 1 P 0 ;0,1,2=218,3=0.000000
L 0.7949 1.4655 0.80908376 1.44328327 1 P 0 ;0,1,2=218,3=0.000000
L 0.80908376 1.44328327 0.78991634 1.44328327 1 P 0 ;0,1,2=218,3=0.000000
L 0.76926693 1.4345 0.76850039 1.44121614 1 P 0 ;0,1,2=218,3=0.000000
L 0.76850039 1.44121614 0.7673499 1.44689921 1 P 0 ;0,1,2=218,3=0.000000
L 0.7673499 1.44689921 0.76581693 1.45206663 1 P 0 ;0,1,2=218,3=0.000000
L 0.76581693 1.45206663 0.7639 1.4577497 1 P 0 ;0,1,2=218,3=0.000000
L 0.7639 1.4577497 0.76083327 1.4655 1 P 0 ;0,1,2=218,3=0.000000
L 0.76083327 1.4655 0.77616683 1.4655 1 P 0 ;0,1,2=218,3=0.000000
L 0.874 1.706 0.874 1.662 1 P 0 
L 0.874 1.662 0.784 1.662 1 P 0 
L 0.784 1.662 0.784 1.706 1 P 0 
L 0.784 1.706 0.874 1.706 1 P 0 
L 0.81366683 1.7195 0.81366683 1.7505 1 P 0 ;0,1,2=219,3=0.000000
L 0.81366683 1.7505 0.80408346 1.7505 1 P 0 ;0,1,2=219,3=0.000000
L 0.80408346 1.7505 0.80101673 1.74894931 1 P 0 ;0,1,2=219,3=0.000000
L 0.80101673 1.74894931 0.7990998 1.74688307 1 P 0 ;0,1,2=219,3=0.000000
L 0.7990998 1.74688307 0.79833327 1.7427497 1 P 0 ;0,1,2=219,3=0.000000
L 0.79833327 1.7427497 0.7990998 1.73861634 1 P 0 ;0,1,2=219,3=0.000000
L 0.7990998 1.73861634 0.8014 1.73603356 1 P 0 ;0,1,2=219,3=0.000000
L 0.8014 1.73603356 0.80408346 1.73448287 1 P 0 ;0,1,2=219,3=0.000000
L 0.80408346 1.73448287 0.81366683 1.73448287 1 P 0 ;0,1,2=219,3=0.000000
L 0.80408346 1.73448287 0.79833327 1.7195 1 P 0 ;0,1,2=219,3=0.000000
L 0.78343337 1.72414892 0.78113386 1.72156614 1 P 0 ;0,1,2=219,3=0.000000
L 0.78113386 1.72156614 0.77845039 1.72001654 1 P 0 ;0,1,2=219,3=0.000000
L 0.77845039 1.72001654 0.77500039 1.7195 1 P 0 ;0,1,2=219,3=0.000000
L 0.77500039 1.7195 0.7715497 1.72053307 1 P 0 ;0,1,2=219,3=0.000000
L 0.7715497 1.72053307 0.76886693 1.72259931 1 P 0 ;0,1,2=219,3=0.000000
L 0.76886693 1.72259931 0.76695 1.72621614 1 P 0 ;0,1,2=219,3=0.000000
L 0.76695 1.72621614 0.76656673 1.73034951 1 P 0 ;0,1,2=219,3=0.000000
L 0.76656673 1.73034951 0.76733327 1.73448287 1 P 0 ;0,1,2=219,3=0.000000
L 0.76733327 1.73448287 0.7692502 1.73706663 1 P 0 ;0,1,2=219,3=0.000000
L 0.7692502 1.73706663 0.77193366 1.73913287 1 P 0 ;0,1,2=219,3=0.000000
L 0.77193366 1.73913287 0.77461644 1.73964941 1 P 0 ;0,1,2=219,3=0.000000
L 0.77461644 1.73964941 0.7772999 1.73913287 1 P 0 ;0,1,2=219,3=0.000000
L 0.7772999 1.73913287 0.7807499 1.73706663 1 P 0 ;0,1,2=219,3=0.000000
L 0.7807499 1.73706663 0.7796001 1.7505 1 P 0 ;0,1,2=219,3=0.000000
L 0.7796001 1.7505 0.7692502 1.7505 1 P 0 ;0,1,2=219,3=0.000000
L 0.74400039 1.7195 0.74131693 1.72001654 1 P 0 ;0,1,2=219,3=0.000000
L 0.74131693 1.72001654 0.7382502 1.72156614 1 P 0 ;0,1,2=219,3=0.000000
L 0.7382502 1.72156614 0.73633327 1.72414892 1 P 0 ;0,1,2=219,3=0.000000
L 0.73633327 1.72414892 0.73556673 1.72776673 1 P 0 ;0,1,2=219,3=0.000000
L 0.73556673 1.72776673 0.73633327 1.73138268 1 P 0 ;0,1,2=219,3=0.000000
L 0.73633327 1.73138268 0.73863346 1.73448287 1 P 0 ;0,1,2=219,3=0.000000
L 0.73863346 1.73448287 0.74208346 1.73603356 1 P 0 ;0,1,2=219,3=0.000000
L 0.74208346 1.73603356 0.74591663 1.73603356 1 P 0 ;0,1,2=219,3=0.000000
L 0.74591663 1.73603356 0.74821683 1.73706663 1 P 0 ;0,1,2=219,3=0.000000
L 0.74821683 1.73706663 0.75013386 1.73964941 1 P 0 ;0,1,2=219,3=0.000000
L 0.75013386 1.73964941 0.7509003 1.74326624 1 P 0 ;0,1,2=219,3=0.000000
L 0.7509003 1.74326624 0.7497499 1.74688307 1 P 0 ;0,1,2=219,3=0.000000
L 0.7497499 1.74688307 0.74706713 1.74946683 1 P 0 ;0,1,2=219,3=0.000000
L 0.74706713 1.74946683 0.74400039 1.7505 1 P 0 ;0,1,2=219,3=0.000000
L 0.74400039 1.7505 0.74093366 1.74946683 1 P 0 ;0,1,2=219,3=0.000000
L 0.74093366 1.74946683 0.7382502 1.74688307 1 P 0 ;0,1,2=219,3=0.000000
L 0.7382502 1.74688307 0.7370998 1.74326624 1 P 0 ;0,1,2=219,3=0.000000
L 0.7370998 1.74326624 0.73786693 1.73964941 1 P 0 ;0,1,2=219,3=0.000000
L 0.73786693 1.73964941 0.73978327 1.73706663 1 P 0 ;0,1,2=219,3=0.000000
L 0.73978327 1.73706663 0.74208346 1.73603356 1 P 0 ;0,1,2=219,3=0.000000
L 0.74208346 1.73603356 0.74591663 1.73603356 1 P 0 ;0,1,2=219,3=0.000000
L 0.74591663 1.73603356 0.74936663 1.73448287 1 P 0 ;0,1,2=219,3=0.000000
L 0.74936663 1.73448287 0.75166683 1.73138268 1 P 0 ;0,1,2=219,3=0.000000
L 0.75166683 1.73138268 0.75243337 1.72776673 1 P 0 ;0,1,2=219,3=0.000000
L 0.75243337 1.72776673 0.75166683 1.72414892 1 P 0 ;0,1,2=219,3=0.000000
L 0.75166683 1.72414892 0.7497499 1.72156614 1 P 0 ;0,1,2=219,3=0.000000
L 0.7497499 1.72156614 0.74668317 1.72001654 1 P 0 ;0,1,2=219,3=0.000000
L 0.74668317 1.72001654 0.74400039 1.7195 1 P 0 ;0,1,2=219,3=0.000000
L 0.741 1.566 0.741 1.522 1 P 0 
L 0.651 1.566 0.741 1.566 1 P 0 
L 0.741 1.522 0.651 1.522 1 P 0 
L 0.651 1.522 0.651 1.566 1 P 0 
L 0.73416683 1.4295 0.73416683 1.4605 1 P 0 ;0,1,2=220,3=0.000000
L 0.73416683 1.4605 0.72458346 1.4605 1 P 0 ;0,1,2=220,3=0.000000
L 0.72458346 1.4605 0.72151673 1.45894931 1 P 0 ;0,1,2=220,3=0.000000
L 0.72151673 1.45894931 0.7195998 1.45688307 1 P 0 ;0,1,2=220,3=0.000000
L 0.7195998 1.45688307 0.71883327 1.4527497 1 P 0 ;0,1,2=220,3=0.000000
L 0.71883327 1.4527497 0.7195998 1.44861634 1 P 0 ;0,1,2=220,3=0.000000
L 0.7195998 1.44861634 0.7219 1.44603356 1 P 0 ;0,1,2=220,3=0.000000
L 0.7219 1.44603356 0.72458346 1.44448287 1 P 0 ;0,1,2=220,3=0.000000
L 0.72458346 1.44448287 0.73416683 1.44448287 1 P 0 ;0,1,2=220,3=0.000000
L 0.72458346 1.44448287 0.71883327 1.4295 1 P 0 ;0,1,2=220,3=0.000000
L 0.69550039 1.4295 0.69550039 1.4605 1 P 0 ;0,1,2=220,3=0.000000
L 0.69550039 1.4605 0.7001001 1.4543003 1 P 0 ;0,1,2=220,3=0.000000
L 0.7001001 1.4295 0.69090069 1.4295 1 P 0 ;0,1,2=220,3=0.000000
L 0.6599 1.4295 0.6599 1.4605 1 P 0 ;0,1,2=220,3=0.000000
L 0.6599 1.4605 0.67408376 1.43828327 1 P 0 ;0,1,2=220,3=0.000000
L 0.67408376 1.43828327 0.65491634 1.43828327 1 P 0 ;0,1,2=220,3=0.000000
L 0.64193337 1.43414892 0.63963386 1.43156614 1 P 0 ;0,1,2=220,3=0.000000
L 0.63963386 1.43156614 0.63695039 1.43001654 1 P 0 ;0,1,2=220,3=0.000000
L 0.63695039 1.43001654 0.63350039 1.4295 1 P 0 ;0,1,2=220,3=0.000000
L 0.63350039 1.4295 0.6300497 1.43053307 1 P 0 ;0,1,2=220,3=0.000000
L 0.6300497 1.43053307 0.62736693 1.43259931 1 P 0 ;0,1,2=220,3=0.000000
L 0.62736693 1.43259931 0.62545 1.43621614 1 P 0 ;0,1,2=220,3=0.000000
L 0.62545 1.43621614 0.62506673 1.44034951 1 P 0 ;0,1,2=220,3=0.000000
L 0.62506673 1.44034951 0.62583327 1.44448287 1 P 0 ;0,1,2=220,3=0.000000
L 0.62583327 1.44448287 0.6277502 1.44706663 1 P 0 ;0,1,2=220,3=0.000000
L 0.6277502 1.44706663 0.63043366 1.44913287 1 P 0 ;0,1,2=220,3=0.000000
L 0.63043366 1.44913287 0.63311644 1.44964941 1 P 0 ;0,1,2=220,3=0.000000
L 0.63311644 1.44964941 0.6357999 1.44913287 1 P 0 ;0,1,2=220,3=0.000000
L 0.6357999 1.44913287 0.6392499 1.44706663 1 P 0 ;0,1,2=220,3=0.000000
L 0.6392499 1.44706663 0.6381001 1.4605 1 P 0 ;0,1,2=220,3=0.000000
L 0.6381001 1.4605 0.6277502 1.4605 1 P 0 ;0,1,2=220,3=0.000000
L 2.105 2.997 2.105 2.907 1 P 0 
L 2.105 2.907 2.061 2.907 1 P 0 
L 2.061 2.907 2.061 2.997 1 P 0 
L 2.061 2.997 2.105 2.997 1 P 0 
L 2.0725 3.05783317 2.1035 3.05783317 1 P 0 ;0,1,2=221,3=90.000000
L 2.1035 3.05783317 2.1035 3.06741654 1 P 0 ;0,1,2=221,3=90.000000
L 2.1035 3.06741654 2.10194931 3.07048327 1 P 0 ;0,1,2=221,3=90.000000
L 2.10194931 3.07048327 2.09988307 3.0724002 1 P 0 ;0,1,2=221,3=90.000000
L 2.09988307 3.0724002 2.0957497 3.07316673 1 P 0 ;0,1,2=221,3=90.000000
L 2.0957497 3.07316673 2.09161634 3.0724002 1 P 0 ;0,1,2=221,3=90.000000
L 2.09161634 3.0724002 2.08903356 3.0701 1 P 0 ;0,1,2=221,3=90.000000
L 2.08903356 3.0701 2.08748287 3.06741654 1 P 0 ;0,1,2=221,3=90.000000
L 2.08748287 3.06741654 2.08748287 3.05783317 1 P 0 ;0,1,2=221,3=90.000000
L 2.08748287 3.06741654 2.0725 3.07316673 1 P 0 ;0,1,2=221,3=90.000000
L 2.0725 3.1011 2.1035 3.1011 1 P 0 ;0,1,2=221,3=90.000000
L 2.1035 3.1011 2.08128327 3.08691624 1 P 0 ;0,1,2=221,3=90.000000
L 2.08128327 3.08691624 2.08128327 3.10608366 1 P 0 ;0,1,2=221,3=90.000000
L 2.1035 3.12749961 2.10246683 3.12443287 1 P 0 ;0,1,2=221,3=90.000000
L 2.10246683 3.12443287 2.09988307 3.12213337 1 P 0 ;0,1,2=221,3=90.000000
L 2.09988307 3.12213337 2.09678376 3.1205997 1 P 0 ;0,1,2=221,3=90.000000
L 2.09678376 3.1205997 2.09264941 3.1194499 1 P 0 ;0,1,2=221,3=90.000000
L 2.09264941 3.1194499 2.08799951 3.11906663 1 P 0 ;0,1,2=221,3=90.000000
L 2.08799951 3.11906663 2.08334951 3.1194499 1 P 0 ;0,1,2=221,3=90.000000
L 2.08334951 3.1194499 2.07921614 3.1205997 1 P 0 ;0,1,2=221,3=90.000000
L 2.07921614 3.1205997 2.07611585 3.12213337 1 P 0 ;0,1,2=221,3=90.000000
L 2.07611585 3.12213337 2.07353307 3.12443287 1 P 0 ;0,1,2=221,3=90.000000
L 2.07353307 3.12443287 2.0725 3.12749961 1 P 0 ;0,1,2=221,3=90.000000
L 2.0725 3.12749961 2.07353307 3.13056634 1 P 0 ;0,1,2=221,3=90.000000
L 2.07353307 3.13056634 2.07611585 3.13286654 1 P 0 ;0,1,2=221,3=90.000000
L 2.07611585 3.13286654 2.07921614 3.1344002 1 P 0 ;0,1,2=221,3=90.000000
L 2.07921614 3.1344002 2.08334951 3.13555 1 P 0 ;0,1,2=221,3=90.000000
L 2.08334951 3.13555 2.08799951 3.13593327 1 P 0 ;0,1,2=221,3=90.000000
L 2.08799951 3.13593327 2.09264941 3.13555 1 P 0 ;0,1,2=221,3=90.000000
L 2.09264941 3.13555 2.09678376 3.1344002 1 P 0 ;0,1,2=221,3=90.000000
L 2.09678376 3.1344002 2.09988307 3.13286654 1 P 0 ;0,1,2=221,3=90.000000
L 2.09988307 3.13286654 2.10246683 3.13056634 1 P 0 ;0,1,2=221,3=90.000000
L 2.10246683 3.13056634 2.1035 3.12749961 1 P 0 ;0,1,2=221,3=90.000000
L 2.07611585 3.15198287 2.07353307 3.15466634 1 P 0 ;0,1,2=221,3=90.000000
L 2.07353307 3.15466634 2.0725 3.15773307 1 P 0 ;0,1,2=221,3=90.000000
L 2.0725 3.15773307 2.07353307 3.1607998 1 P 0 ;0,1,2=221,3=90.000000
L 2.07353307 3.1607998 2.07663238 3.16348327 1 P 0 ;0,1,2=221,3=90.000000
L 2.07663238 3.16348327 2.08128327 3.1654002 1 P 0 ;0,1,2=221,3=90.000000
L 2.08128327 3.1654002 2.08593327 3.16616673 1 P 0 ;0,1,2=221,3=90.000000
L 2.08593327 3.16616673 2.09161634 3.16616673 1 P 0 ;0,1,2=221,3=90.000000
L 2.09161634 3.16616673 2.09626624 3.1654002 1 P 0 ;0,1,2=221,3=90.000000
L 2.09626624 3.1654002 2.1003997 3.16348327 1 P 0 ;0,1,2=221,3=90.000000
L 2.1003997 3.16348327 2.10246683 3.16118307 1 P 0 ;0,1,2=221,3=90.000000
L 2.10246683 3.16118307 2.1035 3.15849961 1 P 0 ;0,1,2=221,3=90.000000
L 2.1035 3.15849961 2.10246683 3.15543287 1 P 0 ;0,1,2=221,3=90.000000
L 2.10246683 3.15543287 2.1003997 3.15313337 1 P 0 ;0,1,2=221,3=90.000000
L 2.1003997 3.15313337 2.0973003 3.1515997 1 P 0 ;0,1,2=221,3=90.000000
L 2.0973003 3.1515997 2.09316594 3.15083317 1 P 0 ;0,1,2=221,3=90.000000
L 2.09316594 3.15083317 2.0895501 3.1515997 1 P 0 ;0,1,2=221,3=90.000000
L 2.0895501 3.1515997 2.08593327 3.15351663 1 P 0 ;0,1,2=221,3=90.000000
L 2.08593327 3.15351663 2.08386604 3.15581683 1 P 0 ;0,1,2=221,3=90.000000
L 2.08386604 3.15581683 2.08334951 3.15849961 1 P 0 ;0,1,2=221,3=90.000000
L 2.08334951 3.15849961 2.08438268 3.16156634 1 P 0 ;0,1,2=221,3=90.000000
L 2.08438268 3.16156634 2.08696634 3.16386654 1 P 0 ;0,1,2=221,3=90.000000
L 2.08696634 3.16386654 2.09161634 3.16616673 1 P 0 ;0,1,2=221,3=90.000000
L 2.15 2.997 2.15 2.907 1 P 0 
L 2.15 2.907 2.106 2.907 1 P 0 
L 2.106 2.907 2.106 2.997 1 P 0 
L 2.106 2.997 2.15 2.997 1 P 0 
L 2.1175 3.05783317 2.1485 3.05783317 1 P 0 ;0,1,2=222,3=90.000000
L 2.1485 3.05783317 2.1485 3.06741654 1 P 0 ;0,1,2=222,3=90.000000
L 2.1485 3.06741654 2.14694931 3.07048327 1 P 0 ;0,1,2=222,3=90.000000
L 2.14694931 3.07048327 2.14488307 3.0724002 1 P 0 ;0,1,2=222,3=90.000000
L 2.14488307 3.0724002 2.1407497 3.07316673 1 P 0 ;0,1,2=222,3=90.000000
L 2.1407497 3.07316673 2.13661634 3.0724002 1 P 0 ;0,1,2=222,3=90.000000
L 2.13661634 3.0724002 2.13403356 3.0701 1 P 0 ;0,1,2=222,3=90.000000
L 2.13403356 3.0701 2.13248287 3.06741654 1 P 0 ;0,1,2=222,3=90.000000
L 2.13248287 3.06741654 2.13248287 3.05783317 1 P 0 ;0,1,2=222,3=90.000000
L 2.13248287 3.06741654 2.1175 3.07316673 1 P 0 ;0,1,2=222,3=90.000000
L 2.1175 3.1011 2.1485 3.1011 1 P 0 ;0,1,2=222,3=90.000000
L 2.1485 3.1011 2.12628327 3.08691624 1 P 0 ;0,1,2=222,3=90.000000
L 2.12628327 3.08691624 2.12628327 3.10608366 1 P 0 ;0,1,2=222,3=90.000000
L 2.1175 3.12749961 2.1485 3.12749961 1 P 0 ;0,1,2=222,3=90.000000
L 2.1485 3.12749961 2.1423003 3.1228999 1 P 0 ;0,1,2=222,3=90.000000
L 2.1175 3.1228999 2.1175 3.13209931 1 P 0 ;0,1,2=222,3=90.000000
L 2.12369961 3.15006663 2.12008278 3.15236614 1 P 0 ;0,1,2=222,3=90.000000
L 2.12008278 3.15236614 2.11801654 3.15543287 1 P 0 ;0,1,2=222,3=90.000000
L 2.11801654 3.15543287 2.1175 3.15888356 1 P 0 ;0,1,2=222,3=90.000000
L 2.1175 3.15888356 2.11801654 3.1619503 1 P 0 ;0,1,2=222,3=90.000000
L 2.11801654 3.1619503 2.12059931 3.16501703 1 P 0 ;0,1,2=222,3=90.000000
L 2.12059931 3.16501703 2.12369961 3.16693327 1 P 0 ;0,1,2=222,3=90.000000
L 2.12369961 3.16693327 2.1267999 3.16731654 1 P 0 ;0,1,2=222,3=90.000000
L 2.1267999 3.16731654 2.13041575 3.16655 1 P 0 ;0,1,2=222,3=90.000000
L 2.13041575 3.16655 2.13299951 3.16386654 1 P 0 ;0,1,2=222,3=90.000000
L 2.13299951 3.16386654 2.13403356 3.16118307 1 P 0 ;0,1,2=222,3=90.000000
L 2.13403356 3.16118307 2.13403356 3.15773307 1 P 0 ;0,1,2=222,3=90.000000
L 2.13403356 3.16118307 2.13558317 3.16348327 1 P 0 ;0,1,2=222,3=90.000000
L 2.13558317 3.16348327 2.13816594 3.1654002 1 P 0 ;0,1,2=222,3=90.000000
L 2.13816594 3.1654002 2.14126624 3.16616673 1 P 0 ;0,1,2=222,3=90.000000
L 2.14126624 3.16616673 2.14436654 3.1654002 1 P 0 ;0,1,2=222,3=90.000000
L 2.14436654 3.1654002 2.14694931 3.16348327 1 P 0 ;0,1,2=222,3=90.000000
L 2.14694931 3.16348327 2.1485 3.16003327 1 P 0 ;0,1,2=222,3=90.000000
L 2.1485 3.16003327 2.14798337 3.15658337 1 P 0 ;0,1,2=222,3=90.000000
L 2.14798337 3.15658337 2.14591624 3.15313337 1 P 0 ;0,1,2=222,3=90.000000
L 5.43 2.892 5.52 2.892 1 P 0 
L 5.52 2.892 5.52 2.848 1 P 0 
L 5.52 2.848 5.43 2.848 1 P 0 
L 5.43 2.848 5.43 2.892 1 P 0 
L 5.42366683 2.8645 5.42366683 2.8955 1 P 0 ;0,1,2=223,3=0.000000
L 5.42366683 2.8955 5.41408346 2.8955 1 P 0 ;0,1,2=223,3=0.000000
L 5.41408346 2.8955 5.41101673 2.89394931 1 P 0 ;0,1,2=223,3=0.000000
L 5.41101673 2.89394931 5.4090998 2.89188307 1 P 0 ;0,1,2=223,3=0.000000
L 5.4090998 2.89188307 5.40833327 2.8877497 1 P 0 ;0,1,2=223,3=0.000000
L 5.40833327 2.8877497 5.4090998 2.88361634 1 P 0 ;0,1,2=223,3=0.000000
L 5.4090998 2.88361634 5.4114 2.88103356 1 P 0 ;0,1,2=223,3=0.000000
L 5.4114 2.88103356 5.41408346 2.87948287 1 P 0 ;0,1,2=223,3=0.000000
L 5.41408346 2.87948287 5.42366683 2.87948287 1 P 0 ;0,1,2=223,3=0.000000
L 5.41408346 2.87948287 5.40833327 2.8645 1 P 0 ;0,1,2=223,3=0.000000
L 5.3804 2.8645 5.3804 2.8955 1 P 0 ;0,1,2=223,3=0.000000
L 5.3804 2.8955 5.39458376 2.87328327 1 P 0 ;0,1,2=223,3=0.000000
L 5.39458376 2.87328327 5.37541634 2.87328327 1 P 0 ;0,1,2=223,3=0.000000
L 5.36243337 2.87069961 5.36013386 2.86708278 1 P 0 ;0,1,2=223,3=0.000000
L 5.36013386 2.86708278 5.35706713 2.86501654 1 P 0 ;0,1,2=223,3=0.000000
L 5.35706713 2.86501654 5.35361644 2.8645 1 P 0 ;0,1,2=223,3=0.000000
L 5.35361644 2.8645 5.3505497 2.86501654 1 P 0 ;0,1,2=223,3=0.000000
L 5.3505497 2.86501654 5.34748297 2.86759931 1 P 0 ;0,1,2=223,3=0.000000
L 5.34748297 2.86759931 5.34556673 2.87069961 1 P 0 ;0,1,2=223,3=0.000000
L 5.34556673 2.87069961 5.34518346 2.8737999 1 P 0 ;0,1,2=223,3=0.000000
L 5.34518346 2.8737999 5.34595 2.87741575 1 P 0 ;0,1,2=223,3=0.000000
L 5.34595 2.87741575 5.34863346 2.87999951 1 P 0 ;0,1,2=223,3=0.000000
L 5.34863346 2.87999951 5.35131693 2.88103356 1 P 0 ;0,1,2=223,3=0.000000
L 5.35131693 2.88103356 5.35476693 2.88103356 1 P 0 ;0,1,2=223,3=0.000000
L 5.35131693 2.88103356 5.34901673 2.88258317 1 P 0 ;0,1,2=223,3=0.000000
L 5.34901673 2.88258317 5.3470998 2.88516594 1 P 0 ;0,1,2=223,3=0.000000
L 5.3470998 2.88516594 5.34633327 2.88826624 1 P 0 ;0,1,2=223,3=0.000000
L 5.34633327 2.88826624 5.3470998 2.89136654 1 P 0 ;0,1,2=223,3=0.000000
L 5.3470998 2.89136654 5.34901673 2.89394931 1 P 0 ;0,1,2=223,3=0.000000
L 5.34901673 2.89394931 5.35246673 2.8955 1 P 0 ;0,1,2=223,3=0.000000
L 5.35246673 2.8955 5.35591663 2.89498337 1 P 0 ;0,1,2=223,3=0.000000
L 5.35591663 2.89498337 5.35936663 2.89291624 1 P 0 ;0,1,2=223,3=0.000000
L 5.57 3.043 5.48 3.043 1 P 0 
L 5.48 3.043 5.48 3.087 1 P 0 
L 5.48 3.087 5.57 3.087 1 P 0 
L 5.57 3.087 5.57 3.043 1 P 0 
L 5.57866683 3.1345 5.57866683 3.1655 1 P 0 ;0,1,2=224,3=0.000000
L 5.57866683 3.1655 5.56908346 3.1655 1 P 0 ;0,1,2=224,3=0.000000
L 5.56908346 3.1655 5.56601673 3.16394931 1 P 0 ;0,1,2=224,3=0.000000
L 5.56601673 3.16394931 5.5640998 3.16188307 1 P 0 ;0,1,2=224,3=0.000000
L 5.5640998 3.16188307 5.56333327 3.1577497 1 P 0 ;0,1,2=224,3=0.000000
L 5.56333327 3.1577497 5.5640998 3.15361634 1 P 0 ;0,1,2=224,3=0.000000
L 5.5640998 3.15361634 5.5664 3.15103356 1 P 0 ;0,1,2=224,3=0.000000
L 5.5664 3.15103356 5.56908346 3.14948287 1 P 0 ;0,1,2=224,3=0.000000
L 5.56908346 3.14948287 5.57866683 3.14948287 1 P 0 ;0,1,2=224,3=0.000000
L 5.56908346 3.14948287 5.56333327 3.1345 1 P 0 ;0,1,2=224,3=0.000000
L 5.5354 3.1345 5.5354 3.1655 1 P 0 ;0,1,2=224,3=0.000000
L 5.5354 3.1655 5.54958376 3.14328327 1 P 0 ;0,1,2=224,3=0.000000
L 5.54958376 3.14328327 5.53041634 3.14328327 1 P 0 ;0,1,2=224,3=0.000000
L 5.50900039 3.1345 5.50900039 3.1655 1 P 0 ;0,1,2=224,3=0.000000
L 5.50900039 3.1655 5.5136001 3.1593003 1 P 0 ;0,1,2=224,3=0.000000
L 5.5136001 3.1345 5.50440069 3.1345 1 P 0 ;0,1,2=224,3=0.000000
L 5.57 2.793 5.48 2.793 1 P 0 
L 5.48 2.793 5.48 2.837 1 P 0 
L 5.48 2.837 5.57 2.837 1 P 0 
L 5.57 2.837 5.57 2.793 1 P 0 
L 5.39866683 2.8095 5.39866683 2.8405 1 P 0 ;0,1,2=225,3=0.000000
L 5.39866683 2.8405 5.38908346 2.8405 1 P 0 ;0,1,2=225,3=0.000000
L 5.38908346 2.8405 5.38601673 2.83894931 1 P 0 ;0,1,2=225,3=0.000000
L 5.38601673 2.83894931 5.3840998 2.83688307 1 P 0 ;0,1,2=225,3=0.000000
L 5.3840998 2.83688307 5.38333327 2.8327497 1 P 0 ;0,1,2=225,3=0.000000
L 5.38333327 2.8327497 5.3840998 2.82861634 1 P 0 ;0,1,2=225,3=0.000000
L 5.3840998 2.82861634 5.3864 2.82603356 1 P 0 ;0,1,2=225,3=0.000000
L 5.3864 2.82603356 5.38908346 2.82448287 1 P 0 ;0,1,2=225,3=0.000000
L 5.38908346 2.82448287 5.39866683 2.82448287 1 P 0 ;0,1,2=225,3=0.000000
L 5.38908346 2.82448287 5.38333327 2.8095 1 P 0 ;0,1,2=225,3=0.000000
L 5.3554 2.8095 5.3554 2.8405 1 P 0 ;0,1,2=225,3=0.000000
L 5.3554 2.8405 5.36958376 2.81828327 1 P 0 ;0,1,2=225,3=0.000000
L 5.36958376 2.81828327 5.35041634 2.81828327 1 P 0 ;0,1,2=225,3=0.000000
L 5.33628356 2.83533346 5.33398337 2.83843278 1 P 0 ;0,1,2=225,3=0.000000
L 5.33398337 2.83843278 5.3312999 2.83998337 1 P 0 ;0,1,2=225,3=0.000000
L 5.3312999 2.83998337 5.32823317 2.8405 1 P 0 ;0,1,2=225,3=0.000000
L 5.32823317 2.8405 5.3244 2.83946683 1 P 0 ;0,1,2=225,3=0.000000
L 5.3244 2.83946683 5.32171654 2.83688307 1 P 0 ;0,1,2=225,3=0.000000
L 5.32171654 2.83688307 5.32095 2.83378376 1 P 0 ;0,1,2=225,3=0.000000
L 5.32095 2.83378376 5.32133327 2.83068258 1 P 0 ;0,1,2=225,3=0.000000
L 5.32133327 2.83068258 5.32286693 2.8280998 1 P 0 ;0,1,2=225,3=0.000000
L 5.32286693 2.8280998 5.33053337 2.82293327 1 P 0 ;0,1,2=225,3=0.000000
L 5.33053337 2.82293327 5.33398337 2.81931644 1 P 0 ;0,1,2=225,3=0.000000
L 5.33398337 2.81931644 5.33628356 2.81414892 1 P 0 ;0,1,2=225,3=0.000000
L 5.33628356 2.81414892 5.3370501 2.8095 1 P 0 ;0,1,2=225,3=0.000000
L 5.3370501 2.8095 5.32095 2.8095 1 P 0 ;0,1,2=225,3=0.000000
L 5.57 2.573 5.48 2.573 1 P 0 
L 5.48 2.573 5.48 2.617 1 P 0 
L 5.48 2.617 5.57 2.617 1 P 0 
L 5.57 2.617 5.57 2.573 1 P 0 
L 5.5795 2.54133317 5.6105 2.54133317 1 P 0 ;0,1,2=226,3=90.000000
L 5.6105 2.54133317 5.6105 2.55091654 1 P 0 ;0,1,2=226,3=90.000000
L 5.6105 2.55091654 5.60894931 2.55398327 1 P 0 ;0,1,2=226,3=90.000000
L 5.60894931 2.55398327 5.60688307 2.5559002 1 P 0 ;0,1,2=226,3=90.000000
L 5.60688307 2.5559002 5.6027497 2.55666673 1 P 0 ;0,1,2=226,3=90.000000
L 5.6027497 2.55666673 5.59861634 2.5559002 1 P 0 ;0,1,2=226,3=90.000000
L 5.59861634 2.5559002 5.59603356 2.5536 1 P 0 ;0,1,2=226,3=90.000000
L 5.59603356 2.5536 5.59448287 2.55091654 1 P 0 ;0,1,2=226,3=90.000000
L 5.59448287 2.55091654 5.59448287 2.54133317 1 P 0 ;0,1,2=226,3=90.000000
L 5.59448287 2.55091654 5.5795 2.55666673 1 P 0 ;0,1,2=226,3=90.000000
L 5.60533346 2.57271644 5.60843278 2.57501663 1 P 0 ;0,1,2=226,3=90.000000
L 5.60843278 2.57501663 5.60998337 2.5777001 1 P 0 ;0,1,2=226,3=90.000000
L 5.60998337 2.5777001 5.6105 2.58076683 1 P 0 ;0,1,2=226,3=90.000000
L 5.6105 2.58076683 5.60946683 2.5846 1 P 0 ;0,1,2=226,3=90.000000
L 5.60946683 2.5846 5.60688307 2.58728346 1 P 0 ;0,1,2=226,3=90.000000
L 5.60688307 2.58728346 5.60378376 2.58805 1 P 0 ;0,1,2=226,3=90.000000
L 5.60378376 2.58805 5.60068258 2.58766673 1 P 0 ;0,1,2=226,3=90.000000
L 5.60068258 2.58766673 5.5980998 2.58613307 1 P 0 ;0,1,2=226,3=90.000000
L 5.5980998 2.58613307 5.59293327 2.57846663 1 P 0 ;0,1,2=226,3=90.000000
L 5.59293327 2.57846663 5.58931644 2.57501663 1 P 0 ;0,1,2=226,3=90.000000
L 5.58931644 2.57501663 5.58414892 2.57271644 1 P 0 ;0,1,2=226,3=90.000000
L 5.58414892 2.57271644 5.5795 2.5719499 1 P 0 ;0,1,2=226,3=90.000000
L 5.5795 2.5719499 5.5795 2.58805 1 P 0 ;0,1,2=226,3=90.000000
L 5.5795 2.61099961 5.58001654 2.61368307 1 P 0 ;0,1,2=226,3=90.000000
L 5.58001654 2.61368307 5.58156614 2.6167498 1 P 0 ;0,1,2=226,3=90.000000
L 5.58156614 2.6167498 5.58414892 2.61866673 1 P 0 ;0,1,2=226,3=90.000000
L 5.58414892 2.61866673 5.58776673 2.61943327 1 P 0 ;0,1,2=226,3=90.000000
L 5.58776673 2.61943327 5.59138268 2.61866673 1 P 0 ;0,1,2=226,3=90.000000
L 5.59138268 2.61866673 5.59448287 2.61636654 1 P 0 ;0,1,2=226,3=90.000000
L 5.59448287 2.61636654 5.59603356 2.61291654 1 P 0 ;0,1,2=226,3=90.000000
L 5.59603356 2.61291654 5.59603356 2.60908337 1 P 0 ;0,1,2=226,3=90.000000
L 5.59603356 2.60908337 5.59706663 2.60678317 1 P 0 ;0,1,2=226,3=90.000000
L 5.59706663 2.60678317 5.59964941 2.60486614 1 P 0 ;0,1,2=226,3=90.000000
L 5.59964941 2.60486614 5.60326624 2.6040997 1 P 0 ;0,1,2=226,3=90.000000
L 5.60326624 2.6040997 5.60688307 2.6052501 1 P 0 ;0,1,2=226,3=90.000000
L 5.60688307 2.6052501 5.60946683 2.60793287 1 P 0 ;0,1,2=226,3=90.000000
L 5.60946683 2.60793287 5.6105 2.61099961 1 P 0 ;0,1,2=226,3=90.000000
L 5.6105 2.61099961 5.60946683 2.61406634 1 P 0 ;0,1,2=226,3=90.000000
L 5.60946683 2.61406634 5.60688307 2.6167498 1 P 0 ;0,1,2=226,3=90.000000
L 5.60688307 2.6167498 5.60326624 2.6179002 1 P 0 ;0,1,2=226,3=90.000000
L 5.60326624 2.6179002 5.59964941 2.61713307 1 P 0 ;0,1,2=226,3=90.000000
L 5.59964941 2.61713307 5.59706663 2.61521673 1 P 0 ;0,1,2=226,3=90.000000
L 5.59706663 2.61521673 5.59603356 2.61291654 1 P 0 ;0,1,2=226,3=90.000000
L 5.59603356 2.61291654 5.59603356 2.60908337 1 P 0 ;0,1,2=226,3=90.000000
L 5.59603356 2.60908337 5.59448287 2.60563337 1 P 0 ;0,1,2=226,3=90.000000
L 5.59448287 2.60563337 5.59138268 2.60333317 1 P 0 ;0,1,2=226,3=90.000000
L 5.59138268 2.60333317 5.58776673 2.60256663 1 P 0 ;0,1,2=226,3=90.000000
L 5.58776673 2.60256663 5.58414892 2.60333317 1 P 0 ;0,1,2=226,3=90.000000
L 5.58414892 2.60333317 5.58156614 2.6052501 1 P 0 ;0,1,2=226,3=90.000000
L 5.58156614 2.6052501 5.58001654 2.60831683 1 P 0 ;0,1,2=226,3=90.000000
L 5.58001654 2.60831683 5.5795 2.61099961 1 P 0 ;0,1,2=226,3=90.000000
L 1.501 3.969 1.411 3.969 1 P 0 
L 1.411 3.969 1.411 4.013 1 P 0 
L 1.411 4.013 1.501 4.013 1 P 0 
L 1.501 4.013 1.501 3.969 1 P 0 
L 1.33566683 3.9515 1.33566683 3.9825 1 P 0 ;0,1,2=227,3=0.000000
L 1.33566683 3.9825 1.32608346 3.9825 1 P 0 ;0,1,2=227,3=0.000000
L 1.32608346 3.9825 1.32301673 3.98094931 1 P 0 ;0,1,2=227,3=0.000000
L 1.32301673 3.98094931 1.3210998 3.97888307 1 P 0 ;0,1,2=227,3=0.000000
L 1.3210998 3.97888307 1.32033327 3.9747497 1 P 0 ;0,1,2=227,3=0.000000
L 1.32033327 3.9747497 1.3210998 3.97061634 1 P 0 ;0,1,2=227,3=0.000000
L 1.3210998 3.97061634 1.3234 3.96803356 1 P 0 ;0,1,2=227,3=0.000000
L 1.3234 3.96803356 1.32608346 3.96648287 1 P 0 ;0,1,2=227,3=0.000000
L 1.32608346 3.96648287 1.33566683 3.96648287 1 P 0 ;0,1,2=227,3=0.000000
L 1.32608346 3.96648287 1.32033327 3.9515 1 P 0 ;0,1,2=227,3=0.000000
L 1.30543337 3.95769961 1.30313386 3.95408278 1 P 0 ;0,1,2=227,3=0.000000
L 1.30313386 3.95408278 1.30006713 3.95201654 1 P 0 ;0,1,2=227,3=0.000000
L 1.30006713 3.95201654 1.29661644 3.9515 1 P 0 ;0,1,2=227,3=0.000000
L 1.29661644 3.9515 1.2935497 3.95201654 1 P 0 ;0,1,2=227,3=0.000000
L 1.2935497 3.95201654 1.29048297 3.95459931 1 P 0 ;0,1,2=227,3=0.000000
L 1.29048297 3.95459931 1.28856673 3.95769961 1 P 0 ;0,1,2=227,3=0.000000
L 1.28856673 3.95769961 1.28818346 3.9607999 1 P 0 ;0,1,2=227,3=0.000000
L 1.28818346 3.9607999 1.28895 3.96441575 1 P 0 ;0,1,2=227,3=0.000000
L 1.28895 3.96441575 1.29163346 3.96699951 1 P 0 ;0,1,2=227,3=0.000000
L 1.29163346 3.96699951 1.29431693 3.96803356 1 P 0 ;0,1,2=227,3=0.000000
L 1.29431693 3.96803356 1.29776693 3.96803356 1 P 0 ;0,1,2=227,3=0.000000
L 1.29431693 3.96803356 1.29201673 3.96958317 1 P 0 ;0,1,2=227,3=0.000000
L 1.29201673 3.96958317 1.2900998 3.97216594 1 P 0 ;0,1,2=227,3=0.000000
L 1.2900998 3.97216594 1.28933327 3.97526624 1 P 0 ;0,1,2=227,3=0.000000
L 1.28933327 3.97526624 1.2900998 3.97836654 1 P 0 ;0,1,2=227,3=0.000000
L 1.2900998 3.97836654 1.29201673 3.98094931 1 P 0 ;0,1,2=227,3=0.000000
L 1.29201673 3.98094931 1.29546673 3.9825 1 P 0 ;0,1,2=227,3=0.000000
L 1.29546673 3.9825 1.29891663 3.98198337 1 P 0 ;0,1,2=227,3=0.000000
L 1.29891663 3.98198337 1.30236663 3.97991624 1 P 0 ;0,1,2=227,3=0.000000
L 1.26600039 3.9825 1.26906713 3.98146683 1 P 0 ;0,1,2=227,3=0.000000
L 1.26906713 3.98146683 1.27136663 3.97888307 1 P 0 ;0,1,2=227,3=0.000000
L 1.27136663 3.97888307 1.2729003 3.97578376 1 P 0 ;0,1,2=227,3=0.000000
L 1.2729003 3.97578376 1.2740501 3.97164941 1 P 0 ;0,1,2=227,3=0.000000
L 1.2740501 3.97164941 1.27443337 3.96699951 1 P 0 ;0,1,2=227,3=0.000000
L 1.27443337 3.96699951 1.2740501 3.96234951 1 P 0 ;0,1,2=227,3=0.000000
L 1.2740501 3.96234951 1.2729003 3.95821614 1 P 0 ;0,1,2=227,3=0.000000
L 1.2729003 3.95821614 1.27136663 3.95511585 1 P 0 ;0,1,2=227,3=0.000000
L 1.27136663 3.95511585 1.26906713 3.95253307 1 P 0 ;0,1,2=227,3=0.000000
L 1.26906713 3.95253307 1.26600039 3.9515 1 P 0 ;0,1,2=227,3=0.000000
L 1.26600039 3.9515 1.26293366 3.95253307 1 P 0 ;0,1,2=227,3=0.000000
L 1.26293366 3.95253307 1.26063346 3.95511585 1 P 0 ;0,1,2=227,3=0.000000
L 1.26063346 3.95511585 1.2590998 3.95821614 1 P 0 ;0,1,2=227,3=0.000000
L 1.2590998 3.95821614 1.25795 3.96234951 1 P 0 ;0,1,2=227,3=0.000000
L 1.25795 3.96234951 1.25756673 3.96699951 1 P 0 ;0,1,2=227,3=0.000000
L 1.25756673 3.96699951 1.25795 3.97164941 1 P 0 ;0,1,2=227,3=0.000000
L 1.25795 3.97164941 1.2590998 3.97578376 1 P 0 ;0,1,2=227,3=0.000000
L 1.2590998 3.97578376 1.26063346 3.97888307 1 P 0 ;0,1,2=227,3=0.000000
L 1.26063346 3.97888307 1.26293366 3.98146683 1 P 0 ;0,1,2=227,3=0.000000
L 1.26293366 3.98146683 1.26600039 3.9825 1 P 0 ;0,1,2=227,3=0.000000
L 1.501 3.924 1.411 3.924 1 P 0 
L 1.411 3.924 1.411 3.968 1 P 0 
L 1.411 3.968 1.501 3.968 1 P 0 
L 1.501 3.968 1.501 3.924 1 P 0 
L 1.33566683 3.9065 1.33566683 3.9375 1 P 0 ;0,1,2=228,3=0.000000
L 1.33566683 3.9375 1.32608346 3.9375 1 P 0 ;0,1,2=228,3=0.000000
L 1.32608346 3.9375 1.32301673 3.93594931 1 P 0 ;0,1,2=228,3=0.000000
L 1.32301673 3.93594931 1.3210998 3.93388307 1 P 0 ;0,1,2=228,3=0.000000
L 1.3210998 3.93388307 1.32033327 3.9297497 1 P 0 ;0,1,2=228,3=0.000000
L 1.32033327 3.9297497 1.3210998 3.92561634 1 P 0 ;0,1,2=228,3=0.000000
L 1.3210998 3.92561634 1.3234 3.92303356 1 P 0 ;0,1,2=228,3=0.000000
L 1.3234 3.92303356 1.32608346 3.92148287 1 P 0 ;0,1,2=228,3=0.000000
L 1.32608346 3.92148287 1.33566683 3.92148287 1 P 0 ;0,1,2=228,3=0.000000
L 1.32608346 3.92148287 1.32033327 3.9065 1 P 0 ;0,1,2=228,3=0.000000
L 1.2924 3.9065 1.2924 3.9375 1 P 0 ;0,1,2=228,3=0.000000
L 1.2924 3.9375 1.30658376 3.91528327 1 P 0 ;0,1,2=228,3=0.000000
L 1.30658376 3.91528327 1.28741634 3.91528327 1 P 0 ;0,1,2=228,3=0.000000
L 1.26600039 3.9065 1.26331693 3.90701654 1 P 0 ;0,1,2=228,3=0.000000
L 1.26331693 3.90701654 1.2602502 3.90856614 1 P 0 ;0,1,2=228,3=0.000000
L 1.2602502 3.90856614 1.25833327 3.91114892 1 P 0 ;0,1,2=228,3=0.000000
L 1.25833327 3.91114892 1.25756673 3.91476673 1 P 0 ;0,1,2=228,3=0.000000
L 1.25756673 3.91476673 1.25833327 3.91838268 1 P 0 ;0,1,2=228,3=0.000000
L 1.25833327 3.91838268 1.26063346 3.92148287 1 P 0 ;0,1,2=228,3=0.000000
L 1.26063346 3.92148287 1.26408346 3.92303356 1 P 0 ;0,1,2=228,3=0.000000
L 1.26408346 3.92303356 1.26791663 3.92303356 1 P 0 ;0,1,2=228,3=0.000000
L 1.26791663 3.92303356 1.27021683 3.92406663 1 P 0 ;0,1,2=228,3=0.000000
L 1.27021683 3.92406663 1.27213386 3.92664941 1 P 0 ;0,1,2=228,3=0.000000
L 1.27213386 3.92664941 1.2729003 3.93026624 1 P 0 ;0,1,2=228,3=0.000000
L 1.2729003 3.93026624 1.2717499 3.93388307 1 P 0 ;0,1,2=228,3=0.000000
L 1.2717499 3.93388307 1.26906713 3.93646683 1 P 0 ;0,1,2=228,3=0.000000
L 1.26906713 3.93646683 1.26600039 3.9375 1 P 0 ;0,1,2=228,3=0.000000
L 1.26600039 3.9375 1.26293366 3.93646683 1 P 0 ;0,1,2=228,3=0.000000
L 1.26293366 3.93646683 1.2602502 3.93388307 1 P 0 ;0,1,2=228,3=0.000000
L 1.2602502 3.93388307 1.2590998 3.93026624 1 P 0 ;0,1,2=228,3=0.000000
L 1.2590998 3.93026624 1.25986693 3.92664941 1 P 0 ;0,1,2=228,3=0.000000
L 1.25986693 3.92664941 1.26178327 3.92406663 1 P 0 ;0,1,2=228,3=0.000000
L 1.26178327 3.92406663 1.26408346 3.92303356 1 P 0 ;0,1,2=228,3=0.000000
L 1.26408346 3.92303356 1.26791663 3.92303356 1 P 0 ;0,1,2=228,3=0.000000
L 1.26791663 3.92303356 1.27136663 3.92148287 1 P 0 ;0,1,2=228,3=0.000000
L 1.27136663 3.92148287 1.27366683 3.91838268 1 P 0 ;0,1,2=228,3=0.000000
L 1.27366683 3.91838268 1.27443337 3.91476673 1 P 0 ;0,1,2=228,3=0.000000
L 1.27443337 3.91476673 1.27366683 3.91114892 1 P 0 ;0,1,2=228,3=0.000000
L 1.27366683 3.91114892 1.2717499 3.90856614 1 P 0 ;0,1,2=228,3=0.000000
L 1.2717499 3.90856614 1.26868317 3.90701654 1 P 0 ;0,1,2=228,3=0.000000
L 1.26868317 3.90701654 1.26600039 3.9065 1 P 0 ;0,1,2=228,3=0.000000
L 1.411 3.923 1.501 3.923 1 P 0 
L 1.501 3.923 1.501 3.879 1 P 0 
L 1.501 3.879 1.411 3.879 1 P 0 
L 1.411 3.879 1.411 3.923 1 P 0 
L 1.33616683 3.8625 1.33616683 3.8935 1 P 0 ;0,1,2=229,3=0.000000
L 1.33616683 3.8935 1.32658346 3.8935 1 P 0 ;0,1,2=229,3=0.000000
L 1.32658346 3.8935 1.32351673 3.89194931 1 P 0 ;0,1,2=229,3=0.000000
L 1.32351673 3.89194931 1.3215998 3.88988307 1 P 0 ;0,1,2=229,3=0.000000
L 1.3215998 3.88988307 1.32083327 3.8857497 1 P 0 ;0,1,2=229,3=0.000000
L 1.32083327 3.8857497 1.3215998 3.88161634 1 P 0 ;0,1,2=229,3=0.000000
L 1.3215998 3.88161634 1.3239 3.87903356 1 P 0 ;0,1,2=229,3=0.000000
L 1.3239 3.87903356 1.32658346 3.87748287 1 P 0 ;0,1,2=229,3=0.000000
L 1.32658346 3.87748287 1.33616683 3.87748287 1 P 0 ;0,1,2=229,3=0.000000
L 1.32658346 3.87748287 1.32083327 3.8625 1 P 0 ;0,1,2=229,3=0.000000
L 1.29750039 3.8625 1.29750039 3.8935 1 P 0 ;0,1,2=229,3=0.000000
L 1.29750039 3.8935 1.3021001 3.8873003 1 P 0 ;0,1,2=229,3=0.000000
L 1.3021001 3.8625 1.29290069 3.8625 1 P 0 ;0,1,2=229,3=0.000000
L 1.2619 3.8625 1.2619 3.8935 1 P 0 ;0,1,2=229,3=0.000000
L 1.2619 3.8935 1.27608376 3.87128327 1 P 0 ;0,1,2=229,3=0.000000
L 1.27608376 3.87128327 1.25691634 3.87128327 1 P 0 ;0,1,2=229,3=0.000000
L 1.24278356 3.88833346 1.24048337 3.89143278 1 P 0 ;0,1,2=229,3=0.000000
L 1.24048337 3.89143278 1.2377999 3.89298337 1 P 0 ;0,1,2=229,3=0.000000
L 1.2377999 3.89298337 1.23473317 3.8935 1 P 0 ;0,1,2=229,3=0.000000
L 1.23473317 3.8935 1.2309 3.89246683 1 P 0 ;0,1,2=229,3=0.000000
L 1.2309 3.89246683 1.22821654 3.88988307 1 P 0 ;0,1,2=229,3=0.000000
L 1.22821654 3.88988307 1.22745 3.88678376 1 P 0 ;0,1,2=229,3=0.000000
L 1.22745 3.88678376 1.22783327 3.88368258 1 P 0 ;0,1,2=229,3=0.000000
L 1.22783327 3.88368258 1.22936693 3.8810998 1 P 0 ;0,1,2=229,3=0.000000
L 1.22936693 3.8810998 1.23703337 3.87593327 1 P 0 ;0,1,2=229,3=0.000000
L 1.23703337 3.87593327 1.24048337 3.87231644 1 P 0 ;0,1,2=229,3=0.000000
L 1.24048337 3.87231644 1.24278356 3.86714892 1 P 0 ;0,1,2=229,3=0.000000
L 1.24278356 3.86714892 1.2435501 3.8625 1 P 0 ;0,1,2=229,3=0.000000
L 1.2435501 3.8625 1.22745 3.8625 1 P 0 ;0,1,2=229,3=0.000000
L 1.2397 0.7306 1.2397 0.6866 1 P 0 
L 1.2397 0.6866 1.1497 0.6866 1 P 0 
L 1.1497 0.6866 1.1497 0.7306 1 P 0 
L 1.1497 0.7306 1.2397 0.7306 1 P 0 
L 1.22316683 0.7395 1.22316683 0.7705 1 P 0 ;0,1,2=230,3=0.000000
L 1.22316683 0.7705 1.21358346 0.7705 1 P 0 ;0,1,2=230,3=0.000000
L 1.21358346 0.7705 1.21051673 0.76894931 1 P 0 ;0,1,2=230,3=0.000000
L 1.21051673 0.76894931 1.2085998 0.76688307 1 P 0 ;0,1,2=230,3=0.000000
L 1.2085998 0.76688307 1.20783327 0.7627497 1 P 0 ;0,1,2=230,3=0.000000
L 1.20783327 0.7627497 1.2085998 0.75861634 1 P 0 ;0,1,2=230,3=0.000000
L 1.2085998 0.75861634 1.2109 0.75603356 1 P 0 ;0,1,2=230,3=0.000000
L 1.2109 0.75603356 1.21358346 0.75448287 1 P 0 ;0,1,2=230,3=0.000000
L 1.21358346 0.75448287 1.22316683 0.75448287 1 P 0 ;0,1,2=230,3=0.000000
L 1.21358346 0.75448287 1.20783327 0.7395 1 P 0 ;0,1,2=230,3=0.000000
L 1.18450039 0.7395 1.18450039 0.7705 1 P 0 ;0,1,2=230,3=0.000000
L 1.18450039 0.7705 1.1891001 0.7643003 1 P 0 ;0,1,2=230,3=0.000000
L 1.1891001 0.7395 1.17990069 0.7395 1 P 0 ;0,1,2=230,3=0.000000
L 0.875 0.687 0.875 0.643 1 P 0 
L 0.875 0.643 0.785 0.643 1 P 0 
L 0.785 0.643 0.785 0.687 1 P 0 
L 0.785 0.687 0.875 0.687 1 P 0 
L 0.86816683 0.5845 0.86816683 0.6155 1 P 0 ;0,1,2=231,3=0.000000
L 0.86816683 0.6155 0.85858346 0.6155 1 P 0 ;0,1,2=231,3=0.000000
L 0.85858346 0.6155 0.85551673 0.61394931 1 P 0 ;0,1,2=231,3=0.000000
L 0.85551673 0.61394931 0.8535998 0.61188307 1 P 0 ;0,1,2=231,3=0.000000
L 0.8535998 0.61188307 0.85283327 0.6077497 1 P 0 ;0,1,2=231,3=0.000000
L 0.85283327 0.6077497 0.8535998 0.60361634 1 P 0 ;0,1,2=231,3=0.000000
L 0.8535998 0.60361634 0.8559 0.60103356 1 P 0 ;0,1,2=231,3=0.000000
L 0.8559 0.60103356 0.85858346 0.59948287 1 P 0 ;0,1,2=231,3=0.000000
L 0.85858346 0.59948287 0.86816683 0.59948287 1 P 0 ;0,1,2=231,3=0.000000
L 0.85858346 0.59948287 0.85283327 0.5845 1 P 0 ;0,1,2=231,3=0.000000
L 0.83793337 0.59069961 0.83563386 0.58708278 1 P 0 ;0,1,2=231,3=0.000000
L 0.83563386 0.58708278 0.83256713 0.58501654 1 P 0 ;0,1,2=231,3=0.000000
L 0.83256713 0.58501654 0.82911644 0.5845 1 P 0 ;0,1,2=231,3=0.000000
L 0.82911644 0.5845 0.8260497 0.58501654 1 P 0 ;0,1,2=231,3=0.000000
L 0.8260497 0.58501654 0.82298297 0.58759931 1 P 0 ;0,1,2=231,3=0.000000
L 0.82298297 0.58759931 0.82106673 0.59069961 1 P 0 ;0,1,2=231,3=0.000000
L 0.82106673 0.59069961 0.82068346 0.5937999 1 P 0 ;0,1,2=231,3=0.000000
L 0.82068346 0.5937999 0.82145 0.59741575 1 P 0 ;0,1,2=231,3=0.000000
L 0.82145 0.59741575 0.82413346 0.59999951 1 P 0 ;0,1,2=231,3=0.000000
L 0.82413346 0.59999951 0.82681693 0.60103356 1 P 0 ;0,1,2=231,3=0.000000
L 0.82681693 0.60103356 0.83026693 0.60103356 1 P 0 ;0,1,2=231,3=0.000000
L 0.82681693 0.60103356 0.82451673 0.60258317 1 P 0 ;0,1,2=231,3=0.000000
L 0.82451673 0.60258317 0.8225998 0.60516594 1 P 0 ;0,1,2=231,3=0.000000
L 0.8225998 0.60516594 0.82183327 0.60826624 1 P 0 ;0,1,2=231,3=0.000000
L 0.82183327 0.60826624 0.8225998 0.61136654 1 P 0 ;0,1,2=231,3=0.000000
L 0.8225998 0.61136654 0.82451673 0.61394931 1 P 0 ;0,1,2=231,3=0.000000
L 0.82451673 0.61394931 0.82796673 0.6155 1 P 0 ;0,1,2=231,3=0.000000
L 0.82796673 0.6155 0.83141663 0.61498337 1 P 0 ;0,1,2=231,3=0.000000
L 0.83141663 0.61498337 0.83486663 0.61291624 1 P 0 ;0,1,2=231,3=0.000000
L 5.932 4.155 5.932 4.065 1 P 0 
L 5.888 4.155 5.932 4.155 1 P 0 
L 5.932 4.065 5.888 4.065 1 P 0 
L 5.888 4.065 5.888 4.155 1 P 0 
L 5.9395 4.00083317 5.9705 4.00083317 1 P 0 ;0,1,2=232,3=90.000000
L 5.9705 4.00083317 5.9705 4.01041654 1 P 0 ;0,1,2=232,3=90.000000
L 5.9705 4.01041654 5.96894931 4.01348327 1 P 0 ;0,1,2=232,3=90.000000
L 5.96894931 4.01348327 5.96688307 4.0154002 1 P 0 ;0,1,2=232,3=90.000000
L 5.96688307 4.0154002 5.9627497 4.01616673 1 P 0 ;0,1,2=232,3=90.000000
L 5.9627497 4.01616673 5.95861634 4.0154002 1 P 0 ;0,1,2=232,3=90.000000
L 5.95861634 4.0154002 5.95603356 4.0131 1 P 0 ;0,1,2=232,3=90.000000
L 5.95603356 4.0131 5.95448287 4.01041654 1 P 0 ;0,1,2=232,3=90.000000
L 5.95448287 4.01041654 5.95448287 4.00083317 1 P 0 ;0,1,2=232,3=90.000000
L 5.95448287 4.01041654 5.9395 4.01616673 1 P 0 ;0,1,2=232,3=90.000000
L 5.9395 4.03949961 5.9705 4.03949961 1 P 0 ;0,1,2=232,3=90.000000
L 5.9705 4.03949961 5.9643003 4.0348999 1 P 0 ;0,1,2=232,3=90.000000
L 5.9395 4.0348999 5.9395 4.04409931 1 P 0 ;0,1,2=232,3=90.000000
L 5.9395 4.07049961 5.9705 4.07049961 1 P 0 ;0,1,2=232,3=90.000000
L 5.9705 4.07049961 5.9643003 4.0658999 1 P 0 ;0,1,2=232,3=90.000000
L 5.9395 4.0658999 5.9395 4.07509931 1 P 0 ;0,1,2=232,3=90.000000
L 5.9395 4.10149961 5.94001654 4.10418307 1 P 0 ;0,1,2=232,3=90.000000
L 5.94001654 4.10418307 5.94156614 4.1072498 1 P 0 ;0,1,2=232,3=90.000000
L 5.94156614 4.1072498 5.94414892 4.10916673 1 P 0 ;0,1,2=232,3=90.000000
L 5.94414892 4.10916673 5.94776673 4.10993327 1 P 0 ;0,1,2=232,3=90.000000
L 5.94776673 4.10993327 5.95138268 4.10916673 1 P 0 ;0,1,2=232,3=90.000000
L 5.95138268 4.10916673 5.95448287 4.10686654 1 P 0 ;0,1,2=232,3=90.000000
L 5.95448287 4.10686654 5.95603356 4.10341654 1 P 0 ;0,1,2=232,3=90.000000
L 5.95603356 4.10341654 5.95603356 4.09958337 1 P 0 ;0,1,2=232,3=90.000000
L 5.95603356 4.09958337 5.95706663 4.09728317 1 P 0 ;0,1,2=232,3=90.000000
L 5.95706663 4.09728317 5.95964941 4.09536614 1 P 0 ;0,1,2=232,3=90.000000
L 5.95964941 4.09536614 5.96326624 4.0945997 1 P 0 ;0,1,2=232,3=90.000000
L 5.96326624 4.0945997 5.96688307 4.0957501 1 P 0 ;0,1,2=232,3=90.000000
L 5.96688307 4.0957501 5.96946683 4.09843287 1 P 0 ;0,1,2=232,3=90.000000
L 5.96946683 4.09843287 5.9705 4.10149961 1 P 0 ;0,1,2=232,3=90.000000
L 5.9705 4.10149961 5.96946683 4.10456634 1 P 0 ;0,1,2=232,3=90.000000
L 5.96946683 4.10456634 5.96688307 4.1072498 1 P 0 ;0,1,2=232,3=90.000000
L 5.96688307 4.1072498 5.96326624 4.1084002 1 P 0 ;0,1,2=232,3=90.000000
L 5.96326624 4.1084002 5.95964941 4.10763307 1 P 0 ;0,1,2=232,3=90.000000
L 5.95964941 4.10763307 5.95706663 4.10571673 1 P 0 ;0,1,2=232,3=90.000000
L 5.95706663 4.10571673 5.95603356 4.10341654 1 P 0 ;0,1,2=232,3=90.000000
L 5.95603356 4.10341654 5.95603356 4.09958337 1 P 0 ;0,1,2=232,3=90.000000
L 5.95603356 4.09958337 5.95448287 4.09613337 1 P 0 ;0,1,2=232,3=90.000000
L 5.95448287 4.09613337 5.95138268 4.09383317 1 P 0 ;0,1,2=232,3=90.000000
L 5.95138268 4.09383317 5.94776673 4.09306663 1 P 0 ;0,1,2=232,3=90.000000
L 5.94776673 4.09306663 5.94414892 4.09383317 1 P 0 ;0,1,2=232,3=90.000000
L 5.94414892 4.09383317 5.94156614 4.0957501 1 P 0 ;0,1,2=232,3=90.000000
L 5.94156614 4.0957501 5.94001654 4.09881683 1 P 0 ;0,1,2=232,3=90.000000
L 5.94001654 4.09881683 5.9395 4.10149961 1 P 0 ;0,1,2=232,3=90.000000
L 6.003 4.155 6.047 4.155 1 P 0 
L 6.047 4.155 6.047 4.065 1 P 0 
L 6.047 4.065 6.003 4.065 1 P 0 
L 6.003 4.065 6.003 4.155 1 P 0 
L 6.0545 4.00583317 6.0855 4.00583317 1 P 0 ;0,1,2=233,3=90.000000
L 6.0855 4.00583317 6.0855 4.01541654 1 P 0 ;0,1,2=233,3=90.000000
L 6.0855 4.01541654 6.08394931 4.01848327 1 P 0 ;0,1,2=233,3=90.000000
L 6.08394931 4.01848327 6.08188307 4.0204002 1 P 0 ;0,1,2=233,3=90.000000
L 6.08188307 4.0204002 6.0777497 4.02116673 1 P 0 ;0,1,2=233,3=90.000000
L 6.0777497 4.02116673 6.07361634 4.0204002 1 P 0 ;0,1,2=233,3=90.000000
L 6.07361634 4.0204002 6.07103356 4.0181 1 P 0 ;0,1,2=233,3=90.000000
L 6.07103356 4.0181 6.06948287 4.01541654 1 P 0 ;0,1,2=233,3=90.000000
L 6.06948287 4.01541654 6.06948287 4.00583317 1 P 0 ;0,1,2=233,3=90.000000
L 6.06948287 4.01541654 6.0545 4.02116673 1 P 0 ;0,1,2=233,3=90.000000
L 6.0545 4.04449961 6.0855 4.04449961 1 P 0 ;0,1,2=233,3=90.000000
L 6.0855 4.04449961 6.0793003 4.0398999 1 P 0 ;0,1,2=233,3=90.000000
L 6.0545 4.0398999 6.0545 4.04909931 1 P 0 ;0,1,2=233,3=90.000000
L 6.0545 4.07549961 6.0855 4.07549961 1 P 0 ;0,1,2=233,3=90.000000
L 6.0855 4.07549961 6.0793003 4.0708999 1 P 0 ;0,1,2=233,3=90.000000
L 6.0545 4.0708999 6.0545 4.08009931 1 P 0 ;0,1,2=233,3=90.000000
L 6.05811585 4.09998287 6.05553307 4.10266634 1 P 0 ;0,1,2=233,3=90.000000
L 6.05553307 4.10266634 6.0545 4.10573307 1 P 0 ;0,1,2=233,3=90.000000
L 6.0545 4.10573307 6.05553307 4.1087998 1 P 0 ;0,1,2=233,3=90.000000
L 6.05553307 4.1087998 6.05863238 4.11148327 1 P 0 ;0,1,2=233,3=90.000000
L 6.05863238 4.11148327 6.06328327 4.1134002 1 P 0 ;0,1,2=233,3=90.000000
L 6.06328327 4.1134002 6.06793327 4.11416673 1 P 0 ;0,1,2=233,3=90.000000
L 6.06793327 4.11416673 6.07361634 4.11416673 1 P 0 ;0,1,2=233,3=90.000000
L 6.07361634 4.11416673 6.07826624 4.1134002 1 P 0 ;0,1,2=233,3=90.000000
L 6.07826624 4.1134002 6.0823997 4.11148327 1 P 0 ;0,1,2=233,3=90.000000
L 6.0823997 4.11148327 6.08446683 4.10918307 1 P 0 ;0,1,2=233,3=90.000000
L 6.08446683 4.10918307 6.0855 4.10649961 1 P 0 ;0,1,2=233,3=90.000000
L 6.0855 4.10649961 6.08446683 4.10343287 1 P 0 ;0,1,2=233,3=90.000000
L 6.08446683 4.10343287 6.0823997 4.10113337 1 P 0 ;0,1,2=233,3=90.000000
L 6.0823997 4.10113337 6.0793003 4.0995997 1 P 0 ;0,1,2=233,3=90.000000
L 6.0793003 4.0995997 6.07516594 4.09883317 1 P 0 ;0,1,2=233,3=90.000000
L 6.07516594 4.09883317 6.0715501 4.0995997 1 P 0 ;0,1,2=233,3=90.000000
L 6.0715501 4.0995997 6.06793327 4.10151663 1 P 0 ;0,1,2=233,3=90.000000
L 6.06793327 4.10151663 6.06586604 4.10381683 1 P 0 ;0,1,2=233,3=90.000000
L 6.06586604 4.10381683 6.06534951 4.10649961 1 P 0 ;0,1,2=233,3=90.000000
L 6.06534951 4.10649961 6.06638268 4.10956634 1 P 0 ;0,1,2=233,3=90.000000
L 6.06638268 4.10956634 6.06896634 4.11186654 1 P 0 ;0,1,2=233,3=90.000000
L 6.06896634 4.11186654 6.07361634 4.11416673 1 P 0 ;0,1,2=233,3=90.000000
L 0.913 0.732 0.913 0.688 1 P 0 
L 0.823 0.732 0.913 0.732 1 P 0 
L 0.913 0.688 0.823 0.688 1 P 0 
L 0.823 0.688 0.823 0.732 1 P 0 
L 0.99866683 0.6945 0.99866683 0.7255 1 P 0 ;0,1,2=234,3=0.000000
L 0.99866683 0.7255 0.98908346 0.7255 1 P 0 ;0,1,2=234,3=0.000000
L 0.98908346 0.7255 0.98601673 0.72394931 1 P 0 ;0,1,2=234,3=0.000000
L 0.98601673 0.72394931 0.9840998 0.72188307 1 P 0 ;0,1,2=234,3=0.000000
L 0.9840998 0.72188307 0.98333327 0.7177497 1 P 0 ;0,1,2=234,3=0.000000
L 0.98333327 0.7177497 0.9840998 0.71361634 1 P 0 ;0,1,2=234,3=0.000000
L 0.9840998 0.71361634 0.9864 0.71103356 1 P 0 ;0,1,2=234,3=0.000000
L 0.9864 0.71103356 0.98908346 0.70948287 1 P 0 ;0,1,2=234,3=0.000000
L 0.98908346 0.70948287 0.99866683 0.70948287 1 P 0 ;0,1,2=234,3=0.000000
L 0.98908346 0.70948287 0.98333327 0.6945 1 P 0 ;0,1,2=234,3=0.000000
L 0.96728356 0.72033346 0.96498337 0.72343278 1 P 0 ;0,1,2=234,3=0.000000
L 0.96498337 0.72343278 0.9622999 0.72498337 1 P 0 ;0,1,2=234,3=0.000000
L 0.9622999 0.72498337 0.95923317 0.7255 1 P 0 ;0,1,2=234,3=0.000000
L 0.95923317 0.7255 0.9554 0.72446683 1 P 0 ;0,1,2=234,3=0.000000
L 0.9554 0.72446683 0.95271654 0.72188307 1 P 0 ;0,1,2=234,3=0.000000
L 0.95271654 0.72188307 0.95195 0.71878376 1 P 0 ;0,1,2=234,3=0.000000
L 0.95195 0.71878376 0.95233327 0.71568258 1 P 0 ;0,1,2=234,3=0.000000
L 0.95233327 0.71568258 0.95386693 0.7130998 1 P 0 ;0,1,2=234,3=0.000000
L 0.95386693 0.7130998 0.96153337 0.70793327 1 P 0 ;0,1,2=234,3=0.000000
L 0.96153337 0.70793327 0.96498337 0.70431644 1 P 0 ;0,1,2=234,3=0.000000
L 0.96498337 0.70431644 0.96728356 0.69914892 1 P 0 ;0,1,2=234,3=0.000000
L 0.96728356 0.69914892 0.9680501 0.6945 1 P 0 ;0,1,2=234,3=0.000000
L 0.9680501 0.6945 0.95195 0.6945 1 P 0 ;0,1,2=234,3=0.000000
L 0.9244 0.6945 0.9244 0.7255 1 P 0 ;0,1,2=234,3=0.000000
L 0.9244 0.7255 0.93858376 0.70328327 1 P 0 ;0,1,2=234,3=0.000000
L 0.93858376 0.70328327 0.91941634 0.70328327 1 P 0 ;0,1,2=234,3=0.000000
L 2.195 2.997 2.195 2.907 1 P 0 
L 2.195 2.907 2.151 2.907 1 P 0 
L 2.151 2.907 2.151 2.997 1 P 0 
L 2.151 2.997 2.195 2.997 1 P 0 
L 2.1625 3.05783317 2.1935 3.05783317 1 P 0 ;0,1,2=235,3=90.000000
L 2.1935 3.05783317 2.1935 3.06741654 1 P 0 ;0,1,2=235,3=90.000000
L 2.1935 3.06741654 2.19194931 3.07048327 1 P 0 ;0,1,2=235,3=90.000000
L 2.19194931 3.07048327 2.18988307 3.0724002 1 P 0 ;0,1,2=235,3=90.000000
L 2.18988307 3.0724002 2.1857497 3.07316673 1 P 0 ;0,1,2=235,3=90.000000
L 2.1857497 3.07316673 2.18161634 3.0724002 1 P 0 ;0,1,2=235,3=90.000000
L 2.18161634 3.0724002 2.17903356 3.0701 1 P 0 ;0,1,2=235,3=90.000000
L 2.17903356 3.0701 2.17748287 3.06741654 1 P 0 ;0,1,2=235,3=90.000000
L 2.17748287 3.06741654 2.17748287 3.05783317 1 P 0 ;0,1,2=235,3=90.000000
L 2.17748287 3.06741654 2.1625 3.07316673 1 P 0 ;0,1,2=235,3=90.000000
L 2.1625 3.1011 2.1935 3.1011 1 P 0 ;0,1,2=235,3=90.000000
L 2.1935 3.1011 2.17128327 3.08691624 1 P 0 ;0,1,2=235,3=90.000000
L 2.17128327 3.08691624 2.17128327 3.10608366 1 P 0 ;0,1,2=235,3=90.000000
L 2.1625 3.12749961 2.1935 3.12749961 1 P 0 ;0,1,2=235,3=90.000000
L 2.1935 3.12749961 2.1873003 3.1228999 1 P 0 ;0,1,2=235,3=90.000000
L 2.1625 3.1228999 2.1625 3.13209931 1 P 0 ;0,1,2=235,3=90.000000
L 2.17541575 3.15121644 2.17903356 3.1538999 1 P 0 ;0,1,2=235,3=90.000000
L 2.17903356 3.1538999 2.1810998 3.1562001 1 P 0 ;0,1,2=235,3=90.000000
L 2.1810998 3.1562001 2.18213287 3.15926683 1 P 0 ;0,1,2=235,3=90.000000
L 2.18213287 3.15926683 2.1810998 3.1619503 1 P 0 ;0,1,2=235,3=90.000000
L 2.1810998 3.1619503 2.17903356 3.16386654 1 P 0 ;0,1,2=235,3=90.000000
L 2.17903356 3.16386654 2.17593327 3.1654002 1 P 0 ;0,1,2=235,3=90.000000
L 2.17593327 3.1654002 2.17231644 3.16578346 1 P 0 ;0,1,2=235,3=90.000000
L 2.17231644 3.16578346 2.16921614 3.1654002 1 P 0 ;0,1,2=235,3=90.000000
L 2.16921614 3.1654002 2.16611585 3.16386654 1 P 0 ;0,1,2=235,3=90.000000
L 2.16611585 3.16386654 2.16353307 3.16156634 1 P 0 ;0,1,2=235,3=90.000000
L 2.16353307 3.16156634 2.1625 3.15888356 1 P 0 ;0,1,2=235,3=90.000000
L 2.1625 3.15888356 2.16353307 3.15581683 1 P 0 ;0,1,2=235,3=90.000000
L 2.16353307 3.15581683 2.16663238 3.15313337 1 P 0 ;0,1,2=235,3=90.000000
L 2.16663238 3.15313337 2.17128327 3.1515997 1 P 0 ;0,1,2=235,3=90.000000
L 2.17128327 3.1515997 2.1764498 3.15121644 1 P 0 ;0,1,2=235,3=90.000000
L 2.1764498 3.15121644 2.18316594 3.15198287 1 P 0 ;0,1,2=235,3=90.000000
L 2.18316594 3.15198287 2.18678376 3.15313337 1 P 0 ;0,1,2=235,3=90.000000
L 2.18678376 3.15313337 2.1903997 3.15504961 1 P 0 ;0,1,2=235,3=90.000000
L 2.1903997 3.15504961 2.19298337 3.15773307 1 P 0 ;0,1,2=235,3=90.000000
L 2.19298337 3.15773307 2.1935 3.16041654 1 P 0 ;0,1,2=235,3=90.000000
L 2.1935 3.16041654 2.19246683 3.1631 1 P 0 ;0,1,2=235,3=90.000000
L 2.19246683 3.1631 2.18988307 3.16501703 1 P 0 ;0,1,2=235,3=90.000000
L 4.95 1.832 4.95 1.788 1 P 0 
L 4.86 1.832 4.95 1.832 1 P 0 
L 4.95 1.788 4.86 1.788 1 P 0 
L 4.86 1.788 4.86 1.832 1 P 0 
L 5.10416683 1.7895 5.10416683 1.8205 1 P 0 ;0,1,2=236,3=0.000000
L 5.10416683 1.8205 5.09458346 1.8205 1 P 0 ;0,1,2=236,3=0.000000
L 5.09458346 1.8205 5.09151673 1.81894931 1 P 0 ;0,1,2=236,3=0.000000
L 5.09151673 1.81894931 5.0895998 1.81688307 1 P 0 ;0,1,2=236,3=0.000000
L 5.0895998 1.81688307 5.08883327 1.8127497 1 P 0 ;0,1,2=236,3=0.000000
L 5.08883327 1.8127497 5.0895998 1.80861634 1 P 0 ;0,1,2=236,3=0.000000
L 5.0895998 1.80861634 5.0919 1.80603356 1 P 0 ;0,1,2=236,3=0.000000
L 5.0919 1.80603356 5.09458346 1.80448287 1 P 0 ;0,1,2=236,3=0.000000
L 5.09458346 1.80448287 5.10416683 1.80448287 1 P 0 ;0,1,2=236,3=0.000000
L 5.09458346 1.80448287 5.08883327 1.7895 1 P 0 ;0,1,2=236,3=0.000000
L 5.06550039 1.7895 5.06550039 1.8205 1 P 0 ;0,1,2=236,3=0.000000
L 5.06550039 1.8205 5.0701001 1.8143003 1 P 0 ;0,1,2=236,3=0.000000
L 5.0701001 1.7895 5.06090069 1.7895 1 P 0 ;0,1,2=236,3=0.000000
L 5.04101713 1.79311585 5.03833366 1.79053307 1 P 0 ;0,1,2=236,3=0.000000
L 5.03833366 1.79053307 5.03526693 1.7895 1 P 0 ;0,1,2=236,3=0.000000
L 5.03526693 1.7895 5.0322002 1.79053307 1 P 0 ;0,1,2=236,3=0.000000
L 5.0322002 1.79053307 5.02951673 1.79363238 1 P 0 ;0,1,2=236,3=0.000000
L 5.02951673 1.79363238 5.0275998 1.79828327 1 P 0 ;0,1,2=236,3=0.000000
L 5.0275998 1.79828327 5.02683327 1.80293327 1 P 0 ;0,1,2=236,3=0.000000
L 5.02683327 1.80293327 5.02683327 1.80861634 1 P 0 ;0,1,2=236,3=0.000000
L 5.02683327 1.80861634 5.0275998 1.81326624 1 P 0 ;0,1,2=236,3=0.000000
L 5.0275998 1.81326624 5.02951673 1.8173997 1 P 0 ;0,1,2=236,3=0.000000
L 5.02951673 1.8173997 5.03181693 1.81946683 1 P 0 ;0,1,2=236,3=0.000000
L 5.03181693 1.81946683 5.03450039 1.8205 1 P 0 ;0,1,2=236,3=0.000000
L 5.03450039 1.8205 5.03756713 1.81946683 1 P 0 ;0,1,2=236,3=0.000000
L 5.03756713 1.81946683 5.03986663 1.8173997 1 P 0 ;0,1,2=236,3=0.000000
L 5.03986663 1.8173997 5.0414003 1.8143003 1 P 0 ;0,1,2=236,3=0.000000
L 5.0414003 1.8143003 5.04216683 1.81016594 1 P 0 ;0,1,2=236,3=0.000000
L 5.04216683 1.81016594 5.0414003 1.8065501 1 P 0 ;0,1,2=236,3=0.000000
L 5.0414003 1.8065501 5.03948337 1.80293327 1 P 0 ;0,1,2=236,3=0.000000
L 5.03948337 1.80293327 5.03718317 1.80086604 1 P 0 ;0,1,2=236,3=0.000000
L 5.03718317 1.80086604 5.03450039 1.80034951 1 P 0 ;0,1,2=236,3=0.000000
L 5.03450039 1.80034951 5.03143366 1.80138268 1 P 0 ;0,1,2=236,3=0.000000
L 5.03143366 1.80138268 5.02913346 1.80396634 1 P 0 ;0,1,2=236,3=0.000000
L 5.02913346 1.80396634 5.02683327 1.80861634 1 P 0 ;0,1,2=236,3=0.000000
L 5.01193337 1.79414892 5.00963386 1.79156614 1 P 0 ;0,1,2=236,3=0.000000
L 5.00963386 1.79156614 5.00695039 1.79001654 1 P 0 ;0,1,2=236,3=0.000000
L 5.00695039 1.79001654 5.00350039 1.7895 1 P 0 ;0,1,2=236,3=0.000000
L 5.00350039 1.7895 5.0000497 1.79053307 1 P 0 ;0,1,2=236,3=0.000000
L 5.0000497 1.79053307 4.99736693 1.79259931 1 P 0 ;0,1,2=236,3=0.000000
L 4.99736693 1.79259931 4.99545 1.79621614 1 P 0 ;0,1,2=236,3=0.000000
L 4.99545 1.79621614 4.99506673 1.80034951 1 P 0 ;0,1,2=236,3=0.000000
L 4.99506673 1.80034951 4.99583327 1.80448287 1 P 0 ;0,1,2=236,3=0.000000
L 4.99583327 1.80448287 4.9977502 1.80706663 1 P 0 ;0,1,2=236,3=0.000000
L 4.9977502 1.80706663 5.00043366 1.80913287 1 P 0 ;0,1,2=236,3=0.000000
L 5.00043366 1.80913287 5.00311644 1.80964941 1 P 0 ;0,1,2=236,3=0.000000
L 5.00311644 1.80964941 5.0057999 1.80913287 1 P 0 ;0,1,2=236,3=0.000000
L 5.0057999 1.80913287 5.0092499 1.80706663 1 P 0 ;0,1,2=236,3=0.000000
L 5.0092499 1.80706663 5.0081001 1.8205 1 P 0 ;0,1,2=236,3=0.000000
L 5.0081001 1.8205 4.9977502 1.8205 1 P 0 ;0,1,2=236,3=0.000000
L 1.033 3.755 1.077 3.755 1 P 0 
L 1.077 3.755 1.077 3.665 1 P 0 
L 1.077 3.665 1.033 3.665 1 P 0 
L 1.033 3.665 1.033 3.755 1 P 0 
L 1.0545 3.77133317 1.0855 3.77133317 1 P 0 ;0,1,2=237,3=90.000000
L 1.0855 3.77133317 1.0855 3.78091654 1 P 0 ;0,1,2=237,3=90.000000
L 1.0855 3.78091654 1.08394931 3.78398327 1 P 0 ;0,1,2=237,3=90.000000
L 1.08394931 3.78398327 1.08188307 3.7859002 1 P 0 ;0,1,2=237,3=90.000000
L 1.08188307 3.7859002 1.0777497 3.78666673 1 P 0 ;0,1,2=237,3=90.000000
L 1.0777497 3.78666673 1.07361634 3.7859002 1 P 0 ;0,1,2=237,3=90.000000
L 1.07361634 3.7859002 1.07103356 3.7836 1 P 0 ;0,1,2=237,3=90.000000
L 1.07103356 3.7836 1.06948287 3.78091654 1 P 0 ;0,1,2=237,3=90.000000
L 1.06948287 3.78091654 1.06948287 3.77133317 1 P 0 ;0,1,2=237,3=90.000000
L 1.06948287 3.78091654 1.0545 3.78666673 1 P 0 ;0,1,2=237,3=90.000000
L 1.0545 3.80999961 1.0855 3.80999961 1 P 0 ;0,1,2=237,3=90.000000
L 1.0855 3.80999961 1.0793003 3.8053999 1 P 0 ;0,1,2=237,3=90.000000
L 1.0545 3.8053999 1.0545 3.81459931 1 P 0 ;0,1,2=237,3=90.000000
L 1.0545 3.84099961 1.05501654 3.84368307 1 P 0 ;0,1,2=237,3=90.000000
L 1.05501654 3.84368307 1.05656614 3.8467498 1 P 0 ;0,1,2=237,3=90.000000
L 1.05656614 3.8467498 1.05914892 3.84866673 1 P 0 ;0,1,2=237,3=90.000000
L 1.05914892 3.84866673 1.06276673 3.84943327 1 P 0 ;0,1,2=237,3=90.000000
L 1.06276673 3.84943327 1.06638268 3.84866673 1 P 0 ;0,1,2=237,3=90.000000
L 1.06638268 3.84866673 1.06948287 3.84636654 1 P 0 ;0,1,2=237,3=90.000000
L 1.06948287 3.84636654 1.07103356 3.84291654 1 P 0 ;0,1,2=237,3=90.000000
L 1.07103356 3.84291654 1.07103356 3.83908337 1 P 0 ;0,1,2=237,3=90.000000
L 1.07103356 3.83908337 1.07206663 3.83678317 1 P 0 ;0,1,2=237,3=90.000000
L 1.07206663 3.83678317 1.07464941 3.83486614 1 P 0 ;0,1,2=237,3=90.000000
L 1.07464941 3.83486614 1.07826624 3.8340997 1 P 0 ;0,1,2=237,3=90.000000
L 1.07826624 3.8340997 1.08188307 3.8352501 1 P 0 ;0,1,2=237,3=90.000000
L 1.08188307 3.8352501 1.08446683 3.83793287 1 P 0 ;0,1,2=237,3=90.000000
L 1.08446683 3.83793287 1.0855 3.84099961 1 P 0 ;0,1,2=237,3=90.000000
L 1.0855 3.84099961 1.08446683 3.84406634 1 P 0 ;0,1,2=237,3=90.000000
L 1.08446683 3.84406634 1.08188307 3.8467498 1 P 0 ;0,1,2=237,3=90.000000
L 1.08188307 3.8467498 1.07826624 3.8479002 1 P 0 ;0,1,2=237,3=90.000000
L 1.07826624 3.8479002 1.07464941 3.84713307 1 P 0 ;0,1,2=237,3=90.000000
L 1.07464941 3.84713307 1.07206663 3.84521673 1 P 0 ;0,1,2=237,3=90.000000
L 1.07206663 3.84521673 1.07103356 3.84291654 1 P 0 ;0,1,2=237,3=90.000000
L 1.07103356 3.84291654 1.07103356 3.83908337 1 P 0 ;0,1,2=237,3=90.000000
L 1.07103356 3.83908337 1.06948287 3.83563337 1 P 0 ;0,1,2=237,3=90.000000
L 1.06948287 3.83563337 1.06638268 3.83333317 1 P 0 ;0,1,2=237,3=90.000000
L 1.06638268 3.83333317 1.06276673 3.83256663 1 P 0 ;0,1,2=237,3=90.000000
L 1.06276673 3.83256663 1.05914892 3.83333317 1 P 0 ;0,1,2=237,3=90.000000
L 1.05914892 3.83333317 1.05656614 3.8352501 1 P 0 ;0,1,2=237,3=90.000000
L 1.05656614 3.8352501 1.05501654 3.83831683 1 P 0 ;0,1,2=237,3=90.000000
L 1.05501654 3.83831683 1.0545 3.84099961 1 P 0 ;0,1,2=237,3=90.000000
L 4.95 2.047 4.95 2.003 1 P 0 
L 4.86 2.047 4.95 2.047 1 P 0 
L 4.95 2.003 4.86 2.003 1 P 0 
L 4.86 2.003 4.86 2.047 1 P 0 
L 5.08916683 2.0045 5.08916683 2.0355 1 P 0 ;0,1,2=238,3=0.000000
L 5.08916683 2.0355 5.07958346 2.0355 1 P 0 ;0,1,2=238,3=0.000000
L 5.07958346 2.0355 5.07651673 2.03394931 1 P 0 ;0,1,2=238,3=0.000000
L 5.07651673 2.03394931 5.0745998 2.03188307 1 P 0 ;0,1,2=238,3=0.000000
L 5.0745998 2.03188307 5.07383327 2.0277497 1 P 0 ;0,1,2=238,3=0.000000
L 5.07383327 2.0277497 5.0745998 2.02361634 1 P 0 ;0,1,2=238,3=0.000000
L 5.0745998 2.02361634 5.0769 2.02103356 1 P 0 ;0,1,2=238,3=0.000000
L 5.0769 2.02103356 5.07958346 2.01948287 1 P 0 ;0,1,2=238,3=0.000000
L 5.07958346 2.01948287 5.08916683 2.01948287 1 P 0 ;0,1,2=238,3=0.000000
L 5.07958346 2.01948287 5.07383327 2.0045 1 P 0 ;0,1,2=238,3=0.000000
L 5.05778356 2.03033346 5.05548337 2.03343278 1 P 0 ;0,1,2=238,3=0.000000
L 5.05548337 2.03343278 5.0527999 2.03498337 1 P 0 ;0,1,2=238,3=0.000000
L 5.0527999 2.03498337 5.04973317 2.0355 1 P 0 ;0,1,2=238,3=0.000000
L 5.04973317 2.0355 5.0459 2.03446683 1 P 0 ;0,1,2=238,3=0.000000
L 5.0459 2.03446683 5.04321654 2.03188307 1 P 0 ;0,1,2=238,3=0.000000
L 5.04321654 2.03188307 5.04245 2.02878376 1 P 0 ;0,1,2=238,3=0.000000
L 5.04245 2.02878376 5.04283327 2.02568258 1 P 0 ;0,1,2=238,3=0.000000
L 5.04283327 2.02568258 5.04436693 2.0230998 1 P 0 ;0,1,2=238,3=0.000000
L 5.04436693 2.0230998 5.05203337 2.01793327 1 P 0 ;0,1,2=238,3=0.000000
L 5.05203337 2.01793327 5.05548337 2.01431644 1 P 0 ;0,1,2=238,3=0.000000
L 5.05548337 2.01431644 5.05778356 2.00914892 1 P 0 ;0,1,2=238,3=0.000000
L 5.05778356 2.00914892 5.0585501 2.0045 1 P 0 ;0,1,2=238,3=0.000000
L 5.0585501 2.0045 5.04245 2.0045 1 P 0 ;0,1,2=238,3=0.000000
L 5.02678356 2.01741575 5.0241001 2.02103356 1 P 0 ;0,1,2=238,3=0.000000
L 5.0241001 2.02103356 5.0217999 2.0230998 1 P 0 ;0,1,2=238,3=0.000000
L 5.0217999 2.0230998 5.01873317 2.02413287 1 P 0 ;0,1,2=238,3=0.000000
L 5.01873317 2.02413287 5.0160497 2.0230998 1 P 0 ;0,1,2=238,3=0.000000
L 5.0160497 2.0230998 5.01413346 2.02103356 1 P 0 ;0,1,2=238,3=0.000000
L 5.01413346 2.02103356 5.0125998 2.01793327 1 P 0 ;0,1,2=238,3=0.000000
L 5.0125998 2.01793327 5.01221654 2.01431644 1 P 0 ;0,1,2=238,3=0.000000
L 5.01221654 2.01431644 5.0125998 2.01121614 1 P 0 ;0,1,2=238,3=0.000000
L 5.0125998 2.01121614 5.01413346 2.00811585 1 P 0 ;0,1,2=238,3=0.000000
L 5.01413346 2.00811585 5.01643366 2.00553307 1 P 0 ;0,1,2=238,3=0.000000
L 5.01643366 2.00553307 5.01911644 2.0045 1 P 0 ;0,1,2=238,3=0.000000
L 5.01911644 2.0045 5.02218317 2.00553307 1 P 0 ;0,1,2=238,3=0.000000
L 5.02218317 2.00553307 5.02486663 2.00863238 1 P 0 ;0,1,2=238,3=0.000000
L 5.02486663 2.00863238 5.0264003 2.01328327 1 P 0 ;0,1,2=238,3=0.000000
L 5.0264003 2.01328327 5.02678356 2.0184498 1 P 0 ;0,1,2=238,3=0.000000
L 5.02678356 2.0184498 5.02601713 2.02516594 1 P 0 ;0,1,2=238,3=0.000000
L 5.02601713 2.02516594 5.02486663 2.02878376 1 P 0 ;0,1,2=238,3=0.000000
L 5.02486663 2.02878376 5.02295039 2.0323997 1 P 0 ;0,1,2=238,3=0.000000
L 5.02295039 2.0323997 5.02026693 2.03498337 1 P 0 ;0,1,2=238,3=0.000000
L 5.02026693 2.03498337 5.01758346 2.0355 1 P 0 ;0,1,2=238,3=0.000000
L 5.01758346 2.0355 5.0149 2.03446683 1 P 0 ;0,1,2=238,3=0.000000
L 5.0149 2.03446683 5.01298297 2.03188307 1 P 0 ;0,1,2=238,3=0.000000
L 4.9839 2.0045 4.9839 2.0355 1 P 0 ;0,1,2=238,3=0.000000
L 4.9839 2.0355 4.99808376 2.01328327 1 P 0 ;0,1,2=238,3=0.000000
L 4.99808376 2.01328327 4.97891634 2.01328327 1 P 0 ;0,1,2=238,3=0.000000
L 4.95 1.787 4.95 1.743 1 P 0 
L 4.86 1.787 4.95 1.787 1 P 0 
L 4.95 1.743 4.86 1.743 1 P 0 
L 4.86 1.743 4.86 1.787 1 P 0 
L 5.10416683 1.7445 5.10416683 1.7755 1 P 0 ;0,1,2=239,3=0.000000
L 5.10416683 1.7755 5.09458346 1.7755 1 P 0 ;0,1,2=239,3=0.000000
L 5.09458346 1.7755 5.09151673 1.77394931 1 P 0 ;0,1,2=239,3=0.000000
L 5.09151673 1.77394931 5.0895998 1.77188307 1 P 0 ;0,1,2=239,3=0.000000
L 5.0895998 1.77188307 5.08883327 1.7677497 1 P 0 ;0,1,2=239,3=0.000000
L 5.08883327 1.7677497 5.0895998 1.76361634 1 P 0 ;0,1,2=239,3=0.000000
L 5.0895998 1.76361634 5.0919 1.76103356 1 P 0 ;0,1,2=239,3=0.000000
L 5.0919 1.76103356 5.09458346 1.75948287 1 P 0 ;0,1,2=239,3=0.000000
L 5.09458346 1.75948287 5.10416683 1.75948287 1 P 0 ;0,1,2=239,3=0.000000
L 5.09458346 1.75948287 5.08883327 1.7445 1 P 0 ;0,1,2=239,3=0.000000
L 5.07278356 1.77033346 5.07048337 1.77343278 1 P 0 ;0,1,2=239,3=0.000000
L 5.07048337 1.77343278 5.0677999 1.77498337 1 P 0 ;0,1,2=239,3=0.000000
L 5.0677999 1.77498337 5.06473317 1.7755 1 P 0 ;0,1,2=239,3=0.000000
L 5.06473317 1.7755 5.0609 1.77446683 1 P 0 ;0,1,2=239,3=0.000000
L 5.0609 1.77446683 5.05821654 1.77188307 1 P 0 ;0,1,2=239,3=0.000000
L 5.05821654 1.77188307 5.05745 1.76878376 1 P 0 ;0,1,2=239,3=0.000000
L 5.05745 1.76878376 5.05783327 1.76568258 1 P 0 ;0,1,2=239,3=0.000000
L 5.05783327 1.76568258 5.05936693 1.7630998 1 P 0 ;0,1,2=239,3=0.000000
L 5.05936693 1.7630998 5.06703337 1.75793327 1 P 0 ;0,1,2=239,3=0.000000
L 5.06703337 1.75793327 5.07048337 1.75431644 1 P 0 ;0,1,2=239,3=0.000000
L 5.07048337 1.75431644 5.07278356 1.74914892 1 P 0 ;0,1,2=239,3=0.000000
L 5.07278356 1.74914892 5.0735501 1.7445 1 P 0 ;0,1,2=239,3=0.000000
L 5.0735501 1.7445 5.05745 1.7445 1 P 0 ;0,1,2=239,3=0.000000
L 5.03450039 1.7755 5.03756713 1.77446683 1 P 0 ;0,1,2=239,3=0.000000
L 5.03756713 1.77446683 5.03986663 1.77188307 1 P 0 ;0,1,2=239,3=0.000000
L 5.03986663 1.77188307 5.0414003 1.76878376 1 P 0 ;0,1,2=239,3=0.000000
L 5.0414003 1.76878376 5.0425501 1.76464941 1 P 0 ;0,1,2=239,3=0.000000
L 5.0425501 1.76464941 5.04293337 1.75999951 1 P 0 ;0,1,2=239,3=0.000000
L 5.04293337 1.75999951 5.0425501 1.75534951 1 P 0 ;0,1,2=239,3=0.000000
L 5.0425501 1.75534951 5.0414003 1.75121614 1 P 0 ;0,1,2=239,3=0.000000
L 5.0414003 1.75121614 5.03986663 1.74811585 1 P 0 ;0,1,2=239,3=0.000000
L 5.03986663 1.74811585 5.03756713 1.74553307 1 P 0 ;0,1,2=239,3=0.000000
L 5.03756713 1.74553307 5.03450039 1.7445 1 P 0 ;0,1,2=239,3=0.000000
L 5.03450039 1.7445 5.03143366 1.74553307 1 P 0 ;0,1,2=239,3=0.000000
L 5.03143366 1.74553307 5.02913346 1.74811585 1 P 0 ;0,1,2=239,3=0.000000
L 5.02913346 1.74811585 5.0275998 1.75121614 1 P 0 ;0,1,2=239,3=0.000000
L 5.0275998 1.75121614 5.02645 1.75534951 1 P 0 ;0,1,2=239,3=0.000000
L 5.02645 1.75534951 5.02606673 1.75999951 1 P 0 ;0,1,2=239,3=0.000000
L 5.02606673 1.75999951 5.02645 1.76464941 1 P 0 ;0,1,2=239,3=0.000000
L 5.02645 1.76464941 5.0275998 1.76878376 1 P 0 ;0,1,2=239,3=0.000000
L 5.0275998 1.76878376 5.02913346 1.77188307 1 P 0 ;0,1,2=239,3=0.000000
L 5.02913346 1.77188307 5.03143366 1.77446683 1 P 0 ;0,1,2=239,3=0.000000
L 5.03143366 1.77446683 5.03450039 1.7755 1 P 0 ;0,1,2=239,3=0.000000
L 5.01001713 1.74811585 5.00733366 1.74553307 1 P 0 ;0,1,2=239,3=0.000000
L 5.00733366 1.74553307 5.00426693 1.7445 1 P 0 ;0,1,2=239,3=0.000000
L 5.00426693 1.7445 5.0012002 1.74553307 1 P 0 ;0,1,2=239,3=0.000000
L 5.0012002 1.74553307 4.99851673 1.74863238 1 P 0 ;0,1,2=239,3=0.000000
L 4.99851673 1.74863238 4.9965998 1.75328327 1 P 0 ;0,1,2=239,3=0.000000
L 4.9965998 1.75328327 4.99583327 1.75793327 1 P 0 ;0,1,2=239,3=0.000000
L 4.99583327 1.75793327 4.99583327 1.76361634 1 P 0 ;0,1,2=239,3=0.000000
L 4.99583327 1.76361634 4.9965998 1.76826624 1 P 0 ;0,1,2=239,3=0.000000
L 4.9965998 1.76826624 4.99851673 1.7723997 1 P 0 ;0,1,2=239,3=0.000000
L 4.99851673 1.7723997 5.00081693 1.77446683 1 P 0 ;0,1,2=239,3=0.000000
L 5.00081693 1.77446683 5.00350039 1.7755 1 P 0 ;0,1,2=239,3=0.000000
L 5.00350039 1.7755 5.00656713 1.77446683 1 P 0 ;0,1,2=239,3=0.000000
L 5.00656713 1.77446683 5.00886663 1.7723997 1 P 0 ;0,1,2=239,3=0.000000
L 5.00886663 1.7723997 5.0104003 1.7693003 1 P 0 ;0,1,2=239,3=0.000000
L 5.0104003 1.7693003 5.01116683 1.76516594 1 P 0 ;0,1,2=239,3=0.000000
L 5.01116683 1.76516594 5.0104003 1.7615501 1 P 0 ;0,1,2=239,3=0.000000
L 5.0104003 1.7615501 5.00848337 1.75793327 1 P 0 ;0,1,2=239,3=0.000000
L 5.00848337 1.75793327 5.00618317 1.75586604 1 P 0 ;0,1,2=239,3=0.000000
L 5.00618317 1.75586604 5.00350039 1.75534951 1 P 0 ;0,1,2=239,3=0.000000
L 5.00350039 1.75534951 5.00043366 1.75638268 1 P 0 ;0,1,2=239,3=0.000000
L 5.00043366 1.75638268 4.99813346 1.75896634 1 P 0 ;0,1,2=239,3=0.000000
L 4.99813346 1.75896634 4.99583327 1.76361634 1 P 0 ;0,1,2=239,3=0.000000
L 4.95 1.997 4.95 1.953 1 P 0 
L 4.86 1.997 4.95 1.997 1 P 0 
L 4.95 1.953 4.86 1.953 1 P 0 
L 4.86 1.953 4.86 1.997 1 P 0 
L 5.08916683 1.9595 5.08916683 1.9905 1 P 0 ;0,1,2=240,3=0.000000
L 5.08916683 1.9905 5.07958346 1.9905 1 P 0 ;0,1,2=240,3=0.000000
L 5.07958346 1.9905 5.07651673 1.98894931 1 P 0 ;0,1,2=240,3=0.000000
L 5.07651673 1.98894931 5.0745998 1.98688307 1 P 0 ;0,1,2=240,3=0.000000
L 5.0745998 1.98688307 5.07383327 1.9827497 1 P 0 ;0,1,2=240,3=0.000000
L 5.07383327 1.9827497 5.0745998 1.97861634 1 P 0 ;0,1,2=240,3=0.000000
L 5.0745998 1.97861634 5.0769 1.97603356 1 P 0 ;0,1,2=240,3=0.000000
L 5.0769 1.97603356 5.07958346 1.97448287 1 P 0 ;0,1,2=240,3=0.000000
L 5.07958346 1.97448287 5.08916683 1.97448287 1 P 0 ;0,1,2=240,3=0.000000
L 5.07958346 1.97448287 5.07383327 1.9595 1 P 0 ;0,1,2=240,3=0.000000
L 5.05778356 1.98533346 5.05548337 1.98843278 1 P 0 ;0,1,2=240,3=0.000000
L 5.05548337 1.98843278 5.0527999 1.98998337 1 P 0 ;0,1,2=240,3=0.000000
L 5.0527999 1.98998337 5.04973317 1.9905 1 P 0 ;0,1,2=240,3=0.000000
L 5.04973317 1.9905 5.0459 1.98946683 1 P 0 ;0,1,2=240,3=0.000000
L 5.0459 1.98946683 5.04321654 1.98688307 1 P 0 ;0,1,2=240,3=0.000000
L 5.04321654 1.98688307 5.04245 1.98378376 1 P 0 ;0,1,2=240,3=0.000000
L 5.04245 1.98378376 5.04283327 1.98068258 1 P 0 ;0,1,2=240,3=0.000000
L 5.04283327 1.98068258 5.04436693 1.9780998 1 P 0 ;0,1,2=240,3=0.000000
L 5.04436693 1.9780998 5.05203337 1.97293327 1 P 0 ;0,1,2=240,3=0.000000
L 5.05203337 1.97293327 5.05548337 1.96931644 1 P 0 ;0,1,2=240,3=0.000000
L 5.05548337 1.96931644 5.05778356 1.96414892 1 P 0 ;0,1,2=240,3=0.000000
L 5.05778356 1.96414892 5.0585501 1.9595 1 P 0 ;0,1,2=240,3=0.000000
L 5.0585501 1.9595 5.04245 1.9595 1 P 0 ;0,1,2=240,3=0.000000
L 5.02678356 1.97241575 5.0241001 1.97603356 1 P 0 ;0,1,2=240,3=0.000000
L 5.0241001 1.97603356 5.0217999 1.9780998 1 P 0 ;0,1,2=240,3=0.000000
L 5.0217999 1.9780998 5.01873317 1.97913287 1 P 0 ;0,1,2=240,3=0.000000
L 5.01873317 1.97913287 5.0160497 1.9780998 1 P 0 ;0,1,2=240,3=0.000000
L 5.0160497 1.9780998 5.01413346 1.97603356 1 P 0 ;0,1,2=240,3=0.000000
L 5.01413346 1.97603356 5.0125998 1.97293327 1 P 0 ;0,1,2=240,3=0.000000
L 5.0125998 1.97293327 5.01221654 1.96931644 1 P 0 ;0,1,2=240,3=0.000000
L 5.01221654 1.96931644 5.0125998 1.96621614 1 P 0 ;0,1,2=240,3=0.000000
L 5.0125998 1.96621614 5.01413346 1.96311585 1 P 0 ;0,1,2=240,3=0.000000
L 5.01413346 1.96311585 5.01643366 1.96053307 1 P 0 ;0,1,2=240,3=0.000000
L 5.01643366 1.96053307 5.01911644 1.9595 1 P 0 ;0,1,2=240,3=0.000000
L 5.01911644 1.9595 5.02218317 1.96053307 1 P 0 ;0,1,2=240,3=0.000000
L 5.02218317 1.96053307 5.02486663 1.96363238 1 P 0 ;0,1,2=240,3=0.000000
L 5.02486663 1.96363238 5.0264003 1.96828327 1 P 0 ;0,1,2=240,3=0.000000
L 5.0264003 1.96828327 5.02678356 1.9734498 1 P 0 ;0,1,2=240,3=0.000000
L 5.02678356 1.9734498 5.02601713 1.98016594 1 P 0 ;0,1,2=240,3=0.000000
L 5.02601713 1.98016594 5.02486663 1.98378376 1 P 0 ;0,1,2=240,3=0.000000
L 5.02486663 1.98378376 5.02295039 1.9873997 1 P 0 ;0,1,2=240,3=0.000000
L 5.02295039 1.9873997 5.02026693 1.98998337 1 P 0 ;0,1,2=240,3=0.000000
L 5.02026693 1.98998337 5.01758346 1.9905 1 P 0 ;0,1,2=240,3=0.000000
L 5.01758346 1.9905 5.0149 1.98946683 1 P 0 ;0,1,2=240,3=0.000000
L 5.0149 1.98946683 5.01298297 1.98688307 1 P 0 ;0,1,2=240,3=0.000000
L 4.99693337 1.96414892 4.99463386 1.96156614 1 P 0 ;0,1,2=240,3=0.000000
L 4.99463386 1.96156614 4.99195039 1.96001654 1 P 0 ;0,1,2=240,3=0.000000
L 4.99195039 1.96001654 4.98850039 1.9595 1 P 0 ;0,1,2=240,3=0.000000
L 4.98850039 1.9595 4.9850497 1.96053307 1 P 0 ;0,1,2=240,3=0.000000
L 4.9850497 1.96053307 4.98236693 1.96259931 1 P 0 ;0,1,2=240,3=0.000000
L 4.98236693 1.96259931 4.98045 1.96621614 1 P 0 ;0,1,2=240,3=0.000000
L 4.98045 1.96621614 4.98006673 1.97034951 1 P 0 ;0,1,2=240,3=0.000000
L 4.98006673 1.97034951 4.98083327 1.97448287 1 P 0 ;0,1,2=240,3=0.000000
L 4.98083327 1.97448287 4.9827502 1.97706663 1 P 0 ;0,1,2=240,3=0.000000
L 4.9827502 1.97706663 4.98543366 1.97913287 1 P 0 ;0,1,2=240,3=0.000000
L 4.98543366 1.97913287 4.98811644 1.97964941 1 P 0 ;0,1,2=240,3=0.000000
L 4.98811644 1.97964941 4.9907999 1.97913287 1 P 0 ;0,1,2=240,3=0.000000
L 4.9907999 1.97913287 4.9942499 1.97706663 1 P 0 ;0,1,2=240,3=0.000000
L 4.9942499 1.97706663 4.9931001 1.9905 1 P 0 ;0,1,2=240,3=0.000000
L 4.9931001 1.9905 4.9827502 1.9905 1 P 0 ;0,1,2=240,3=0.000000
L 4.552 2.485 4.552 2.395 1 P 0 
L 4.552 2.395 4.508 2.395 1 P 0 
L 4.508 2.395 4.508 2.485 1 P 0 
L 4.508 2.485 4.552 2.485 1 P 0 
L 4.5195 2.52083317 4.5505 2.52083317 1 P 0 ;0,1,2=241,3=90.000000
L 4.5505 2.52083317 4.5505 2.53041654 1 P 0 ;0,1,2=241,3=90.000000
L 4.5505 2.53041654 4.54894931 2.53348327 1 P 0 ;0,1,2=241,3=90.000000
L 4.54894931 2.53348327 4.54688307 2.5354002 1 P 0 ;0,1,2=241,3=90.000000
L 4.54688307 2.5354002 4.5427497 2.53616673 1 P 0 ;0,1,2=241,3=90.000000
L 4.5427497 2.53616673 4.53861634 2.5354002 1 P 0 ;0,1,2=241,3=90.000000
L 4.53861634 2.5354002 4.53603356 2.5331 1 P 0 ;0,1,2=241,3=90.000000
L 4.53603356 2.5331 4.53448287 2.53041654 1 P 0 ;0,1,2=241,3=90.000000
L 4.53448287 2.53041654 4.53448287 2.52083317 1 P 0 ;0,1,2=241,3=90.000000
L 4.53448287 2.53041654 4.5195 2.53616673 1 P 0 ;0,1,2=241,3=90.000000
L 4.54533346 2.55221644 4.54843278 2.55451663 1 P 0 ;0,1,2=241,3=90.000000
L 4.54843278 2.55451663 4.54998337 2.5572001 1 P 0 ;0,1,2=241,3=90.000000
L 4.54998337 2.5572001 4.5505 2.56026683 1 P 0 ;0,1,2=241,3=90.000000
L 4.5505 2.56026683 4.54946683 2.5641 1 P 0 ;0,1,2=241,3=90.000000
L 4.54946683 2.5641 4.54688307 2.56678346 1 P 0 ;0,1,2=241,3=90.000000
L 4.54688307 2.56678346 4.54378376 2.56755 1 P 0 ;0,1,2=241,3=90.000000
L 4.54378376 2.56755 4.54068258 2.56716673 1 P 0 ;0,1,2=241,3=90.000000
L 4.54068258 2.56716673 4.5380998 2.56563307 1 P 0 ;0,1,2=241,3=90.000000
L 4.5380998 2.56563307 4.53293327 2.55796663 1 P 0 ;0,1,2=241,3=90.000000
L 4.53293327 2.55796663 4.52931644 2.55451663 1 P 0 ;0,1,2=241,3=90.000000
L 4.52931644 2.55451663 4.52414892 2.55221644 1 P 0 ;0,1,2=241,3=90.000000
L 4.52414892 2.55221644 4.5195 2.5514499 1 P 0 ;0,1,2=241,3=90.000000
L 4.5195 2.5514499 4.5195 2.56755 1 P 0 ;0,1,2=241,3=90.000000
L 4.5195 2.59049961 4.5505 2.59049961 1 P 0 ;0,1,2=241,3=90.000000
L 4.5505 2.59049961 4.5443003 2.5858999 1 P 0 ;0,1,2=241,3=90.000000
L 4.5195 2.5858999 4.5195 2.59509931 1 P 0 ;0,1,2=241,3=90.000000
L 4.52414892 2.61306663 4.52156614 2.61536614 1 P 0 ;0,1,2=241,3=90.000000
L 4.52156614 2.61536614 4.52001654 2.61804961 1 P 0 ;0,1,2=241,3=90.000000
L 4.52001654 2.61804961 4.5195 2.62149961 1 P 0 ;0,1,2=241,3=90.000000
L 4.5195 2.62149961 4.52053307 2.6249503 1 P 0 ;0,1,2=241,3=90.000000
L 4.52053307 2.6249503 4.52259931 2.62763307 1 P 0 ;0,1,2=241,3=90.000000
L 4.52259931 2.62763307 4.52621614 2.62955 1 P 0 ;0,1,2=241,3=90.000000
L 4.52621614 2.62955 4.53034951 2.62993327 1 P 0 ;0,1,2=241,3=90.000000
L 4.53034951 2.62993327 4.53448287 2.62916673 1 P 0 ;0,1,2=241,3=90.000000
L 4.53448287 2.62916673 4.53706663 2.6272498 1 P 0 ;0,1,2=241,3=90.000000
L 4.53706663 2.6272498 4.53913287 2.62456634 1 P 0 ;0,1,2=241,3=90.000000
L 4.53913287 2.62456634 4.53964941 2.62188356 1 P 0 ;0,1,2=241,3=90.000000
L 4.53964941 2.62188356 4.53913287 2.6192001 1 P 0 ;0,1,2=241,3=90.000000
L 4.53913287 2.6192001 4.53706663 2.6157501 1 P 0 ;0,1,2=241,3=90.000000
L 4.53706663 2.6157501 4.5505 2.6168999 1 P 0 ;0,1,2=241,3=90.000000
L 4.5505 2.6168999 4.5505 2.6272498 1 P 0 ;0,1,2=241,3=90.000000
L 4.463 2.395 4.463 2.485 1 P 0 
L 4.463 2.485 4.507 2.485 1 P 0 
L 4.507 2.485 4.507 2.395 1 P 0 
L 4.507 2.395 4.463 2.395 1 P 0 
L 4.4745 2.52083317 4.5055 2.52083317 1 P 0 ;0,1,2=242,3=90.000000
L 4.5055 2.52083317 4.5055 2.53041654 1 P 0 ;0,1,2=242,3=90.000000
L 4.5055 2.53041654 4.50394931 2.53348327 1 P 0 ;0,1,2=242,3=90.000000
L 4.50394931 2.53348327 4.50188307 2.5354002 1 P 0 ;0,1,2=242,3=90.000000
L 4.50188307 2.5354002 4.4977497 2.53616673 1 P 0 ;0,1,2=242,3=90.000000
L 4.4977497 2.53616673 4.49361634 2.5354002 1 P 0 ;0,1,2=242,3=90.000000
L 4.49361634 2.5354002 4.49103356 2.5331 1 P 0 ;0,1,2=242,3=90.000000
L 4.49103356 2.5331 4.48948287 2.53041654 1 P 0 ;0,1,2=242,3=90.000000
L 4.48948287 2.53041654 4.48948287 2.52083317 1 P 0 ;0,1,2=242,3=90.000000
L 4.48948287 2.53041654 4.4745 2.53616673 1 P 0 ;0,1,2=242,3=90.000000
L 4.50033346 2.55221644 4.50343278 2.55451663 1 P 0 ;0,1,2=242,3=90.000000
L 4.50343278 2.55451663 4.50498337 2.5572001 1 P 0 ;0,1,2=242,3=90.000000
L 4.50498337 2.5572001 4.5055 2.56026683 1 P 0 ;0,1,2=242,3=90.000000
L 4.5055 2.56026683 4.50446683 2.5641 1 P 0 ;0,1,2=242,3=90.000000
L 4.50446683 2.5641 4.50188307 2.56678346 1 P 0 ;0,1,2=242,3=90.000000
L 4.50188307 2.56678346 4.49878376 2.56755 1 P 0 ;0,1,2=242,3=90.000000
L 4.49878376 2.56755 4.49568258 2.56716673 1 P 0 ;0,1,2=242,3=90.000000
L 4.49568258 2.56716673 4.4930998 2.56563307 1 P 0 ;0,1,2=242,3=90.000000
L 4.4930998 2.56563307 4.48793327 2.55796663 1 P 0 ;0,1,2=242,3=90.000000
L 4.48793327 2.55796663 4.48431644 2.55451663 1 P 0 ;0,1,2=242,3=90.000000
L 4.48431644 2.55451663 4.47914892 2.55221644 1 P 0 ;0,1,2=242,3=90.000000
L 4.47914892 2.55221644 4.4745 2.5514499 1 P 0 ;0,1,2=242,3=90.000000
L 4.4745 2.5514499 4.4745 2.56755 1 P 0 ;0,1,2=242,3=90.000000
L 4.4745 2.59049961 4.5055 2.59049961 1 P 0 ;0,1,2=242,3=90.000000
L 4.5055 2.59049961 4.4993003 2.5858999 1 P 0 ;0,1,2=242,3=90.000000
L 4.4745 2.5858999 4.4745 2.59509931 1 P 0 ;0,1,2=242,3=90.000000
L 4.48741575 2.61421644 4.49103356 2.6168999 1 P 0 ;0,1,2=242,3=90.000000
L 4.49103356 2.6168999 4.4930998 2.6192001 1 P 0 ;0,1,2=242,3=90.000000
L 4.4930998 2.6192001 4.49413287 2.62226683 1 P 0 ;0,1,2=242,3=90.000000
L 4.49413287 2.62226683 4.4930998 2.6249503 1 P 0 ;0,1,2=242,3=90.000000
L 4.4930998 2.6249503 4.49103356 2.62686654 1 P 0 ;0,1,2=242,3=90.000000
L 4.49103356 2.62686654 4.48793327 2.6284002 1 P 0 ;0,1,2=242,3=90.000000
L 4.48793327 2.6284002 4.48431644 2.62878346 1 P 0 ;0,1,2=242,3=90.000000
L 4.48431644 2.62878346 4.48121614 2.6284002 1 P 0 ;0,1,2=242,3=90.000000
L 4.48121614 2.6284002 4.47811585 2.62686654 1 P 0 ;0,1,2=242,3=90.000000
L 4.47811585 2.62686654 4.47553307 2.62456634 1 P 0 ;0,1,2=242,3=90.000000
L 4.47553307 2.62456634 4.4745 2.62188356 1 P 0 ;0,1,2=242,3=90.000000
L 4.4745 2.62188356 4.47553307 2.61881683 1 P 0 ;0,1,2=242,3=90.000000
L 4.47553307 2.61881683 4.47863238 2.61613337 1 P 0 ;0,1,2=242,3=90.000000
L 4.47863238 2.61613337 4.48328327 2.6145997 1 P 0 ;0,1,2=242,3=90.000000
L 4.48328327 2.6145997 4.4884498 2.61421644 1 P 0 ;0,1,2=242,3=90.000000
L 4.4884498 2.61421644 4.49516594 2.61498287 1 P 0 ;0,1,2=242,3=90.000000
L 4.49516594 2.61498287 4.49878376 2.61613337 1 P 0 ;0,1,2=242,3=90.000000
L 4.49878376 2.61613337 4.5023997 2.61804961 1 P 0 ;0,1,2=242,3=90.000000
L 4.5023997 2.61804961 4.50498337 2.62073307 1 P 0 ;0,1,2=242,3=90.000000
L 4.50498337 2.62073307 4.5055 2.62341654 1 P 0 ;0,1,2=242,3=90.000000
L 4.5055 2.62341654 4.50446683 2.6261 1 P 0 ;0,1,2=242,3=90.000000
L 4.50446683 2.6261 4.50188307 2.62801703 1 P 0 ;0,1,2=242,3=90.000000
L 2.8625 1.967 2.8625 1.923 1 P 0 
L 2.7725 1.967 2.8625 1.967 1 P 0 
L 2.8625 1.923 2.7725 1.923 1 P 0 
L 2.7725 1.923 2.7725 1.967 1 P 0 
L 2.76366683 1.9295 2.76366683 1.9605 1 P 0 ;0,1,2=243,3=0.000000
L 2.76366683 1.9605 2.75408346 1.9605 1 P 0 ;0,1,2=243,3=0.000000
L 2.75408346 1.9605 2.75101673 1.95894931 1 P 0 ;0,1,2=243,3=0.000000
L 2.75101673 1.95894931 2.7490998 1.95688307 1 P 0 ;0,1,2=243,3=0.000000
L 2.7490998 1.95688307 2.74833327 1.9527497 1 P 0 ;0,1,2=243,3=0.000000
L 2.74833327 1.9527497 2.7490998 1.94861634 1 P 0 ;0,1,2=243,3=0.000000
L 2.7490998 1.94861634 2.7514 1.94603356 1 P 0 ;0,1,2=243,3=0.000000
L 2.7514 1.94603356 2.75408346 1.94448287 1 P 0 ;0,1,2=243,3=0.000000
L 2.75408346 1.94448287 2.76366683 1.94448287 1 P 0 ;0,1,2=243,3=0.000000
L 2.75408346 1.94448287 2.74833327 1.9295 1 P 0 ;0,1,2=243,3=0.000000
L 2.72500039 1.9295 2.72231693 1.93001654 1 P 0 ;0,1,2=243,3=0.000000
L 2.72231693 1.93001654 2.7192502 1.93156614 1 P 0 ;0,1,2=243,3=0.000000
L 2.7192502 1.93156614 2.71733327 1.93414892 1 P 0 ;0,1,2=243,3=0.000000
L 2.71733327 1.93414892 2.71656673 1.93776673 1 P 0 ;0,1,2=243,3=0.000000
L 2.71656673 1.93776673 2.71733327 1.94138268 1 P 0 ;0,1,2=243,3=0.000000
L 2.71733327 1.94138268 2.71963346 1.94448287 1 P 0 ;0,1,2=243,3=0.000000
L 2.71963346 1.94448287 2.72308346 1.94603356 1 P 0 ;0,1,2=243,3=0.000000
L 2.72308346 1.94603356 2.72691663 1.94603356 1 P 0 ;0,1,2=243,3=0.000000
L 2.72691663 1.94603356 2.72921683 1.94706663 1 P 0 ;0,1,2=243,3=0.000000
L 2.72921683 1.94706663 2.73113386 1.94964941 1 P 0 ;0,1,2=243,3=0.000000
L 2.73113386 1.94964941 2.7319003 1.95326624 1 P 0 ;0,1,2=243,3=0.000000
L 2.7319003 1.95326624 2.7307499 1.95688307 1 P 0 ;0,1,2=243,3=0.000000
L 2.7307499 1.95688307 2.72806713 1.95946683 1 P 0 ;0,1,2=243,3=0.000000
L 2.72806713 1.95946683 2.72500039 1.9605 1 P 0 ;0,1,2=243,3=0.000000
L 2.72500039 1.9605 2.72193366 1.95946683 1 P 0 ;0,1,2=243,3=0.000000
L 2.72193366 1.95946683 2.7192502 1.95688307 1 P 0 ;0,1,2=243,3=0.000000
L 2.7192502 1.95688307 2.7180998 1.95326624 1 P 0 ;0,1,2=243,3=0.000000
L 2.7180998 1.95326624 2.71886693 1.94964941 1 P 0 ;0,1,2=243,3=0.000000
L 2.71886693 1.94964941 2.72078327 1.94706663 1 P 0 ;0,1,2=243,3=0.000000
L 2.72078327 1.94706663 2.72308346 1.94603356 1 P 0 ;0,1,2=243,3=0.000000
L 2.72308346 1.94603356 2.72691663 1.94603356 1 P 0 ;0,1,2=243,3=0.000000
L 2.72691663 1.94603356 2.73036663 1.94448287 1 P 0 ;0,1,2=243,3=0.000000
L 2.73036663 1.94448287 2.73266683 1.94138268 1 P 0 ;0,1,2=243,3=0.000000
L 2.73266683 1.94138268 2.73343337 1.93776673 1 P 0 ;0,1,2=243,3=0.000000
L 2.73343337 1.93776673 2.73266683 1.93414892 1 P 0 ;0,1,2=243,3=0.000000
L 2.73266683 1.93414892 2.7307499 1.93156614 1 P 0 ;0,1,2=243,3=0.000000
L 2.7307499 1.93156614 2.72768317 1.93001654 1 P 0 ;0,1,2=243,3=0.000000
L 2.72768317 1.93001654 2.72500039 1.9295 1 P 0 ;0,1,2=243,3=0.000000
L 2.70051713 1.93311585 2.69783366 1.93053307 1 P 0 ;0,1,2=243,3=0.000000
L 2.69783366 1.93053307 2.69476693 1.9295 1 P 0 ;0,1,2=243,3=0.000000
L 2.69476693 1.9295 2.6917002 1.93053307 1 P 0 ;0,1,2=243,3=0.000000
L 2.6917002 1.93053307 2.68901673 1.93363238 1 P 0 ;0,1,2=243,3=0.000000
L 2.68901673 1.93363238 2.6870998 1.93828327 1 P 0 ;0,1,2=243,3=0.000000
L 2.6870998 1.93828327 2.68633327 1.94293327 1 P 0 ;0,1,2=243,3=0.000000
L 2.68633327 1.94293327 2.68633327 1.94861634 1 P 0 ;0,1,2=243,3=0.000000
L 2.68633327 1.94861634 2.6870998 1.95326624 1 P 0 ;0,1,2=243,3=0.000000
L 2.6870998 1.95326624 2.68901673 1.9573997 1 P 0 ;0,1,2=243,3=0.000000
L 2.68901673 1.9573997 2.69131693 1.95946683 1 P 0 ;0,1,2=243,3=0.000000
L 2.69131693 1.95946683 2.69400039 1.9605 1 P 0 ;0,1,2=243,3=0.000000
L 2.69400039 1.9605 2.69706713 1.95946683 1 P 0 ;0,1,2=243,3=0.000000
L 2.69706713 1.95946683 2.69936663 1.9573997 1 P 0 ;0,1,2=243,3=0.000000
L 2.69936663 1.9573997 2.7009003 1.9543003 1 P 0 ;0,1,2=243,3=0.000000
L 2.7009003 1.9543003 2.70166683 1.95016594 1 P 0 ;0,1,2=243,3=0.000000
L 2.70166683 1.95016594 2.7009003 1.9465501 1 P 0 ;0,1,2=243,3=0.000000
L 2.7009003 1.9465501 2.69898337 1.94293327 1 P 0 ;0,1,2=243,3=0.000000
L 2.69898337 1.94293327 2.69668317 1.94086604 1 P 0 ;0,1,2=243,3=0.000000
L 2.69668317 1.94086604 2.69400039 1.94034951 1 P 0 ;0,1,2=243,3=0.000000
L 2.69400039 1.94034951 2.69093366 1.94138268 1 P 0 ;0,1,2=243,3=0.000000
L 2.69093366 1.94138268 2.68863346 1.94396634 1 P 0 ;0,1,2=243,3=0.000000
L 2.68863346 1.94396634 2.68633327 1.94861634 1 P 0 ;0,1,2=243,3=0.000000
L 3.485 2.232 3.485 2.188 1 P 0 
L 3.485 2.188 3.395 2.188 1 P 0 
L 3.395 2.188 3.395 2.232 1 P 0 
L 3.395 2.232 3.485 2.232 1 P 0 
L 3.54866683 2.0745 3.54866683 2.1055 1 P 0 ;0,1,2=244,3=0.000000
L 3.54866683 2.1055 3.53908346 2.1055 1 P 0 ;0,1,2=244,3=0.000000
L 3.53908346 2.1055 3.53601673 2.10394931 1 P 0 ;0,1,2=244,3=0.000000
L 3.53601673 2.10394931 3.5340998 2.10188307 1 P 0 ;0,1,2=244,3=0.000000
L 3.5340998 2.10188307 3.53333327 2.0977497 1 P 0 ;0,1,2=244,3=0.000000
L 3.53333327 2.0977497 3.5340998 2.09361634 1 P 0 ;0,1,2=244,3=0.000000
L 3.5340998 2.09361634 3.5364 2.09103356 1 P 0 ;0,1,2=244,3=0.000000
L 3.5364 2.09103356 3.53908346 2.08948287 1 P 0 ;0,1,2=244,3=0.000000
L 3.53908346 2.08948287 3.54866683 2.08948287 1 P 0 ;0,1,2=244,3=0.000000
L 3.53908346 2.08948287 3.53333327 2.0745 1 P 0 ;0,1,2=244,3=0.000000
L 3.51076693 2.0745 3.51000039 2.08121614 1 P 0 ;0,1,2=244,3=0.000000
L 3.51000039 2.08121614 3.5088499 2.08689921 1 P 0 ;0,1,2=244,3=0.000000
L 3.5088499 2.08689921 3.50731693 2.09206663 1 P 0 ;0,1,2=244,3=0.000000
L 3.50731693 2.09206663 3.5054 2.0977497 1 P 0 ;0,1,2=244,3=0.000000
L 3.5054 2.0977497 3.50233327 2.1055 1 P 0 ;0,1,2=244,3=0.000000
L 3.50233327 2.1055 3.51766683 2.1055 1 P 0 ;0,1,2=244,3=0.000000
L 3.48628356 2.08741575 3.4836001 2.09103356 1 P 0 ;0,1,2=244,3=0.000000
L 3.4836001 2.09103356 3.4812999 2.0930998 1 P 0 ;0,1,2=244,3=0.000000
L 3.4812999 2.0930998 3.47823317 2.09413287 1 P 0 ;0,1,2=244,3=0.000000
L 3.47823317 2.09413287 3.4755497 2.0930998 1 P 0 ;0,1,2=244,3=0.000000
L 3.4755497 2.0930998 3.47363346 2.09103356 1 P 0 ;0,1,2=244,3=0.000000
L 3.47363346 2.09103356 3.4720998 2.08793327 1 P 0 ;0,1,2=244,3=0.000000
L 3.4720998 2.08793327 3.47171654 2.08431644 1 P 0 ;0,1,2=244,3=0.000000
L 3.47171654 2.08431644 3.4720998 2.08121614 1 P 0 ;0,1,2=244,3=0.000000
L 3.4720998 2.08121614 3.47363346 2.07811585 1 P 0 ;0,1,2=244,3=0.000000
L 3.47363346 2.07811585 3.47593366 2.07553307 1 P 0 ;0,1,2=244,3=0.000000
L 3.47593366 2.07553307 3.47861644 2.0745 1 P 0 ;0,1,2=244,3=0.000000
L 3.47861644 2.0745 3.48168317 2.07553307 1 P 0 ;0,1,2=244,3=0.000000
L 3.48168317 2.07553307 3.48436663 2.07863238 1 P 0 ;0,1,2=244,3=0.000000
L 3.48436663 2.07863238 3.4859003 2.08328327 1 P 0 ;0,1,2=244,3=0.000000
L 3.4859003 2.08328327 3.48628356 2.0884498 1 P 0 ;0,1,2=244,3=0.000000
L 3.48628356 2.0884498 3.48551713 2.09516594 1 P 0 ;0,1,2=244,3=0.000000
L 3.48551713 2.09516594 3.48436663 2.09878376 1 P 0 ;0,1,2=244,3=0.000000
L 3.48436663 2.09878376 3.48245039 2.1023997 1 P 0 ;0,1,2=244,3=0.000000
L 3.48245039 2.1023997 3.47976693 2.10498337 1 P 0 ;0,1,2=244,3=0.000000
L 3.47976693 2.10498337 3.47708346 2.1055 1 P 0 ;0,1,2=244,3=0.000000
L 3.47708346 2.1055 3.4744 2.10446683 1 P 0 ;0,1,2=244,3=0.000000
L 3.4744 2.10446683 3.47248297 2.10188307 1 P 0 ;0,1,2=244,3=0.000000
L 3.305 2.232 3.395 2.232 1 P 0 
L 3.395 2.232 3.395 2.188 1 P 0 
L 3.395 2.188 3.305 2.188 1 P 0 
L 3.305 2.188 3.305 2.232 1 P 0 
L 3.30866683 2.1495 3.30866683 2.1805 1 P 0 ;0,1,2=245,3=0.000000
L 3.30866683 2.1805 3.29908346 2.1805 1 P 0 ;0,1,2=245,3=0.000000
L 3.29908346 2.1805 3.29601673 2.17894931 1 P 0 ;0,1,2=245,3=0.000000
L 3.29601673 2.17894931 3.2940998 2.17688307 1 P 0 ;0,1,2=245,3=0.000000
L 3.2940998 2.17688307 3.29333327 2.1727497 1 P 0 ;0,1,2=245,3=0.000000
L 3.29333327 2.1727497 3.2940998 2.16861634 1 P 0 ;0,1,2=245,3=0.000000
L 3.2940998 2.16861634 3.2964 2.16603356 1 P 0 ;0,1,2=245,3=0.000000
L 3.2964 2.16603356 3.29908346 2.16448287 1 P 0 ;0,1,2=245,3=0.000000
L 3.29908346 2.16448287 3.30866683 2.16448287 1 P 0 ;0,1,2=245,3=0.000000
L 3.29908346 2.16448287 3.29333327 2.1495 1 P 0 ;0,1,2=245,3=0.000000
L 3.27076693 2.1495 3.27000039 2.15621614 1 P 0 ;0,1,2=245,3=0.000000
L 3.27000039 2.15621614 3.2688499 2.16189921 1 P 0 ;0,1,2=245,3=0.000000
L 3.2688499 2.16189921 3.26731693 2.16706663 1 P 0 ;0,1,2=245,3=0.000000
L 3.26731693 2.16706663 3.2654 2.1727497 1 P 0 ;0,1,2=245,3=0.000000
L 3.2654 2.1727497 3.26233327 2.1805 1 P 0 ;0,1,2=245,3=0.000000
L 3.26233327 2.1805 3.27766683 2.1805 1 P 0 ;0,1,2=245,3=0.000000
L 3.23976693 2.1495 3.23900039 2.15621614 1 P 0 ;0,1,2=245,3=0.000000
L 3.23900039 2.15621614 3.2378499 2.16189921 1 P 0 ;0,1,2=245,3=0.000000
L 3.2378499 2.16189921 3.23631693 2.16706663 1 P 0 ;0,1,2=245,3=0.000000
L 3.23631693 2.16706663 3.2344 2.1727497 1 P 0 ;0,1,2=245,3=0.000000
L 3.2344 2.1727497 3.23133327 2.1805 1 P 0 ;0,1,2=245,3=0.000000
L 3.23133327 2.1805 3.24666683 2.1805 1 P 0 ;0,1,2=245,3=0.000000
L 3.395 2.233 3.305 2.233 1 P 0 
L 3.305 2.233 3.305 2.277 1 P 0 
L 3.305 2.277 3.395 2.277 1 P 0 
L 3.395 2.277 3.395 2.233 1 P 0 
L 3.37866683 2.2845 3.37866683 2.3155 1 P 0 ;0,1,2=246,3=0.000000
L 3.37866683 2.3155 3.36908346 2.3155 1 P 0 ;0,1,2=246,3=0.000000
L 3.36908346 2.3155 3.36601673 2.31394931 1 P 0 ;0,1,2=246,3=0.000000
L 3.36601673 2.31394931 3.3640998 2.31188307 1 P 0 ;0,1,2=246,3=0.000000
L 3.3640998 2.31188307 3.36333327 2.3077497 1 P 0 ;0,1,2=246,3=0.000000
L 3.36333327 2.3077497 3.3640998 2.30361634 1 P 0 ;0,1,2=246,3=0.000000
L 3.3640998 2.30361634 3.3664 2.30103356 1 P 0 ;0,1,2=246,3=0.000000
L 3.3664 2.30103356 3.36908346 2.29948287 1 P 0 ;0,1,2=246,3=0.000000
L 3.36908346 2.29948287 3.37866683 2.29948287 1 P 0 ;0,1,2=246,3=0.000000
L 3.36908346 2.29948287 3.36333327 2.2845 1 P 0 ;0,1,2=246,3=0.000000
L 3.34076693 2.2845 3.34000039 2.29121614 1 P 0 ;0,1,2=246,3=0.000000
L 3.34000039 2.29121614 3.3388499 2.29689921 1 P 0 ;0,1,2=246,3=0.000000
L 3.3388499 2.29689921 3.33731693 2.30206663 1 P 0 ;0,1,2=246,3=0.000000
L 3.33731693 2.30206663 3.3354 2.3077497 1 P 0 ;0,1,2=246,3=0.000000
L 3.3354 2.3077497 3.33233327 2.3155 1 P 0 ;0,1,2=246,3=0.000000
L 3.33233327 2.3155 3.34766683 2.3155 1 P 0 ;0,1,2=246,3=0.000000
L 3.31743337 2.28914892 3.31513386 2.28656614 1 P 0 ;0,1,2=246,3=0.000000
L 3.31513386 2.28656614 3.31245039 2.28501654 1 P 0 ;0,1,2=246,3=0.000000
L 3.31245039 2.28501654 3.30900039 2.2845 1 P 0 ;0,1,2=246,3=0.000000
L 3.30900039 2.2845 3.3055497 2.28553307 1 P 0 ;0,1,2=246,3=0.000000
L 3.3055497 2.28553307 3.30286693 2.28759931 1 P 0 ;0,1,2=246,3=0.000000
L 3.30286693 2.28759931 3.30095 2.29121614 1 P 0 ;0,1,2=246,3=0.000000
L 3.30095 2.29121614 3.30056673 2.29534951 1 P 0 ;0,1,2=246,3=0.000000
L 3.30056673 2.29534951 3.30133327 2.29948287 1 P 0 ;0,1,2=246,3=0.000000
L 3.30133327 2.29948287 3.3032502 2.30206663 1 P 0 ;0,1,2=246,3=0.000000
L 3.3032502 2.30206663 3.30593366 2.30413287 1 P 0 ;0,1,2=246,3=0.000000
L 3.30593366 2.30413287 3.30861644 2.30464941 1 P 0 ;0,1,2=246,3=0.000000
L 3.30861644 2.30464941 3.3112999 2.30413287 1 P 0 ;0,1,2=246,3=0.000000
L 3.3112999 2.30413287 3.3147499 2.30206663 1 P 0 ;0,1,2=246,3=0.000000
L 3.3147499 2.30206663 3.3136001 2.3155 1 P 0 ;0,1,2=246,3=0.000000
L 3.3136001 2.3155 3.3032502 2.3155 1 P 0 ;0,1,2=246,3=0.000000
L 3.485 2.277 3.485 2.233 1 P 0 
L 3.395 2.277 3.485 2.277 1 P 0 
L 3.485 2.233 3.395 2.233 1 P 0 
L 3.395 2.233 3.395 2.277 1 P 0 
L 3.54866683 2.1195 3.54866683 2.1505 1 P 0 ;0,1,2=247,3=0.000000
L 3.54866683 2.1505 3.53908346 2.1505 1 P 0 ;0,1,2=247,3=0.000000
L 3.53908346 2.1505 3.53601673 2.14894931 1 P 0 ;0,1,2=247,3=0.000000
L 3.53601673 2.14894931 3.5340998 2.14688307 1 P 0 ;0,1,2=247,3=0.000000
L 3.5340998 2.14688307 3.53333327 2.1427497 1 P 0 ;0,1,2=247,3=0.000000
L 3.53333327 2.1427497 3.5340998 2.13861634 1 P 0 ;0,1,2=247,3=0.000000
L 3.5340998 2.13861634 3.5364 2.13603356 1 P 0 ;0,1,2=247,3=0.000000
L 3.5364 2.13603356 3.53908346 2.13448287 1 P 0 ;0,1,2=247,3=0.000000
L 3.53908346 2.13448287 3.54866683 2.13448287 1 P 0 ;0,1,2=247,3=0.000000
L 3.53908346 2.13448287 3.53333327 2.1195 1 P 0 ;0,1,2=247,3=0.000000
L 3.51076693 2.1195 3.51000039 2.12621614 1 P 0 ;0,1,2=247,3=0.000000
L 3.51000039 2.12621614 3.5088499 2.13189921 1 P 0 ;0,1,2=247,3=0.000000
L 3.5088499 2.13189921 3.50731693 2.13706663 1 P 0 ;0,1,2=247,3=0.000000
L 3.50731693 2.13706663 3.5054 2.1427497 1 P 0 ;0,1,2=247,3=0.000000
L 3.5054 2.1427497 3.50233327 2.1505 1 P 0 ;0,1,2=247,3=0.000000
L 3.50233327 2.1505 3.51766683 2.1505 1 P 0 ;0,1,2=247,3=0.000000
L 3.4744 2.1195 3.4744 2.1505 1 P 0 ;0,1,2=247,3=0.000000
L 3.4744 2.1505 3.48858376 2.12828327 1 P 0 ;0,1,2=247,3=0.000000
L 3.48858376 2.12828327 3.46941634 2.12828327 1 P 0 ;0,1,2=247,3=0.000000
L 3.509 1.95348996 3.599 1.95348996 1 P 0 
L 3.599 1.95348996 3.599 1.90948996 1 P 0 
L 3.599 1.90948996 3.509 1.90948996 1 P 0 
L 3.509 1.90948996 3.509 1.95348996 1 P 0 
L 3.63816683 2.016 3.63816683 2.047 1 P 0 ;0,1,2=248,3=0.000000
L 3.63816683 2.047 3.62858346 2.047 1 P 0 ;0,1,2=248,3=0.000000
L 3.62858346 2.047 3.62551673 2.04544931 1 P 0 ;0,1,2=248,3=0.000000
L 3.62551673 2.04544931 3.6235998 2.04338307 1 P 0 ;0,1,2=248,3=0.000000
L 3.6235998 2.04338307 3.62283327 2.0392497 1 P 0 ;0,1,2=248,3=0.000000
L 3.62283327 2.0392497 3.6235998 2.03511634 1 P 0 ;0,1,2=248,3=0.000000
L 3.6235998 2.03511634 3.6259 2.03253356 1 P 0 ;0,1,2=248,3=0.000000
L 3.6259 2.03253356 3.62858346 2.03098287 1 P 0 ;0,1,2=248,3=0.000000
L 3.62858346 2.03098287 3.63816683 2.03098287 1 P 0 ;0,1,2=248,3=0.000000
L 3.62858346 2.03098287 3.62283327 2.016 1 P 0 ;0,1,2=248,3=0.000000
L 3.59950039 2.016 3.59950039 2.047 1 P 0 ;0,1,2=248,3=0.000000
L 3.59950039 2.047 3.6041001 2.0408003 1 P 0 ;0,1,2=248,3=0.000000
L 3.6041001 2.016 3.59490069 2.016 1 P 0 ;0,1,2=248,3=0.000000
L 3.56850039 2.047 3.57156713 2.04596683 1 P 0 ;0,1,2=248,3=0.000000
L 3.57156713 2.04596683 3.57386663 2.04338307 1 P 0 ;0,1,2=248,3=0.000000
L 3.57386663 2.04338307 3.5754003 2.04028376 1 P 0 ;0,1,2=248,3=0.000000
L 3.5754003 2.04028376 3.5765501 2.03614941 1 P 0 ;0,1,2=248,3=0.000000
L 3.5765501 2.03614941 3.57693337 2.03149951 1 P 0 ;0,1,2=248,3=0.000000
L 3.57693337 2.03149951 3.5765501 2.02684951 1 P 0 ;0,1,2=248,3=0.000000
L 3.5765501 2.02684951 3.5754003 2.02271614 1 P 0 ;0,1,2=248,3=0.000000
L 3.5754003 2.02271614 3.57386663 2.01961585 1 P 0 ;0,1,2=248,3=0.000000
L 3.57386663 2.01961585 3.57156713 2.01703307 1 P 0 ;0,1,2=248,3=0.000000
L 3.57156713 2.01703307 3.56850039 2.016 1 P 0 ;0,1,2=248,3=0.000000
L 3.56850039 2.016 3.56543366 2.01703307 1 P 0 ;0,1,2=248,3=0.000000
L 3.56543366 2.01703307 3.56313346 2.01961585 1 P 0 ;0,1,2=248,3=0.000000
L 3.56313346 2.01961585 3.5615998 2.02271614 1 P 0 ;0,1,2=248,3=0.000000
L 3.5615998 2.02271614 3.56045 2.02684951 1 P 0 ;0,1,2=248,3=0.000000
L 3.56045 2.02684951 3.56006673 2.03149951 1 P 0 ;0,1,2=248,3=0.000000
L 3.56006673 2.03149951 3.56045 2.03614941 1 P 0 ;0,1,2=248,3=0.000000
L 3.56045 2.03614941 3.5615998 2.04028376 1 P 0 ;0,1,2=248,3=0.000000
L 3.5615998 2.04028376 3.56313346 2.04338307 1 P 0 ;0,1,2=248,3=0.000000
L 3.56313346 2.04338307 3.56543366 2.04596683 1 P 0 ;0,1,2=248,3=0.000000
L 3.56543366 2.04596683 3.56850039 2.047 1 P 0 ;0,1,2=248,3=0.000000
L 3.54593337 2.02064892 3.54363386 2.01806614 1 P 0 ;0,1,2=248,3=0.000000
L 3.54363386 2.01806614 3.54095039 2.01651654 1 P 0 ;0,1,2=248,3=0.000000
L 3.54095039 2.01651654 3.53750039 2.016 1 P 0 ;0,1,2=248,3=0.000000
L 3.53750039 2.016 3.5340497 2.01703307 1 P 0 ;0,1,2=248,3=0.000000
L 3.5340497 2.01703307 3.53136693 2.01909931 1 P 0 ;0,1,2=248,3=0.000000
L 3.53136693 2.01909931 3.52945 2.02271614 1 P 0 ;0,1,2=248,3=0.000000
L 3.52945 2.02271614 3.52906673 2.02684951 1 P 0 ;0,1,2=248,3=0.000000
L 3.52906673 2.02684951 3.52983327 2.03098287 1 P 0 ;0,1,2=248,3=0.000000
L 3.52983327 2.03098287 3.5317502 2.03356663 1 P 0 ;0,1,2=248,3=0.000000
L 3.5317502 2.03356663 3.53443366 2.03563287 1 P 0 ;0,1,2=248,3=0.000000
L 3.53443366 2.03563287 3.53711644 2.03614941 1 P 0 ;0,1,2=248,3=0.000000
L 3.53711644 2.03614941 3.5397999 2.03563287 1 P 0 ;0,1,2=248,3=0.000000
L 3.5397999 2.03563287 3.5432499 2.03356663 1 P 0 ;0,1,2=248,3=0.000000
L 3.5432499 2.03356663 3.5421001 2.047 1 P 0 ;0,1,2=248,3=0.000000
L 3.5421001 2.047 3.5317502 2.047 1 P 0 ;0,1,2=248,3=0.000000
L 2.888 2.365 2.932 2.365 1 P 0 
L 2.932 2.365 2.932 2.275 1 P 0 
L 2.932 2.275 2.888 2.275 1 P 0 
L 2.888 2.275 2.888 2.365 1 P 0 
L 3.1645 2.38133317 3.1955 2.38133317 1 P 0 ;0,1,2=249,3=90.000000
L 3.1955 2.38133317 3.1955 2.39091654 1 P 0 ;0,1,2=249,3=90.000000
L 3.1955 2.39091654 3.19394931 2.39398327 1 P 0 ;0,1,2=249,3=90.000000
L 3.19394931 2.39398327 3.19188307 2.3959002 1 P 0 ;0,1,2=249,3=90.000000
L 3.19188307 2.3959002 3.1877497 2.39666673 1 P 0 ;0,1,2=249,3=90.000000
L 3.1877497 2.39666673 3.18361634 2.3959002 1 P 0 ;0,1,2=249,3=90.000000
L 3.18361634 2.3959002 3.18103356 2.3936 1 P 0 ;0,1,2=249,3=90.000000
L 3.18103356 2.3936 3.17948287 2.39091654 1 P 0 ;0,1,2=249,3=90.000000
L 3.17948287 2.39091654 3.17948287 2.38133317 1 P 0 ;0,1,2=249,3=90.000000
L 3.17948287 2.39091654 3.1645 2.39666673 1 P 0 ;0,1,2=249,3=90.000000
L 3.1645 2.4246 3.1955 2.4246 1 P 0 ;0,1,2=249,3=90.000000
L 3.1955 2.4246 3.17328327 2.41041624 1 P 0 ;0,1,2=249,3=90.000000
L 3.17328327 2.41041624 3.17328327 2.42958366 1 P 0 ;0,1,2=249,3=90.000000
L 3.1645 2.4556 3.1955 2.4556 1 P 0 ;0,1,2=249,3=90.000000
L 3.1955 2.4556 3.17328327 2.44141624 1 P 0 ;0,1,2=249,3=90.000000
L 3.17328327 2.44141624 3.17328327 2.46058366 1 P 0 ;0,1,2=249,3=90.000000
L 2.665 2.397 2.665 2.353 1 P 0 
L 2.665 2.353 2.575 2.353 1 P 0 
L 2.575 2.353 2.575 2.397 1 P 0 
L 2.575 2.397 2.665 2.397 1 P 0 
L 2.62916683 2.4045 2.62916683 2.4355 1 P 0 ;0,1,2=250,3=0.000000
L 2.62916683 2.4355 2.61958346 2.4355 1 P 0 ;0,1,2=250,3=0.000000
L 2.61958346 2.4355 2.61651673 2.43394931 1 P 0 ;0,1,2=250,3=0.000000
L 2.61651673 2.43394931 2.6145998 2.43188307 1 P 0 ;0,1,2=250,3=0.000000
L 2.6145998 2.43188307 2.61383327 2.4277497 1 P 0 ;0,1,2=250,3=0.000000
L 2.61383327 2.4277497 2.6145998 2.42361634 1 P 0 ;0,1,2=250,3=0.000000
L 2.6145998 2.42361634 2.6169 2.42103356 1 P 0 ;0,1,2=250,3=0.000000
L 2.6169 2.42103356 2.61958346 2.41948287 1 P 0 ;0,1,2=250,3=0.000000
L 2.61958346 2.41948287 2.62916683 2.41948287 1 P 0 ;0,1,2=250,3=0.000000
L 2.61958346 2.41948287 2.61383327 2.4045 1 P 0 ;0,1,2=250,3=0.000000
L 2.59778356 2.43033346 2.59548337 2.43343278 1 P 0 ;0,1,2=250,3=0.000000
L 2.59548337 2.43343278 2.5927999 2.43498337 1 P 0 ;0,1,2=250,3=0.000000
L 2.5927999 2.43498337 2.58973317 2.4355 1 P 0 ;0,1,2=250,3=0.000000
L 2.58973317 2.4355 2.5859 2.43446683 1 P 0 ;0,1,2=250,3=0.000000
L 2.5859 2.43446683 2.58321654 2.43188307 1 P 0 ;0,1,2=250,3=0.000000
L 2.58321654 2.43188307 2.58245 2.42878376 1 P 0 ;0,1,2=250,3=0.000000
L 2.58245 2.42878376 2.58283327 2.42568258 1 P 0 ;0,1,2=250,3=0.000000
L 2.58283327 2.42568258 2.58436693 2.4230998 1 P 0 ;0,1,2=250,3=0.000000
L 2.58436693 2.4230998 2.59203337 2.41793327 1 P 0 ;0,1,2=250,3=0.000000
L 2.59203337 2.41793327 2.59548337 2.41431644 1 P 0 ;0,1,2=250,3=0.000000
L 2.59548337 2.41431644 2.59778356 2.40914892 1 P 0 ;0,1,2=250,3=0.000000
L 2.59778356 2.40914892 2.5985501 2.4045 1 P 0 ;0,1,2=250,3=0.000000
L 2.5985501 2.4045 2.58245 2.4045 1 P 0 ;0,1,2=250,3=0.000000
L 2.56678356 2.41741575 2.5641001 2.42103356 1 P 0 ;0,1,2=250,3=0.000000
L 2.5641001 2.42103356 2.5617999 2.4230998 1 P 0 ;0,1,2=250,3=0.000000
L 2.5617999 2.4230998 2.55873317 2.42413287 1 P 0 ;0,1,2=250,3=0.000000
L 2.55873317 2.42413287 2.5560497 2.4230998 1 P 0 ;0,1,2=250,3=0.000000
L 2.5560497 2.4230998 2.55413346 2.42103356 1 P 0 ;0,1,2=250,3=0.000000
L 2.55413346 2.42103356 2.5525998 2.41793327 1 P 0 ;0,1,2=250,3=0.000000
L 2.5525998 2.41793327 2.55221654 2.41431644 1 P 0 ;0,1,2=250,3=0.000000
L 2.55221654 2.41431644 2.5525998 2.41121614 1 P 0 ;0,1,2=250,3=0.000000
L 2.5525998 2.41121614 2.55413346 2.40811585 1 P 0 ;0,1,2=250,3=0.000000
L 2.55413346 2.40811585 2.55643366 2.40553307 1 P 0 ;0,1,2=250,3=0.000000
L 2.55643366 2.40553307 2.55911644 2.4045 1 P 0 ;0,1,2=250,3=0.000000
L 2.55911644 2.4045 2.56218317 2.40553307 1 P 0 ;0,1,2=250,3=0.000000
L 2.56218317 2.40553307 2.56486663 2.40863238 1 P 0 ;0,1,2=250,3=0.000000
L 2.56486663 2.40863238 2.5664003 2.41328327 1 P 0 ;0,1,2=250,3=0.000000
L 2.5664003 2.41328327 2.56678356 2.4184498 1 P 0 ;0,1,2=250,3=0.000000
L 2.56678356 2.4184498 2.56601713 2.42516594 1 P 0 ;0,1,2=250,3=0.000000
L 2.56601713 2.42516594 2.56486663 2.42878376 1 P 0 ;0,1,2=250,3=0.000000
L 2.56486663 2.42878376 2.56295039 2.4323997 1 P 0 ;0,1,2=250,3=0.000000
L 2.56295039 2.4323997 2.56026693 2.43498337 1 P 0 ;0,1,2=250,3=0.000000
L 2.56026693 2.43498337 2.55758346 2.4355 1 P 0 ;0,1,2=250,3=0.000000
L 2.55758346 2.4355 2.5549 2.43446683 1 P 0 ;0,1,2=250,3=0.000000
L 2.5549 2.43446683 2.55298297 2.43188307 1 P 0 ;0,1,2=250,3=0.000000
L 2.52926693 2.4045 2.52850039 2.41121614 1 P 0 ;0,1,2=250,3=0.000000
L 2.52850039 2.41121614 2.5273499 2.41689921 1 P 0 ;0,1,2=250,3=0.000000
L 2.5273499 2.41689921 2.52581693 2.42206663 1 P 0 ;0,1,2=250,3=0.000000
L 2.52581693 2.42206663 2.5239 2.4277497 1 P 0 ;0,1,2=250,3=0.000000
L 2.5239 2.4277497 2.52083327 2.4355 1 P 0 ;0,1,2=250,3=0.000000
L 2.52083327 2.4355 2.53616683 2.4355 1 P 0 ;0,1,2=250,3=0.000000
L 2.485 2.397 2.575 2.397 1 P 0 
L 2.575 2.397 2.575 2.353 1 P 0 
L 2.575 2.353 2.485 2.353 1 P 0 
L 2.485 2.353 2.485 2.397 1 P 0 
L 2.49916683 2.4045 2.49916683 2.4355 1 P 0 ;0,1,2=251,3=0.000000
L 2.49916683 2.4355 2.48958346 2.4355 1 P 0 ;0,1,2=251,3=0.000000
L 2.48958346 2.4355 2.48651673 2.43394931 1 P 0 ;0,1,2=251,3=0.000000
L 2.48651673 2.43394931 2.4845998 2.43188307 1 P 0 ;0,1,2=251,3=0.000000
L 2.4845998 2.43188307 2.48383327 2.4277497 1 P 0 ;0,1,2=251,3=0.000000
L 2.48383327 2.4277497 2.4845998 2.42361634 1 P 0 ;0,1,2=251,3=0.000000
L 2.4845998 2.42361634 2.4869 2.42103356 1 P 0 ;0,1,2=251,3=0.000000
L 2.4869 2.42103356 2.48958346 2.41948287 1 P 0 ;0,1,2=251,3=0.000000
L 2.48958346 2.41948287 2.49916683 2.41948287 1 P 0 ;0,1,2=251,3=0.000000
L 2.48958346 2.41948287 2.48383327 2.4045 1 P 0 ;0,1,2=251,3=0.000000
L 2.46050039 2.4045 2.46050039 2.4355 1 P 0 ;0,1,2=251,3=0.000000
L 2.46050039 2.4355 2.4651001 2.4293003 1 P 0 ;0,1,2=251,3=0.000000
L 2.4651001 2.4045 2.45590069 2.4045 1 P 0 ;0,1,2=251,3=0.000000
L 2.42950039 2.4355 2.43256713 2.43446683 1 P 0 ;0,1,2=251,3=0.000000
L 2.43256713 2.43446683 2.43486663 2.43188307 1 P 0 ;0,1,2=251,3=0.000000
L 2.43486663 2.43188307 2.4364003 2.42878376 1 P 0 ;0,1,2=251,3=0.000000
L 2.4364003 2.42878376 2.4375501 2.42464941 1 P 0 ;0,1,2=251,3=0.000000
L 2.4375501 2.42464941 2.43793337 2.41999951 1 P 0 ;0,1,2=251,3=0.000000
L 2.43793337 2.41999951 2.4375501 2.41534951 1 P 0 ;0,1,2=251,3=0.000000
L 2.4375501 2.41534951 2.4364003 2.41121614 1 P 0 ;0,1,2=251,3=0.000000
L 2.4364003 2.41121614 2.43486663 2.40811585 1 P 0 ;0,1,2=251,3=0.000000
L 2.43486663 2.40811585 2.43256713 2.40553307 1 P 0 ;0,1,2=251,3=0.000000
L 2.43256713 2.40553307 2.42950039 2.4045 1 P 0 ;0,1,2=251,3=0.000000
L 2.42950039 2.4045 2.42643366 2.40553307 1 P 0 ;0,1,2=251,3=0.000000
L 2.42643366 2.40553307 2.42413346 2.40811585 1 P 0 ;0,1,2=251,3=0.000000
L 2.42413346 2.40811585 2.4225998 2.41121614 1 P 0 ;0,1,2=251,3=0.000000
L 2.4225998 2.41121614 2.42145 2.41534951 1 P 0 ;0,1,2=251,3=0.000000
L 2.42145 2.41534951 2.42106673 2.41999951 1 P 0 ;0,1,2=251,3=0.000000
L 2.42106673 2.41999951 2.42145 2.42464941 1 P 0 ;0,1,2=251,3=0.000000
L 2.42145 2.42464941 2.4225998 2.42878376 1 P 0 ;0,1,2=251,3=0.000000
L 2.4225998 2.42878376 2.42413346 2.43188307 1 P 0 ;0,1,2=251,3=0.000000
L 2.42413346 2.43188307 2.42643366 2.43446683 1 P 0 ;0,1,2=251,3=0.000000
L 2.42643366 2.43446683 2.42950039 2.4355 1 P 0 ;0,1,2=251,3=0.000000
L 2.39926693 2.4045 2.39850039 2.41121614 1 P 0 ;0,1,2=251,3=0.000000
L 2.39850039 2.41121614 2.3973499 2.41689921 1 P 0 ;0,1,2=251,3=0.000000
L 2.3973499 2.41689921 2.39581693 2.42206663 1 P 0 ;0,1,2=251,3=0.000000
L 2.39581693 2.42206663 2.3939 2.4277497 1 P 0 ;0,1,2=251,3=0.000000
L 2.3939 2.4277497 2.39083327 2.4355 1 P 0 ;0,1,2=251,3=0.000000
L 2.39083327 2.4355 2.40616683 2.4355 1 P 0 ;0,1,2=251,3=0.000000
L 5.47 0.662 5.47 0.618 1 P 0 
L 5.47 0.618 5.38 0.618 1 P 0 
L 5.38 0.618 5.38 0.662 1 P 0 
L 5.38 0.662 5.47 0.662 1 P 0 
L 5.42416683 0.5695 5.42416683 0.6005 1 P 0 ;0,1,2=252,3=0.000000
L 5.42416683 0.6005 5.41458346 0.6005 1 P 0 ;0,1,2=252,3=0.000000
L 5.41458346 0.6005 5.41151673 0.59894931 1 P 0 ;0,1,2=252,3=0.000000
L 5.41151673 0.59894931 5.4095998 0.59688307 1 P 0 ;0,1,2=252,3=0.000000
L 5.4095998 0.59688307 5.40883327 0.5927497 1 P 0 ;0,1,2=252,3=0.000000
L 5.40883327 0.5927497 5.4095998 0.58861634 1 P 0 ;0,1,2=252,3=0.000000
L 5.4095998 0.58861634 5.4119 0.58603356 1 P 0 ;0,1,2=252,3=0.000000
L 5.4119 0.58603356 5.41458346 0.58448287 1 P 0 ;0,1,2=252,3=0.000000
L 5.41458346 0.58448287 5.42416683 0.58448287 1 P 0 ;0,1,2=252,3=0.000000
L 5.41458346 0.58448287 5.40883327 0.5695 1 P 0 ;0,1,2=252,3=0.000000
L 5.39278356 0.59533346 5.39048337 0.59843278 1 P 0 ;0,1,2=252,3=0.000000
L 5.39048337 0.59843278 5.3877999 0.59998337 1 P 0 ;0,1,2=252,3=0.000000
L 5.3877999 0.59998337 5.38473317 0.6005 1 P 0 ;0,1,2=252,3=0.000000
L 5.38473317 0.6005 5.3809 0.59946683 1 P 0 ;0,1,2=252,3=0.000000
L 5.3809 0.59946683 5.37821654 0.59688307 1 P 0 ;0,1,2=252,3=0.000000
L 5.37821654 0.59688307 5.37745 0.59378376 1 P 0 ;0,1,2=252,3=0.000000
L 5.37745 0.59378376 5.37783327 0.59068258 1 P 0 ;0,1,2=252,3=0.000000
L 5.37783327 0.59068258 5.37936693 0.5880998 1 P 0 ;0,1,2=252,3=0.000000
L 5.37936693 0.5880998 5.38703337 0.58293327 1 P 0 ;0,1,2=252,3=0.000000
L 5.38703337 0.58293327 5.39048337 0.57931644 1 P 0 ;0,1,2=252,3=0.000000
L 5.39048337 0.57931644 5.39278356 0.57414892 1 P 0 ;0,1,2=252,3=0.000000
L 5.39278356 0.57414892 5.3935501 0.5695 1 P 0 ;0,1,2=252,3=0.000000
L 5.3935501 0.5695 5.37745 0.5695 1 P 0 ;0,1,2=252,3=0.000000
L 5.36293337 0.57569961 5.36063386 0.57208278 1 P 0 ;0,1,2=252,3=0.000000
L 5.36063386 0.57208278 5.35756713 0.57001654 1 P 0 ;0,1,2=252,3=0.000000
L 5.35756713 0.57001654 5.35411644 0.5695 1 P 0 ;0,1,2=252,3=0.000000
L 5.35411644 0.5695 5.3510497 0.57001654 1 P 0 ;0,1,2=252,3=0.000000
L 5.3510497 0.57001654 5.34798297 0.57259931 1 P 0 ;0,1,2=252,3=0.000000
L 5.34798297 0.57259931 5.34606673 0.57569961 1 P 0 ;0,1,2=252,3=0.000000
L 5.34606673 0.57569961 5.34568346 0.5787999 1 P 0 ;0,1,2=252,3=0.000000
L 5.34568346 0.5787999 5.34645 0.58241575 1 P 0 ;0,1,2=252,3=0.000000
L 5.34645 0.58241575 5.34913346 0.58499951 1 P 0 ;0,1,2=252,3=0.000000
L 5.34913346 0.58499951 5.35181693 0.58603356 1 P 0 ;0,1,2=252,3=0.000000
L 5.35181693 0.58603356 5.35526693 0.58603356 1 P 0 ;0,1,2=252,3=0.000000
L 5.35181693 0.58603356 5.34951673 0.58758317 1 P 0 ;0,1,2=252,3=0.000000
L 5.34951673 0.58758317 5.3475998 0.59016594 1 P 0 ;0,1,2=252,3=0.000000
L 5.3475998 0.59016594 5.34683327 0.59326624 1 P 0 ;0,1,2=252,3=0.000000
L 5.34683327 0.59326624 5.3475998 0.59636654 1 P 0 ;0,1,2=252,3=0.000000
L 5.3475998 0.59636654 5.34951673 0.59894931 1 P 0 ;0,1,2=252,3=0.000000
L 5.34951673 0.59894931 5.35296673 0.6005 1 P 0 ;0,1,2=252,3=0.000000
L 5.35296673 0.6005 5.35641663 0.59998337 1 P 0 ;0,1,2=252,3=0.000000
L 5.35641663 0.59998337 5.35986663 0.59791624 1 P 0 ;0,1,2=252,3=0.000000
L 5.32350039 0.6005 5.32656713 0.59946683 1 P 0 ;0,1,2=252,3=0.000000
L 5.32656713 0.59946683 5.32886663 0.59688307 1 P 0 ;0,1,2=252,3=0.000000
L 5.32886663 0.59688307 5.3304003 0.59378376 1 P 0 ;0,1,2=252,3=0.000000
L 5.3304003 0.59378376 5.3315501 0.58964941 1 P 0 ;0,1,2=252,3=0.000000
L 5.3315501 0.58964941 5.33193337 0.58499951 1 P 0 ;0,1,2=252,3=0.000000
L 5.33193337 0.58499951 5.3315501 0.58034951 1 P 0 ;0,1,2=252,3=0.000000
L 5.3315501 0.58034951 5.3304003 0.57621614 1 P 0 ;0,1,2=252,3=0.000000
L 5.3304003 0.57621614 5.32886663 0.57311585 1 P 0 ;0,1,2=252,3=0.000000
L 5.32886663 0.57311585 5.32656713 0.57053307 1 P 0 ;0,1,2=252,3=0.000000
L 5.32656713 0.57053307 5.32350039 0.5695 1 P 0 ;0,1,2=252,3=0.000000
L 5.32350039 0.5695 5.32043366 0.57053307 1 P 0 ;0,1,2=252,3=0.000000
L 5.32043366 0.57053307 5.31813346 0.57311585 1 P 0 ;0,1,2=252,3=0.000000
L 5.31813346 0.57311585 5.3165998 0.57621614 1 P 0 ;0,1,2=252,3=0.000000
L 5.3165998 0.57621614 5.31545 0.58034951 1 P 0 ;0,1,2=252,3=0.000000
L 5.31545 0.58034951 5.31506673 0.58499951 1 P 0 ;0,1,2=252,3=0.000000
L 5.31506673 0.58499951 5.31545 0.58964941 1 P 0 ;0,1,2=252,3=0.000000
L 5.31545 0.58964941 5.3165998 0.59378376 1 P 0 ;0,1,2=252,3=0.000000
L 5.3165998 0.59378376 5.31813346 0.59688307 1 P 0 ;0,1,2=252,3=0.000000
L 5.31813346 0.59688307 5.32043366 0.59946683 1 P 0 ;0,1,2=252,3=0.000000
L 5.32043366 0.59946683 5.32350039 0.6005 1 P 0 ;0,1,2=252,3=0.000000
L 6.322 2.03373996 6.322 1.94373996 1 P 0 
L 6.278 2.03373996 6.322 2.03373996 1 P 0 
L 6.322 1.94373996 6.278 1.94373996 1 P 0 
L 6.278 1.94373996 6.278 2.03373996 1 P 0 
L 6.3395 1.62457313 6.3705 1.62457313 1 P 0 ;0,1,2=253,3=90.000000
L 6.3705 1.62457313 6.3705 1.6341565 1 P 0 ;0,1,2=253,3=90.000000
L 6.3705 1.6341565 6.36894931 1.63722323 1 P 0 ;0,1,2=253,3=90.000000
L 6.36894931 1.63722323 6.36688307 1.63914016 1 P 0 ;0,1,2=253,3=90.000000
L 6.36688307 1.63914016 6.3627497 1.63990669 1 P 0 ;0,1,2=253,3=90.000000
L 6.3627497 1.63990669 6.35861634 1.63914016 1 P 0 ;0,1,2=253,3=90.000000
L 6.35861634 1.63914016 6.35603356 1.63683996 1 P 0 ;0,1,2=253,3=90.000000
L 6.35603356 1.63683996 6.35448287 1.6341565 1 P 0 ;0,1,2=253,3=90.000000
L 6.35448287 1.6341565 6.35448287 1.62457313 1 P 0 ;0,1,2=253,3=90.000000
L 6.35448287 1.6341565 6.3395 1.63990669 1 P 0 ;0,1,2=253,3=90.000000
L 6.3395 1.66323957 6.3705 1.66323957 1 P 0 ;0,1,2=253,3=90.000000
L 6.3705 1.66323957 6.3643003 1.65863986 1 P 0 ;0,1,2=253,3=90.000000
L 6.3395 1.65863986 6.3395 1.66783927 1 P 0 ;0,1,2=253,3=90.000000
L 6.3705 1.69423957 6.36946683 1.69117283 1 P 0 ;0,1,2=253,3=90.000000
L 6.36946683 1.69117283 6.36688307 1.68887333 1 P 0 ;0,1,2=253,3=90.000000
L 6.36688307 1.68887333 6.36378376 1.68733967 1 P 0 ;0,1,2=253,3=90.000000
L 6.36378376 1.68733967 6.35964941 1.68618986 1 P 0 ;0,1,2=253,3=90.000000
L 6.35964941 1.68618986 6.35499951 1.68580659 1 P 0 ;0,1,2=253,3=90.000000
L 6.35499951 1.68580659 6.35034951 1.68618986 1 P 0 ;0,1,2=253,3=90.000000
L 6.35034951 1.68618986 6.34621614 1.68733967 1 P 0 ;0,1,2=253,3=90.000000
L 6.34621614 1.68733967 6.34311585 1.68887333 1 P 0 ;0,1,2=253,3=90.000000
L 6.34311585 1.68887333 6.34053307 1.69117283 1 P 0 ;0,1,2=253,3=90.000000
L 6.34053307 1.69117283 6.3395 1.69423957 1 P 0 ;0,1,2=253,3=90.000000
L 6.3395 1.69423957 6.34053307 1.6973063 1 P 0 ;0,1,2=253,3=90.000000
L 6.34053307 1.6973063 6.34311585 1.6996065 1 P 0 ;0,1,2=253,3=90.000000
L 6.34311585 1.6996065 6.34621614 1.70114016 1 P 0 ;0,1,2=253,3=90.000000
L 6.34621614 1.70114016 6.35034951 1.70228996 1 P 0 ;0,1,2=253,3=90.000000
L 6.35034951 1.70228996 6.35499951 1.70267323 1 P 0 ;0,1,2=253,3=90.000000
L 6.35499951 1.70267323 6.35964941 1.70228996 1 P 0 ;0,1,2=253,3=90.000000
L 6.35964941 1.70228996 6.36378376 1.70114016 1 P 0 ;0,1,2=253,3=90.000000
L 6.36378376 1.70114016 6.36688307 1.6996065 1 P 0 ;0,1,2=253,3=90.000000
L 6.36688307 1.6996065 6.36946683 1.6973063 1 P 0 ;0,1,2=253,3=90.000000
L 6.36946683 1.6973063 6.3705 1.69423957 1 P 0 ;0,1,2=253,3=90.000000
L 6.3395 1.72523957 6.3705 1.72523957 1 P 0 ;0,1,2=253,3=90.000000
L 6.3705 1.72523957 6.3643003 1.72063986 1 P 0 ;0,1,2=253,3=90.000000
L 6.3395 1.72063986 6.3395 1.72983927 1 P 0 ;0,1,2=253,3=90.000000
L 5.533 0.584 5.533 0.674 1 P 0 
L 5.533 0.674 5.577 0.674 1 P 0 
L 5.577 0.674 5.577 0.584 1 P 0 
L 5.577 0.584 5.533 0.584 1 P 0 
L 5.5345 0.80083317 5.5655 0.80083317 1 P 0 ;0,1,2=254,3=90.000000
L 5.5655 0.80083317 5.5655 0.81041654 1 P 0 ;0,1,2=254,3=90.000000
L 5.5655 0.81041654 5.56394931 0.81348327 1 P 0 ;0,1,2=254,3=90.000000
L 5.56394931 0.81348327 5.56188307 0.8154002 1 P 0 ;0,1,2=254,3=90.000000
L 5.56188307 0.8154002 5.5577497 0.81616673 1 P 0 ;0,1,2=254,3=90.000000
L 5.5577497 0.81616673 5.55361634 0.8154002 1 P 0 ;0,1,2=254,3=90.000000
L 5.55361634 0.8154002 5.55103356 0.8131 1 P 0 ;0,1,2=254,3=90.000000
L 5.55103356 0.8131 5.54948287 0.81041654 1 P 0 ;0,1,2=254,3=90.000000
L 5.54948287 0.81041654 5.54948287 0.80083317 1 P 0 ;0,1,2=254,3=90.000000
L 5.54948287 0.81041654 5.5345 0.81616673 1 P 0 ;0,1,2=254,3=90.000000
L 5.56033346 0.83221644 5.56343278 0.83451663 1 P 0 ;0,1,2=254,3=90.000000
L 5.56343278 0.83451663 5.56498337 0.8372001 1 P 0 ;0,1,2=254,3=90.000000
L 5.56498337 0.8372001 5.5655 0.84026683 1 P 0 ;0,1,2=254,3=90.000000
L 5.5655 0.84026683 5.56446683 0.8441 1 P 0 ;0,1,2=254,3=90.000000
L 5.56446683 0.8441 5.56188307 0.84678346 1 P 0 ;0,1,2=254,3=90.000000
L 5.56188307 0.84678346 5.55878376 0.84755 1 P 0 ;0,1,2=254,3=90.000000
L 5.55878376 0.84755 5.55568258 0.84716673 1 P 0 ;0,1,2=254,3=90.000000
L 5.55568258 0.84716673 5.5530998 0.84563307 1 P 0 ;0,1,2=254,3=90.000000
L 5.5530998 0.84563307 5.54793327 0.83796663 1 P 0 ;0,1,2=254,3=90.000000
L 5.54793327 0.83796663 5.54431644 0.83451663 1 P 0 ;0,1,2=254,3=90.000000
L 5.54431644 0.83451663 5.53914892 0.83221644 1 P 0 ;0,1,2=254,3=90.000000
L 5.53914892 0.83221644 5.5345 0.8314499 1 P 0 ;0,1,2=254,3=90.000000
L 5.5345 0.8314499 5.5345 0.84755 1 P 0 ;0,1,2=254,3=90.000000
L 5.56033346 0.86321644 5.56343278 0.86551663 1 P 0 ;0,1,2=254,3=90.000000
L 5.56343278 0.86551663 5.56498337 0.8682001 1 P 0 ;0,1,2=254,3=90.000000
L 5.56498337 0.8682001 5.5655 0.87126683 1 P 0 ;0,1,2=254,3=90.000000
L 5.5655 0.87126683 5.56446683 0.8751 1 P 0 ;0,1,2=254,3=90.000000
L 5.56446683 0.8751 5.56188307 0.87778346 1 P 0 ;0,1,2=254,3=90.000000
L 5.56188307 0.87778346 5.55878376 0.87855 1 P 0 ;0,1,2=254,3=90.000000
L 5.55878376 0.87855 5.55568258 0.87816673 1 P 0 ;0,1,2=254,3=90.000000
L 5.55568258 0.87816673 5.5530998 0.87663307 1 P 0 ;0,1,2=254,3=90.000000
L 5.5530998 0.87663307 5.54793327 0.86896663 1 P 0 ;0,1,2=254,3=90.000000
L 5.54793327 0.86896663 5.54431644 0.86551663 1 P 0 ;0,1,2=254,3=90.000000
L 5.54431644 0.86551663 5.53914892 0.86321644 1 P 0 ;0,1,2=254,3=90.000000
L 5.53914892 0.86321644 5.5345 0.8624499 1 P 0 ;0,1,2=254,3=90.000000
L 5.5345 0.8624499 5.5345 0.87855 1 P 0 ;0,1,2=254,3=90.000000
L 5.53811585 0.89498287 5.53553307 0.89766634 1 P 0 ;0,1,2=254,3=90.000000
L 5.53553307 0.89766634 5.5345 0.90073307 1 P 0 ;0,1,2=254,3=90.000000
L 5.5345 0.90073307 5.53553307 0.9037998 1 P 0 ;0,1,2=254,3=90.000000
L 5.53553307 0.9037998 5.53863238 0.90648327 1 P 0 ;0,1,2=254,3=90.000000
L 5.53863238 0.90648327 5.54328327 0.9084002 1 P 0 ;0,1,2=254,3=90.000000
L 5.54328327 0.9084002 5.54793327 0.90916673 1 P 0 ;0,1,2=254,3=90.000000
L 5.54793327 0.90916673 5.55361634 0.90916673 1 P 0 ;0,1,2=254,3=90.000000
L 5.55361634 0.90916673 5.55826624 0.9084002 1 P 0 ;0,1,2=254,3=90.000000
L 5.55826624 0.9084002 5.5623997 0.90648327 1 P 0 ;0,1,2=254,3=90.000000
L 5.5623997 0.90648327 5.56446683 0.90418307 1 P 0 ;0,1,2=254,3=90.000000
L 5.56446683 0.90418307 5.5655 0.90149961 1 P 0 ;0,1,2=254,3=90.000000
L 5.5655 0.90149961 5.56446683 0.89843287 1 P 0 ;0,1,2=254,3=90.000000
L 5.56446683 0.89843287 5.5623997 0.89613337 1 P 0 ;0,1,2=254,3=90.000000
L 5.5623997 0.89613337 5.5593003 0.8945997 1 P 0 ;0,1,2=254,3=90.000000
L 5.5593003 0.8945997 5.55516594 0.89383317 1 P 0 ;0,1,2=254,3=90.000000
L 5.55516594 0.89383317 5.5515501 0.8945997 1 P 0 ;0,1,2=254,3=90.000000
L 5.5515501 0.8945997 5.54793327 0.89651663 1 P 0 ;0,1,2=254,3=90.000000
L 5.54793327 0.89651663 5.54586604 0.89881683 1 P 0 ;0,1,2=254,3=90.000000
L 5.54586604 0.89881683 5.54534951 0.90149961 1 P 0 ;0,1,2=254,3=90.000000
L 5.54534951 0.90149961 5.54638268 0.90456634 1 P 0 ;0,1,2=254,3=90.000000
L 5.54638268 0.90456634 5.54896634 0.90686654 1 P 0 ;0,1,2=254,3=90.000000
L 5.54896634 0.90686654 5.55361634 0.90916673 1 P 0 ;0,1,2=254,3=90.000000
L 2.518 2.24 2.562 2.24 1 P 0 
L 2.562 2.24 2.562 2.15 1 P 0 
L 2.562 2.15 2.518 2.15 1 P 0 
L 2.518 2.15 2.518 2.24 1 P 0 
L 2.5395 1.90633317 2.5705 1.90633317 1 P 0 ;0,1,2=255,3=90.000000
L 2.5705 1.90633317 2.5705 1.91591654 1 P 0 ;0,1,2=255,3=90.000000
L 2.5705 1.91591654 2.56894931 1.91898327 1 P 0 ;0,1,2=255,3=90.000000
L 2.56894931 1.91898327 2.56688307 1.9209002 1 P 0 ;0,1,2=255,3=90.000000
L 2.56688307 1.9209002 2.5627497 1.92166673 1 P 0 ;0,1,2=255,3=90.000000
L 2.5627497 1.92166673 2.55861634 1.9209002 1 P 0 ;0,1,2=255,3=90.000000
L 2.55861634 1.9209002 2.55603356 1.9186 1 P 0 ;0,1,2=255,3=90.000000
L 2.55603356 1.9186 2.55448287 1.91591654 1 P 0 ;0,1,2=255,3=90.000000
L 2.55448287 1.91591654 2.55448287 1.90633317 1 P 0 ;0,1,2=255,3=90.000000
L 2.55448287 1.91591654 2.5395 1.92166673 1 P 0 ;0,1,2=255,3=90.000000
L 2.54311585 1.93848287 2.54053307 1.94116634 1 P 0 ;0,1,2=255,3=90.000000
L 2.54053307 1.94116634 2.5395 1.94423307 1 P 0 ;0,1,2=255,3=90.000000
L 2.5395 1.94423307 2.54053307 1.9472998 1 P 0 ;0,1,2=255,3=90.000000
L 2.54053307 1.9472998 2.54363238 1.94998327 1 P 0 ;0,1,2=255,3=90.000000
L 2.54363238 1.94998327 2.54828327 1.9519002 1 P 0 ;0,1,2=255,3=90.000000
L 2.54828327 1.9519002 2.55293327 1.95266673 1 P 0 ;0,1,2=255,3=90.000000
L 2.55293327 1.95266673 2.55861634 1.95266673 1 P 0 ;0,1,2=255,3=90.000000
L 2.55861634 1.95266673 2.56326624 1.9519002 1 P 0 ;0,1,2=255,3=90.000000
L 2.56326624 1.9519002 2.5673997 1.94998327 1 P 0 ;0,1,2=255,3=90.000000
L 2.5673997 1.94998327 2.56946683 1.94768307 1 P 0 ;0,1,2=255,3=90.000000
L 2.56946683 1.94768307 2.5705 1.94499961 1 P 0 ;0,1,2=255,3=90.000000
L 2.5705 1.94499961 2.56946683 1.94193287 1 P 0 ;0,1,2=255,3=90.000000
L 2.56946683 1.94193287 2.5673997 1.93963337 1 P 0 ;0,1,2=255,3=90.000000
L 2.5673997 1.93963337 2.5643003 1.9380997 1 P 0 ;0,1,2=255,3=90.000000
L 2.5643003 1.9380997 2.56016594 1.93733317 1 P 0 ;0,1,2=255,3=90.000000
L 2.56016594 1.93733317 2.5565501 1.9380997 1 P 0 ;0,1,2=255,3=90.000000
L 2.5565501 1.9380997 2.55293327 1.94001663 1 P 0 ;0,1,2=255,3=90.000000
L 2.55293327 1.94001663 2.55086604 1.94231683 1 P 0 ;0,1,2=255,3=90.000000
L 2.55086604 1.94231683 2.55034951 1.94499961 1 P 0 ;0,1,2=255,3=90.000000
L 2.55034951 1.94499961 2.55138268 1.94806634 1 P 0 ;0,1,2=255,3=90.000000
L 2.55138268 1.94806634 2.55396634 1.95036654 1 P 0 ;0,1,2=255,3=90.000000
L 2.55396634 1.95036654 2.55861634 1.95266673 1 P 0 ;0,1,2=255,3=90.000000
L 2.54311585 1.96948287 2.54053307 1.97216634 1 P 0 ;0,1,2=255,3=90.000000
L 2.54053307 1.97216634 2.5395 1.97523307 1 P 0 ;0,1,2=255,3=90.000000
L 2.5395 1.97523307 2.54053307 1.9782998 1 P 0 ;0,1,2=255,3=90.000000
L 2.54053307 1.9782998 2.54363238 1.98098327 1 P 0 ;0,1,2=255,3=90.000000
L 2.54363238 1.98098327 2.54828327 1.9829002 1 P 0 ;0,1,2=255,3=90.000000
L 2.54828327 1.9829002 2.55293327 1.98366673 1 P 0 ;0,1,2=255,3=90.000000
L 2.55293327 1.98366673 2.55861634 1.98366673 1 P 0 ;0,1,2=255,3=90.000000
L 2.55861634 1.98366673 2.56326624 1.9829002 1 P 0 ;0,1,2=255,3=90.000000
L 2.56326624 1.9829002 2.5673997 1.98098327 1 P 0 ;0,1,2=255,3=90.000000
L 2.5673997 1.98098327 2.56946683 1.97868307 1 P 0 ;0,1,2=255,3=90.000000
L 2.56946683 1.97868307 2.5705 1.97599961 1 P 0 ;0,1,2=255,3=90.000000
L 2.5705 1.97599961 2.56946683 1.97293287 1 P 0 ;0,1,2=255,3=90.000000
L 2.56946683 1.97293287 2.5673997 1.97063337 1 P 0 ;0,1,2=255,3=90.000000
L 2.5673997 1.97063337 2.5643003 1.9690997 1 P 0 ;0,1,2=255,3=90.000000
L 2.5643003 1.9690997 2.56016594 1.96833317 1 P 0 ;0,1,2=255,3=90.000000
L 2.56016594 1.96833317 2.5565501 1.9690997 1 P 0 ;0,1,2=255,3=90.000000
L 2.5565501 1.9690997 2.55293327 1.97101663 1 P 0 ;0,1,2=255,3=90.000000
L 2.55293327 1.97101663 2.55086604 1.97331683 1 P 0 ;0,1,2=255,3=90.000000
L 2.55086604 1.97331683 2.55034951 1.97599961 1 P 0 ;0,1,2=255,3=90.000000
L 2.55034951 1.97599961 2.55138268 1.97906634 1 P 0 ;0,1,2=255,3=90.000000
L 2.55138268 1.97906634 2.55396634 1.98136654 1 P 0 ;0,1,2=255,3=90.000000
L 2.55396634 1.98136654 2.55861634 1.98366673 1 P 0 ;0,1,2=255,3=90.000000
L 6.233 2.03373996 6.277 2.03373996 1 P 0 
L 6.233 1.94373996 6.233 2.03373996 1 P 0 
L 6.277 2.03373996 6.277 1.94373996 1 P 0 
L 6.277 1.94373996 6.233 1.94373996 1 P 0 
L 6.2945 1.62457313 6.3255 1.62457313 1 P 0 ;0,1,2=256,3=90.000000
L 6.3255 1.62457313 6.3255 1.6341565 1 P 0 ;0,1,2=256,3=90.000000
L 6.3255 1.6341565 6.32394931 1.63722323 1 P 0 ;0,1,2=256,3=90.000000
L 6.32394931 1.63722323 6.32188307 1.63914016 1 P 0 ;0,1,2=256,3=90.000000
L 6.32188307 1.63914016 6.3177497 1.63990669 1 P 0 ;0,1,2=256,3=90.000000
L 6.3177497 1.63990669 6.31361634 1.63914016 1 P 0 ;0,1,2=256,3=90.000000
L 6.31361634 1.63914016 6.31103356 1.63683996 1 P 0 ;0,1,2=256,3=90.000000
L 6.31103356 1.63683996 6.30948287 1.6341565 1 P 0 ;0,1,2=256,3=90.000000
L 6.30948287 1.6341565 6.30948287 1.62457313 1 P 0 ;0,1,2=256,3=90.000000
L 6.30948287 1.6341565 6.2945 1.63990669 1 P 0 ;0,1,2=256,3=90.000000
L 6.2945 1.66323957 6.3255 1.66323957 1 P 0 ;0,1,2=256,3=90.000000
L 6.3255 1.66323957 6.3193003 1.65863986 1 P 0 ;0,1,2=256,3=90.000000
L 6.2945 1.65863986 6.2945 1.66783927 1 P 0 ;0,1,2=256,3=90.000000
L 6.3255 1.69423957 6.32446683 1.69117283 1 P 0 ;0,1,2=256,3=90.000000
L 6.32446683 1.69117283 6.32188307 1.68887333 1 P 0 ;0,1,2=256,3=90.000000
L 6.32188307 1.68887333 6.31878376 1.68733967 1 P 0 ;0,1,2=256,3=90.000000
L 6.31878376 1.68733967 6.31464941 1.68618986 1 P 0 ;0,1,2=256,3=90.000000
L 6.31464941 1.68618986 6.30999951 1.68580659 1 P 0 ;0,1,2=256,3=90.000000
L 6.30999951 1.68580659 6.30534951 1.68618986 1 P 0 ;0,1,2=256,3=90.000000
L 6.30534951 1.68618986 6.30121614 1.68733967 1 P 0 ;0,1,2=256,3=90.000000
L 6.30121614 1.68733967 6.29811585 1.68887333 1 P 0 ;0,1,2=256,3=90.000000
L 6.29811585 1.68887333 6.29553307 1.69117283 1 P 0 ;0,1,2=256,3=90.000000
L 6.29553307 1.69117283 6.2945 1.69423957 1 P 0 ;0,1,2=256,3=90.000000
L 6.2945 1.69423957 6.29553307 1.6973063 1 P 0 ;0,1,2=256,3=90.000000
L 6.29553307 1.6973063 6.29811585 1.6996065 1 P 0 ;0,1,2=256,3=90.000000
L 6.29811585 1.6996065 6.30121614 1.70114016 1 P 0 ;0,1,2=256,3=90.000000
L 6.30121614 1.70114016 6.30534951 1.70228996 1 P 0 ;0,1,2=256,3=90.000000
L 6.30534951 1.70228996 6.30999951 1.70267323 1 P 0 ;0,1,2=256,3=90.000000
L 6.30999951 1.70267323 6.31464941 1.70228996 1 P 0 ;0,1,2=256,3=90.000000
L 6.31464941 1.70228996 6.31878376 1.70114016 1 P 0 ;0,1,2=256,3=90.000000
L 6.31878376 1.70114016 6.32188307 1.6996065 1 P 0 ;0,1,2=256,3=90.000000
L 6.32188307 1.6996065 6.32446683 1.6973063 1 P 0 ;0,1,2=256,3=90.000000
L 6.32446683 1.6973063 6.3255 1.69423957 1 P 0 ;0,1,2=256,3=90.000000
L 6.32033346 1.7179564 6.32343278 1.72025659 1 P 0 ;0,1,2=256,3=90.000000
L 6.32343278 1.72025659 6.32498337 1.72294006 1 P 0 ;0,1,2=256,3=90.000000
L 6.32498337 1.72294006 6.3255 1.72600679 1 P 0 ;0,1,2=256,3=90.000000
L 6.3255 1.72600679 6.32446683 1.72983996 1 P 0 ;0,1,2=256,3=90.000000
L 6.32446683 1.72983996 6.32188307 1.73252343 1 P 0 ;0,1,2=256,3=90.000000
L 6.32188307 1.73252343 6.31878376 1.73328996 1 P 0 ;0,1,2=256,3=90.000000
L 6.31878376 1.73328996 6.31568258 1.73290669 1 P 0 ;0,1,2=256,3=90.000000
L 6.31568258 1.73290669 6.3130998 1.73137303 1 P 0 ;0,1,2=256,3=90.000000
L 6.3130998 1.73137303 6.30793327 1.72370659 1 P 0 ;0,1,2=256,3=90.000000
L 6.30793327 1.72370659 6.30431644 1.72025659 1 P 0 ;0,1,2=256,3=90.000000
L 6.30431644 1.72025659 6.29914892 1.7179564 1 P 0 ;0,1,2=256,3=90.000000
L 6.29914892 1.7179564 6.2945 1.71718986 1 P 0 ;0,1,2=256,3=90.000000
L 6.2945 1.71718986 6.2945 1.73328996 1 P 0 ;0,1,2=256,3=90.000000
L 2.518 2.33 2.562 2.33 1 P 0 
L 2.518 2.24 2.518 2.33 1 P 0 
L 2.562 2.33 2.562 2.24 1 P 0 
L 2.562 2.24 2.518 2.24 1 P 0 
L 2.5395 1.99583317 2.5705 1.99583317 1 P 0 ;0,1,2=257,3=90.000000
L 2.5705 1.99583317 2.5705 2.00541654 1 P 0 ;0,1,2=257,3=90.000000
L 2.5705 2.00541654 2.56894931 2.00848327 1 P 0 ;0,1,2=257,3=90.000000
L 2.56894931 2.00848327 2.56688307 2.0104002 1 P 0 ;0,1,2=257,3=90.000000
L 2.56688307 2.0104002 2.5627497 2.01116673 1 P 0 ;0,1,2=257,3=90.000000
L 2.5627497 2.01116673 2.55861634 2.0104002 1 P 0 ;0,1,2=257,3=90.000000
L 2.55861634 2.0104002 2.55603356 2.0081 1 P 0 ;0,1,2=257,3=90.000000
L 2.55603356 2.0081 2.55448287 2.00541654 1 P 0 ;0,1,2=257,3=90.000000
L 2.55448287 2.00541654 2.55448287 1.99583317 1 P 0 ;0,1,2=257,3=90.000000
L 2.55448287 2.00541654 2.5395 2.01116673 1 P 0 ;0,1,2=257,3=90.000000
L 2.5395 2.03449961 2.5705 2.03449961 1 P 0 ;0,1,2=257,3=90.000000
L 2.5705 2.03449961 2.5643003 2.0298999 1 P 0 ;0,1,2=257,3=90.000000
L 2.5395 2.0298999 2.5395 2.03909931 1 P 0 ;0,1,2=257,3=90.000000
L 2.5705 2.06549961 2.56946683 2.06243287 1 P 0 ;0,1,2=257,3=90.000000
L 2.56946683 2.06243287 2.56688307 2.06013337 1 P 0 ;0,1,2=257,3=90.000000
L 2.56688307 2.06013337 2.56378376 2.0585997 1 P 0 ;0,1,2=257,3=90.000000
L 2.56378376 2.0585997 2.55964941 2.0574499 1 P 0 ;0,1,2=257,3=90.000000
L 2.55964941 2.0574499 2.55499951 2.05706663 1 P 0 ;0,1,2=257,3=90.000000
L 2.55499951 2.05706663 2.55034951 2.0574499 1 P 0 ;0,1,2=257,3=90.000000
L 2.55034951 2.0574499 2.54621614 2.0585997 1 P 0 ;0,1,2=257,3=90.000000
L 2.54621614 2.0585997 2.54311585 2.06013337 1 P 0 ;0,1,2=257,3=90.000000
L 2.54311585 2.06013337 2.54053307 2.06243287 1 P 0 ;0,1,2=257,3=90.000000
L 2.54053307 2.06243287 2.5395 2.06549961 1 P 0 ;0,1,2=257,3=90.000000
L 2.5395 2.06549961 2.54053307 2.06856634 1 P 0 ;0,1,2=257,3=90.000000
L 2.54053307 2.06856634 2.54311585 2.07086654 1 P 0 ;0,1,2=257,3=90.000000
L 2.54311585 2.07086654 2.54621614 2.0724002 1 P 0 ;0,1,2=257,3=90.000000
L 2.54621614 2.0724002 2.55034951 2.07355 1 P 0 ;0,1,2=257,3=90.000000
L 2.55034951 2.07355 2.55499951 2.07393327 1 P 0 ;0,1,2=257,3=90.000000
L 2.55499951 2.07393327 2.55964941 2.07355 1 P 0 ;0,1,2=257,3=90.000000
L 2.55964941 2.07355 2.56378376 2.0724002 1 P 0 ;0,1,2=257,3=90.000000
L 2.56378376 2.0724002 2.56688307 2.07086654 1 P 0 ;0,1,2=257,3=90.000000
L 2.56688307 2.07086654 2.56946683 2.06856634 1 P 0 ;0,1,2=257,3=90.000000
L 2.56946683 2.06856634 2.5705 2.06549961 1 P 0 ;0,1,2=257,3=90.000000
L 2.5705 2.09649961 2.56946683 2.09343287 1 P 0 ;0,1,2=257,3=90.000000
L 2.56946683 2.09343287 2.56688307 2.09113337 1 P 0 ;0,1,2=257,3=90.000000
L 2.56688307 2.09113337 2.56378376 2.0895997 1 P 0 ;0,1,2=257,3=90.000000
L 2.56378376 2.0895997 2.55964941 2.0884499 1 P 0 ;0,1,2=257,3=90.000000
L 2.55964941 2.0884499 2.55499951 2.08806663 1 P 0 ;0,1,2=257,3=90.000000
L 2.55499951 2.08806663 2.55034951 2.0884499 1 P 0 ;0,1,2=257,3=90.000000
L 2.55034951 2.0884499 2.54621614 2.0895997 1 P 0 ;0,1,2=257,3=90.000000
L 2.54621614 2.0895997 2.54311585 2.09113337 1 P 0 ;0,1,2=257,3=90.000000
L 2.54311585 2.09113337 2.54053307 2.09343287 1 P 0 ;0,1,2=257,3=90.000000
L 2.54053307 2.09343287 2.5395 2.09649961 1 P 0 ;0,1,2=257,3=90.000000
L 2.5395 2.09649961 2.54053307 2.09956634 1 P 0 ;0,1,2=257,3=90.000000
L 2.54053307 2.09956634 2.54311585 2.10186654 1 P 0 ;0,1,2=257,3=90.000000
L 2.54311585 2.10186654 2.54621614 2.1034002 1 P 0 ;0,1,2=257,3=90.000000
L 2.54621614 2.1034002 2.55034951 2.10455 1 P 0 ;0,1,2=257,3=90.000000
L 2.55034951 2.10455 2.55499951 2.10493327 1 P 0 ;0,1,2=257,3=90.000000
L 2.55499951 2.10493327 2.55964941 2.10455 1 P 0 ;0,1,2=257,3=90.000000
L 2.55964941 2.10455 2.56378376 2.1034002 1 P 0 ;0,1,2=257,3=90.000000
L 2.56378376 2.1034002 2.56688307 2.10186654 1 P 0 ;0,1,2=257,3=90.000000
L 2.56688307 2.10186654 2.56946683 2.09956634 1 P 0 ;0,1,2=257,3=90.000000
L 2.56946683 2.09956634 2.5705 2.09649961 1 P 0 ;0,1,2=257,3=90.000000
L 6.188 2.03373996 6.232 2.03373996 1 P 0 
L 6.232 2.03373996 6.232 1.94373996 1 P 0 
L 6.232 1.94373996 6.188 1.94373996 1 P 0 
L 6.188 1.94373996 6.188 2.03373996 1 P 0 
L 6.2495 1.62457313 6.2805 1.62457313 1 P 0 ;0,1,2=258,3=90.000000
L 6.2805 1.62457313 6.2805 1.6341565 1 P 0 ;0,1,2=258,3=90.000000
L 6.2805 1.6341565 6.27894931 1.63722323 1 P 0 ;0,1,2=258,3=90.000000
L 6.27894931 1.63722323 6.27688307 1.63914016 1 P 0 ;0,1,2=258,3=90.000000
L 6.27688307 1.63914016 6.2727497 1.63990669 1 P 0 ;0,1,2=258,3=90.000000
L 6.2727497 1.63990669 6.26861634 1.63914016 1 P 0 ;0,1,2=258,3=90.000000
L 6.26861634 1.63914016 6.26603356 1.63683996 1 P 0 ;0,1,2=258,3=90.000000
L 6.26603356 1.63683996 6.26448287 1.6341565 1 P 0 ;0,1,2=258,3=90.000000
L 6.26448287 1.6341565 6.26448287 1.62457313 1 P 0 ;0,1,2=258,3=90.000000
L 6.26448287 1.6341565 6.2495 1.63990669 1 P 0 ;0,1,2=258,3=90.000000
L 6.2495 1.66323957 6.2805 1.66323957 1 P 0 ;0,1,2=258,3=90.000000
L 6.2805 1.66323957 6.2743003 1.65863986 1 P 0 ;0,1,2=258,3=90.000000
L 6.2495 1.65863986 6.2495 1.66783927 1 P 0 ;0,1,2=258,3=90.000000
L 6.2805 1.69423957 6.27946683 1.69117283 1 P 0 ;0,1,2=258,3=90.000000
L 6.27946683 1.69117283 6.27688307 1.68887333 1 P 0 ;0,1,2=258,3=90.000000
L 6.27688307 1.68887333 6.27378376 1.68733967 1 P 0 ;0,1,2=258,3=90.000000
L 6.27378376 1.68733967 6.26964941 1.68618986 1 P 0 ;0,1,2=258,3=90.000000
L 6.26964941 1.68618986 6.26499951 1.68580659 1 P 0 ;0,1,2=258,3=90.000000
L 6.26499951 1.68580659 6.26034951 1.68618986 1 P 0 ;0,1,2=258,3=90.000000
L 6.26034951 1.68618986 6.25621614 1.68733967 1 P 0 ;0,1,2=258,3=90.000000
L 6.25621614 1.68733967 6.25311585 1.68887333 1 P 0 ;0,1,2=258,3=90.000000
L 6.25311585 1.68887333 6.25053307 1.69117283 1 P 0 ;0,1,2=258,3=90.000000
L 6.25053307 1.69117283 6.2495 1.69423957 1 P 0 ;0,1,2=258,3=90.000000
L 6.2495 1.69423957 6.25053307 1.6973063 1 P 0 ;0,1,2=258,3=90.000000
L 6.25053307 1.6973063 6.25311585 1.6996065 1 P 0 ;0,1,2=258,3=90.000000
L 6.25311585 1.6996065 6.25621614 1.70114016 1 P 0 ;0,1,2=258,3=90.000000
L 6.25621614 1.70114016 6.26034951 1.70228996 1 P 0 ;0,1,2=258,3=90.000000
L 6.26034951 1.70228996 6.26499951 1.70267323 1 P 0 ;0,1,2=258,3=90.000000
L 6.26499951 1.70267323 6.26964941 1.70228996 1 P 0 ;0,1,2=258,3=90.000000
L 6.26964941 1.70228996 6.27378376 1.70114016 1 P 0 ;0,1,2=258,3=90.000000
L 6.27378376 1.70114016 6.27688307 1.6996065 1 P 0 ;0,1,2=258,3=90.000000
L 6.27688307 1.6996065 6.27946683 1.6973063 1 P 0 ;0,1,2=258,3=90.000000
L 6.27946683 1.6973063 6.2805 1.69423957 1 P 0 ;0,1,2=258,3=90.000000
L 6.25569961 1.71680659 6.25208278 1.7191061 1 P 0 ;0,1,2=258,3=90.000000
L 6.25208278 1.7191061 6.25001654 1.72217283 1 P 0 ;0,1,2=258,3=90.000000
L 6.25001654 1.72217283 6.2495 1.72562352 1 P 0 ;0,1,2=258,3=90.000000
L 6.2495 1.72562352 6.25001654 1.72869026 1 P 0 ;0,1,2=258,3=90.000000
L 6.25001654 1.72869026 6.25259931 1.73175699 1 P 0 ;0,1,2=258,3=90.000000
L 6.25259931 1.73175699 6.25569961 1.73367323 1 P 0 ;0,1,2=258,3=90.000000
L 6.25569961 1.73367323 6.2587999 1.7340565 1 P 0 ;0,1,2=258,3=90.000000
L 6.2587999 1.7340565 6.26241575 1.73328996 1 P 0 ;0,1,2=258,3=90.000000
L 6.26241575 1.73328996 6.26499951 1.7306065 1 P 0 ;0,1,2=258,3=90.000000
L 6.26499951 1.7306065 6.26603356 1.72792303 1 P 0 ;0,1,2=258,3=90.000000
L 6.26603356 1.72792303 6.26603356 1.72447303 1 P 0 ;0,1,2=258,3=90.000000
L 6.26603356 1.72792303 6.26758317 1.73022323 1 P 0 ;0,1,2=258,3=90.000000
L 6.26758317 1.73022323 6.27016594 1.73214016 1 P 0 ;0,1,2=258,3=90.000000
L 6.27016594 1.73214016 6.27326624 1.73290669 1 P 0 ;0,1,2=258,3=90.000000
L 6.27326624 1.73290669 6.27636654 1.73214016 1 P 0 ;0,1,2=258,3=90.000000
L 6.27636654 1.73214016 6.27894931 1.73022323 1 P 0 ;0,1,2=258,3=90.000000
L 6.27894931 1.73022323 6.2805 1.72677323 1 P 0 ;0,1,2=258,3=90.000000
L 6.2805 1.72677323 6.27998337 1.72332333 1 P 0 ;0,1,2=258,3=90.000000
L 6.27998337 1.72332333 6.27791624 1.71987333 1 P 0 ;0,1,2=258,3=90.000000
L 5.794 0.724 5.794 0.634 1 P 0 
L 5.794 0.634 5.75 0.634 1 P 0 
L 5.75 0.634 5.75 0.724 1 P 0 
L 5.75 0.724 5.794 0.724 1 P 0 
L 5.8295 0.61083317 5.8605 0.61083317 1 P 0 ;0,1,2=259,3=90.000000
L 5.8605 0.61083317 5.8605 0.62041654 1 P 0 ;0,1,2=259,3=90.000000
L 5.8605 0.62041654 5.85894931 0.62348327 1 P 0 ;0,1,2=259,3=90.000000
L 5.85894931 0.62348327 5.85688307 0.6254002 1 P 0 ;0,1,2=259,3=90.000000
L 5.85688307 0.6254002 5.8527497 0.62616673 1 P 0 ;0,1,2=259,3=90.000000
L 5.8527497 0.62616673 5.84861634 0.6254002 1 P 0 ;0,1,2=259,3=90.000000
L 5.84861634 0.6254002 5.84603356 0.6231 1 P 0 ;0,1,2=259,3=90.000000
L 5.84603356 0.6231 5.84448287 0.62041654 1 P 0 ;0,1,2=259,3=90.000000
L 5.84448287 0.62041654 5.84448287 0.61083317 1 P 0 ;0,1,2=259,3=90.000000
L 5.84448287 0.62041654 5.8295 0.62616673 1 P 0 ;0,1,2=259,3=90.000000
L 5.85533346 0.64221644 5.85843278 0.64451663 1 P 0 ;0,1,2=259,3=90.000000
L 5.85843278 0.64451663 5.85998337 0.6472001 1 P 0 ;0,1,2=259,3=90.000000
L 5.85998337 0.6472001 5.8605 0.65026683 1 P 0 ;0,1,2=259,3=90.000000
L 5.8605 0.65026683 5.85946683 0.6541 1 P 0 ;0,1,2=259,3=90.000000
L 5.85946683 0.6541 5.85688307 0.65678346 1 P 0 ;0,1,2=259,3=90.000000
L 5.85688307 0.65678346 5.85378376 0.65755 1 P 0 ;0,1,2=259,3=90.000000
L 5.85378376 0.65755 5.85068258 0.65716673 1 P 0 ;0,1,2=259,3=90.000000
L 5.85068258 0.65716673 5.8480998 0.65563307 1 P 0 ;0,1,2=259,3=90.000000
L 5.8480998 0.65563307 5.84293327 0.64796663 1 P 0 ;0,1,2=259,3=90.000000
L 5.84293327 0.64796663 5.83931644 0.64451663 1 P 0 ;0,1,2=259,3=90.000000
L 5.83931644 0.64451663 5.83414892 0.64221644 1 P 0 ;0,1,2=259,3=90.000000
L 5.83414892 0.64221644 5.8295 0.6414499 1 P 0 ;0,1,2=259,3=90.000000
L 5.8295 0.6414499 5.8295 0.65755 1 P 0 ;0,1,2=259,3=90.000000
L 5.85533346 0.67321644 5.85843278 0.67551663 1 P 0 ;0,1,2=259,3=90.000000
L 5.85843278 0.67551663 5.85998337 0.6782001 1 P 0 ;0,1,2=259,3=90.000000
L 5.85998337 0.6782001 5.8605 0.68126683 1 P 0 ;0,1,2=259,3=90.000000
L 5.8605 0.68126683 5.85946683 0.6851 1 P 0 ;0,1,2=259,3=90.000000
L 5.85946683 0.6851 5.85688307 0.68778346 1 P 0 ;0,1,2=259,3=90.000000
L 5.85688307 0.68778346 5.85378376 0.68855 1 P 0 ;0,1,2=259,3=90.000000
L 5.85378376 0.68855 5.85068258 0.68816673 1 P 0 ;0,1,2=259,3=90.000000
L 5.85068258 0.68816673 5.8480998 0.68663307 1 P 0 ;0,1,2=259,3=90.000000
L 5.8480998 0.68663307 5.84293327 0.67896663 1 P 0 ;0,1,2=259,3=90.000000
L 5.84293327 0.67896663 5.83931644 0.67551663 1 P 0 ;0,1,2=259,3=90.000000
L 5.83931644 0.67551663 5.83414892 0.67321644 1 P 0 ;0,1,2=259,3=90.000000
L 5.83414892 0.67321644 5.8295 0.6724499 1 P 0 ;0,1,2=259,3=90.000000
L 5.8295 0.6724499 5.8295 0.68855 1 P 0 ;0,1,2=259,3=90.000000
L 5.8295 0.71073307 5.83621614 0.71149961 1 P 0 ;0,1,2=259,3=90.000000
L 5.83621614 0.71149961 5.84189921 0.7126501 1 P 0 ;0,1,2=259,3=90.000000
L 5.84189921 0.7126501 5.84706663 0.71418307 1 P 0 ;0,1,2=259,3=90.000000
L 5.84706663 0.71418307 5.8527497 0.7161 1 P 0 ;0,1,2=259,3=90.000000
L 5.8527497 0.7161 5.8605 0.71916673 1 P 0 ;0,1,2=259,3=90.000000
L 5.8605 0.71916673 5.8605 0.70383317 1 P 0 ;0,1,2=259,3=90.000000
L 5.797 0.82 5.797 0.73 1 P 0 
L 5.753 0.82 5.797 0.82 1 P 0 
L 5.797 0.73 5.753 0.73 1 P 0 
L 5.753 0.73 5.753 0.82 1 P 0 
L 5.7595 0.83083317 5.7905 0.83083317 1 P 0 ;0,1,2=260,3=90.000000
L 5.7905 0.83083317 5.7905 0.84041654 1 P 0 ;0,1,2=260,3=90.000000
L 5.7905 0.84041654 5.78894931 0.84348327 1 P 0 ;0,1,2=260,3=90.000000
L 5.78894931 0.84348327 5.78688307 0.8454002 1 P 0 ;0,1,2=260,3=90.000000
L 5.78688307 0.8454002 5.7827497 0.84616673 1 P 0 ;0,1,2=260,3=90.000000
L 5.7827497 0.84616673 5.77861634 0.8454002 1 P 0 ;0,1,2=260,3=90.000000
L 5.77861634 0.8454002 5.77603356 0.8431 1 P 0 ;0,1,2=260,3=90.000000
L 5.77603356 0.8431 5.77448287 0.84041654 1 P 0 ;0,1,2=260,3=90.000000
L 5.77448287 0.84041654 5.77448287 0.83083317 1 P 0 ;0,1,2=260,3=90.000000
L 5.77448287 0.84041654 5.7595 0.84616673 1 P 0 ;0,1,2=260,3=90.000000
L 5.78533346 0.86221644 5.78843278 0.86451663 1 P 0 ;0,1,2=260,3=90.000000
L 5.78843278 0.86451663 5.78998337 0.8672001 1 P 0 ;0,1,2=260,3=90.000000
L 5.78998337 0.8672001 5.7905 0.87026683 1 P 0 ;0,1,2=260,3=90.000000
L 5.7905 0.87026683 5.78946683 0.8741 1 P 0 ;0,1,2=260,3=90.000000
L 5.78946683 0.8741 5.78688307 0.87678346 1 P 0 ;0,1,2=260,3=90.000000
L 5.78688307 0.87678346 5.78378376 0.87755 1 P 0 ;0,1,2=260,3=90.000000
L 5.78378376 0.87755 5.78068258 0.87716673 1 P 0 ;0,1,2=260,3=90.000000
L 5.78068258 0.87716673 5.7780998 0.87563307 1 P 0 ;0,1,2=260,3=90.000000
L 5.7780998 0.87563307 5.77293327 0.86796663 1 P 0 ;0,1,2=260,3=90.000000
L 5.77293327 0.86796663 5.76931644 0.86451663 1 P 0 ;0,1,2=260,3=90.000000
L 5.76931644 0.86451663 5.76414892 0.86221644 1 P 0 ;0,1,2=260,3=90.000000
L 5.76414892 0.86221644 5.7595 0.8614499 1 P 0 ;0,1,2=260,3=90.000000
L 5.7595 0.8614499 5.7595 0.87755 1 P 0 ;0,1,2=260,3=90.000000
L 5.78533346 0.89321644 5.78843278 0.89551663 1 P 0 ;0,1,2=260,3=90.000000
L 5.78843278 0.89551663 5.78998337 0.8982001 1 P 0 ;0,1,2=260,3=90.000000
L 5.78998337 0.8982001 5.7905 0.90126683 1 P 0 ;0,1,2=260,3=90.000000
L 5.7905 0.90126683 5.78946683 0.9051 1 P 0 ;0,1,2=260,3=90.000000
L 5.78946683 0.9051 5.78688307 0.90778346 1 P 0 ;0,1,2=260,3=90.000000
L 5.78688307 0.90778346 5.78378376 0.90855 1 P 0 ;0,1,2=260,3=90.000000
L 5.78378376 0.90855 5.78068258 0.90816673 1 P 0 ;0,1,2=260,3=90.000000
L 5.78068258 0.90816673 5.7780998 0.90663307 1 P 0 ;0,1,2=260,3=90.000000
L 5.7780998 0.90663307 5.77293327 0.89896663 1 P 0 ;0,1,2=260,3=90.000000
L 5.77293327 0.89896663 5.76931644 0.89551663 1 P 0 ;0,1,2=260,3=90.000000
L 5.76931644 0.89551663 5.76414892 0.89321644 1 P 0 ;0,1,2=260,3=90.000000
L 5.76414892 0.89321644 5.7595 0.8924499 1 P 0 ;0,1,2=260,3=90.000000
L 5.7595 0.8924499 5.7595 0.90855 1 P 0 ;0,1,2=260,3=90.000000
L 5.76414892 0.92306663 5.76156614 0.92536614 1 P 0 ;0,1,2=260,3=90.000000
L 5.76156614 0.92536614 5.76001654 0.92804961 1 P 0 ;0,1,2=260,3=90.000000
L 5.76001654 0.92804961 5.7595 0.93149961 1 P 0 ;0,1,2=260,3=90.000000
L 5.7595 0.93149961 5.76053307 0.9349503 1 P 0 ;0,1,2=260,3=90.000000
L 5.76053307 0.9349503 5.76259931 0.93763307 1 P 0 ;0,1,2=260,3=90.000000
L 5.76259931 0.93763307 5.76621614 0.93955 1 P 0 ;0,1,2=260,3=90.000000
L 5.76621614 0.93955 5.77034951 0.93993327 1 P 0 ;0,1,2=260,3=90.000000
L 5.77034951 0.93993327 5.77448287 0.93916673 1 P 0 ;0,1,2=260,3=90.000000
L 5.77448287 0.93916673 5.77706663 0.9372498 1 P 0 ;0,1,2=260,3=90.000000
L 5.77706663 0.9372498 5.77913287 0.93456634 1 P 0 ;0,1,2=260,3=90.000000
L 5.77913287 0.93456634 5.77964941 0.93188356 1 P 0 ;0,1,2=260,3=90.000000
L 5.77964941 0.93188356 5.77913287 0.9292001 1 P 0 ;0,1,2=260,3=90.000000
L 5.77913287 0.9292001 5.77706663 0.9257501 1 P 0 ;0,1,2=260,3=90.000000
L 5.77706663 0.9257501 5.7905 0.9268999 1 P 0 ;0,1,2=260,3=90.000000
L 5.7905 0.9268999 5.7905 0.9372498 1 P 0 ;0,1,2=260,3=90.000000
L 4.95 1.697 4.95 1.653 1 P 0 
L 4.86 1.697 4.95 1.697 1 P 0 
L 4.95 1.653 4.86 1.653 1 P 0 
L 4.86 1.653 4.86 1.697 1 P 0 
L 5.09416683 1.6545 5.09416683 1.6855 1 P 0 ;0,1,2=261,3=0.000000
L 5.09416683 1.6855 5.08458346 1.6855 1 P 0 ;0,1,2=261,3=0.000000
L 5.08458346 1.6855 5.08151673 1.68394931 1 P 0 ;0,1,2=261,3=0.000000
L 5.08151673 1.68394931 5.0795998 1.68188307 1 P 0 ;0,1,2=261,3=0.000000
L 5.0795998 1.68188307 5.07883327 1.6777497 1 P 0 ;0,1,2=261,3=0.000000
L 5.07883327 1.6777497 5.0795998 1.67361634 1 P 0 ;0,1,2=261,3=0.000000
L 5.0795998 1.67361634 5.0819 1.67103356 1 P 0 ;0,1,2=261,3=0.000000
L 5.0819 1.67103356 5.08458346 1.66948287 1 P 0 ;0,1,2=261,3=0.000000
L 5.08458346 1.66948287 5.09416683 1.66948287 1 P 0 ;0,1,2=261,3=0.000000
L 5.08458346 1.66948287 5.07883327 1.6545 1 P 0 ;0,1,2=261,3=0.000000
L 5.06278356 1.68033346 5.06048337 1.68343278 1 P 0 ;0,1,2=261,3=0.000000
L 5.06048337 1.68343278 5.0577999 1.68498337 1 P 0 ;0,1,2=261,3=0.000000
L 5.0577999 1.68498337 5.05473317 1.6855 1 P 0 ;0,1,2=261,3=0.000000
L 5.05473317 1.6855 5.0509 1.68446683 1 P 0 ;0,1,2=261,3=0.000000
L 5.0509 1.68446683 5.04821654 1.68188307 1 P 0 ;0,1,2=261,3=0.000000
L 5.04821654 1.68188307 5.04745 1.67878376 1 P 0 ;0,1,2=261,3=0.000000
L 5.04745 1.67878376 5.04783327 1.67568258 1 P 0 ;0,1,2=261,3=0.000000
L 5.04783327 1.67568258 5.04936693 1.6730998 1 P 0 ;0,1,2=261,3=0.000000
L 5.04936693 1.6730998 5.05703337 1.66793327 1 P 0 ;0,1,2=261,3=0.000000
L 5.05703337 1.66793327 5.06048337 1.66431644 1 P 0 ;0,1,2=261,3=0.000000
L 5.06048337 1.66431644 5.06278356 1.65914892 1 P 0 ;0,1,2=261,3=0.000000
L 5.06278356 1.65914892 5.0635501 1.6545 1 P 0 ;0,1,2=261,3=0.000000
L 5.0635501 1.6545 5.04745 1.6545 1 P 0 ;0,1,2=261,3=0.000000
L 5.02450039 1.6545 5.02450039 1.6855 1 P 0 ;0,1,2=261,3=0.000000
L 5.02450039 1.6855 5.0291001 1.6793003 1 P 0 ;0,1,2=261,3=0.000000
L 5.0291001 1.6545 5.01990069 1.6545 1 P 0 ;0,1,2=261,3=0.000000
L 4.99350039 1.6545 4.99081693 1.65501654 1 P 0 ;0,1,2=261,3=0.000000
L 4.99081693 1.65501654 4.9877502 1.65656614 1 P 0 ;0,1,2=261,3=0.000000
L 4.9877502 1.65656614 4.98583327 1.65914892 1 P 0 ;0,1,2=261,3=0.000000
L 4.98583327 1.65914892 4.98506673 1.66276673 1 P 0 ;0,1,2=261,3=0.000000
L 4.98506673 1.66276673 4.98583327 1.66638268 1 P 0 ;0,1,2=261,3=0.000000
L 4.98583327 1.66638268 4.98813346 1.66948287 1 P 0 ;0,1,2=261,3=0.000000
L 4.98813346 1.66948287 4.99158346 1.67103356 1 P 0 ;0,1,2=261,3=0.000000
L 4.99158346 1.67103356 4.99541663 1.67103356 1 P 0 ;0,1,2=261,3=0.000000
L 4.99541663 1.67103356 4.99771683 1.67206663 1 P 0 ;0,1,2=261,3=0.000000
L 4.99771683 1.67206663 4.99963386 1.67464941 1 P 0 ;0,1,2=261,3=0.000000
L 4.99963386 1.67464941 5.0004003 1.67826624 1 P 0 ;0,1,2=261,3=0.000000
L 5.0004003 1.67826624 4.9992499 1.68188307 1 P 0 ;0,1,2=261,3=0.000000
L 4.9992499 1.68188307 4.99656713 1.68446683 1 P 0 ;0,1,2=261,3=0.000000
L 4.99656713 1.68446683 4.99350039 1.6855 1 P 0 ;0,1,2=261,3=0.000000
L 4.99350039 1.6855 4.99043366 1.68446683 1 P 0 ;0,1,2=261,3=0.000000
L 4.99043366 1.68446683 4.9877502 1.68188307 1 P 0 ;0,1,2=261,3=0.000000
L 4.9877502 1.68188307 4.9865998 1.67826624 1 P 0 ;0,1,2=261,3=0.000000
L 4.9865998 1.67826624 4.98736693 1.67464941 1 P 0 ;0,1,2=261,3=0.000000
L 4.98736693 1.67464941 4.98928327 1.67206663 1 P 0 ;0,1,2=261,3=0.000000
L 4.98928327 1.67206663 4.99158346 1.67103356 1 P 0 ;0,1,2=261,3=0.000000
L 4.99158346 1.67103356 4.99541663 1.67103356 1 P 0 ;0,1,2=261,3=0.000000
L 4.99541663 1.67103356 4.99886663 1.66948287 1 P 0 ;0,1,2=261,3=0.000000
L 4.99886663 1.66948287 5.00116683 1.66638268 1 P 0 ;0,1,2=261,3=0.000000
L 5.00116683 1.66638268 5.00193337 1.66276673 1 P 0 ;0,1,2=261,3=0.000000
L 5.00193337 1.66276673 5.00116683 1.65914892 1 P 0 ;0,1,2=261,3=0.000000
L 5.00116683 1.65914892 4.9992499 1.65656614 1 P 0 ;0,1,2=261,3=0.000000
L 4.9992499 1.65656614 4.99618317 1.65501654 1 P 0 ;0,1,2=261,3=0.000000
L 4.99618317 1.65501654 4.99350039 1.6545 1 P 0 ;0,1,2=261,3=0.000000
L 4.95 1.652 4.95 1.608 1 P 0 
L 4.86 1.652 4.95 1.652 1 P 0 
L 4.95 1.608 4.86 1.608 1 P 0 
L 4.86 1.608 4.86 1.652 1 P 0 
L 5.09416683 1.6095 5.09416683 1.6405 1 P 0 ;0,1,2=262,3=0.000000
L 5.09416683 1.6405 5.08458346 1.6405 1 P 0 ;0,1,2=262,3=0.000000
L 5.08458346 1.6405 5.08151673 1.63894931 1 P 0 ;0,1,2=262,3=0.000000
L 5.08151673 1.63894931 5.0795998 1.63688307 1 P 0 ;0,1,2=262,3=0.000000
L 5.0795998 1.63688307 5.07883327 1.6327497 1 P 0 ;0,1,2=262,3=0.000000
L 5.07883327 1.6327497 5.0795998 1.62861634 1 P 0 ;0,1,2=262,3=0.000000
L 5.0795998 1.62861634 5.0819 1.62603356 1 P 0 ;0,1,2=262,3=0.000000
L 5.0819 1.62603356 5.08458346 1.62448287 1 P 0 ;0,1,2=262,3=0.000000
L 5.08458346 1.62448287 5.09416683 1.62448287 1 P 0 ;0,1,2=262,3=0.000000
L 5.08458346 1.62448287 5.07883327 1.6095 1 P 0 ;0,1,2=262,3=0.000000
L 5.06278356 1.63533346 5.06048337 1.63843278 1 P 0 ;0,1,2=262,3=0.000000
L 5.06048337 1.63843278 5.0577999 1.63998337 1 P 0 ;0,1,2=262,3=0.000000
L 5.0577999 1.63998337 5.05473317 1.6405 1 P 0 ;0,1,2=262,3=0.000000
L 5.05473317 1.6405 5.0509 1.63946683 1 P 0 ;0,1,2=262,3=0.000000
L 5.0509 1.63946683 5.04821654 1.63688307 1 P 0 ;0,1,2=262,3=0.000000
L 5.04821654 1.63688307 5.04745 1.63378376 1 P 0 ;0,1,2=262,3=0.000000
L 5.04745 1.63378376 5.04783327 1.63068258 1 P 0 ;0,1,2=262,3=0.000000
L 5.04783327 1.63068258 5.04936693 1.6280998 1 P 0 ;0,1,2=262,3=0.000000
L 5.04936693 1.6280998 5.05703337 1.62293327 1 P 0 ;0,1,2=262,3=0.000000
L 5.05703337 1.62293327 5.06048337 1.61931644 1 P 0 ;0,1,2=262,3=0.000000
L 5.06048337 1.61931644 5.06278356 1.61414892 1 P 0 ;0,1,2=262,3=0.000000
L 5.06278356 1.61414892 5.0635501 1.6095 1 P 0 ;0,1,2=262,3=0.000000
L 5.0635501 1.6095 5.04745 1.6095 1 P 0 ;0,1,2=262,3=0.000000
L 5.02450039 1.6095 5.02450039 1.6405 1 P 0 ;0,1,2=262,3=0.000000
L 5.02450039 1.6405 5.0291001 1.6343003 1 P 0 ;0,1,2=262,3=0.000000
L 5.0291001 1.6095 5.01990069 1.6095 1 P 0 ;0,1,2=262,3=0.000000
L 4.99426693 1.6095 4.99350039 1.61621614 1 P 0 ;0,1,2=262,3=0.000000
L 4.99350039 1.61621614 4.9923499 1.62189921 1 P 0 ;0,1,2=262,3=0.000000
L 4.9923499 1.62189921 4.99081693 1.62706663 1 P 0 ;0,1,2=262,3=0.000000
L 4.99081693 1.62706663 4.9889 1.6327497 1 P 0 ;0,1,2=262,3=0.000000
L 4.9889 1.6327497 4.98583327 1.6405 1 P 0 ;0,1,2=262,3=0.000000
L 4.98583327 1.6405 5.00116683 1.6405 1 P 0 ;0,1,2=262,3=0.000000
L 4.59 2.967 4.59 2.923 1 P 0 
L 4.59 2.923 4.5 2.923 1 P 0 
L 4.5 2.923 4.5 2.967 1 P 0 
L 4.5 2.967 4.59 2.967 1 P 0 
L 4.59416683 3.0145 4.59416683 3.0455 1 P 0 ;0,1,2=263,3=0.000000
L 4.59416683 3.0455 4.58458346 3.0455 1 P 0 ;0,1,2=263,3=0.000000
L 4.58458346 3.0455 4.58151673 3.04394931 1 P 0 ;0,1,2=263,3=0.000000
L 4.58151673 3.04394931 4.5795998 3.04188307 1 P 0 ;0,1,2=263,3=0.000000
L 4.5795998 3.04188307 4.57883327 3.0377497 1 P 0 ;0,1,2=263,3=0.000000
L 4.57883327 3.0377497 4.5795998 3.03361634 1 P 0 ;0,1,2=263,3=0.000000
L 4.5795998 3.03361634 4.5819 3.03103356 1 P 0 ;0,1,2=263,3=0.000000
L 4.5819 3.03103356 4.58458346 3.02948287 1 P 0 ;0,1,2=263,3=0.000000
L 4.58458346 3.02948287 4.59416683 3.02948287 1 P 0 ;0,1,2=263,3=0.000000
L 4.58458346 3.02948287 4.57883327 3.0145 1 P 0 ;0,1,2=263,3=0.000000
L 4.56278356 3.04033346 4.56048337 3.04343278 1 P 0 ;0,1,2=263,3=0.000000
L 4.56048337 3.04343278 4.5577999 3.04498337 1 P 0 ;0,1,2=263,3=0.000000
L 4.5577999 3.04498337 4.55473317 3.0455 1 P 0 ;0,1,2=263,3=0.000000
L 4.55473317 3.0455 4.5509 3.04446683 1 P 0 ;0,1,2=263,3=0.000000
L 4.5509 3.04446683 4.54821654 3.04188307 1 P 0 ;0,1,2=263,3=0.000000
L 4.54821654 3.04188307 4.54745 3.03878376 1 P 0 ;0,1,2=263,3=0.000000
L 4.54745 3.03878376 4.54783327 3.03568258 1 P 0 ;0,1,2=263,3=0.000000
L 4.54783327 3.03568258 4.54936693 3.0330998 1 P 0 ;0,1,2=263,3=0.000000
L 4.54936693 3.0330998 4.55703337 3.02793327 1 P 0 ;0,1,2=263,3=0.000000
L 4.55703337 3.02793327 4.56048337 3.02431644 1 P 0 ;0,1,2=263,3=0.000000
L 4.56048337 3.02431644 4.56278356 3.01914892 1 P 0 ;0,1,2=263,3=0.000000
L 4.56278356 3.01914892 4.5635501 3.0145 1 P 0 ;0,1,2=263,3=0.000000
L 4.5635501 3.0145 4.54745 3.0145 1 P 0 ;0,1,2=263,3=0.000000
L 4.53178356 3.04033346 4.52948337 3.04343278 1 P 0 ;0,1,2=263,3=0.000000
L 4.52948337 3.04343278 4.5267999 3.04498337 1 P 0 ;0,1,2=263,3=0.000000
L 4.5267999 3.04498337 4.52373317 3.0455 1 P 0 ;0,1,2=263,3=0.000000
L 4.52373317 3.0455 4.5199 3.04446683 1 P 0 ;0,1,2=263,3=0.000000
L 4.5199 3.04446683 4.51721654 3.04188307 1 P 0 ;0,1,2=263,3=0.000000
L 4.51721654 3.04188307 4.51645 3.03878376 1 P 0 ;0,1,2=263,3=0.000000
L 4.51645 3.03878376 4.51683327 3.03568258 1 P 0 ;0,1,2=263,3=0.000000
L 4.51683327 3.03568258 4.51836693 3.0330998 1 P 0 ;0,1,2=263,3=0.000000
L 4.51836693 3.0330998 4.52603337 3.02793327 1 P 0 ;0,1,2=263,3=0.000000
L 4.52603337 3.02793327 4.52948337 3.02431644 1 P 0 ;0,1,2=263,3=0.000000
L 4.52948337 3.02431644 4.53178356 3.01914892 1 P 0 ;0,1,2=263,3=0.000000
L 4.53178356 3.01914892 4.5325501 3.0145 1 P 0 ;0,1,2=263,3=0.000000
L 4.5325501 3.0145 4.51645 3.0145 1 P 0 ;0,1,2=263,3=0.000000
L 4.50078356 3.02741575 4.4981001 3.03103356 1 P 0 ;0,1,2=263,3=0.000000
L 4.4981001 3.03103356 4.4957999 3.0330998 1 P 0 ;0,1,2=263,3=0.000000
L 4.4957999 3.0330998 4.49273317 3.03413287 1 P 0 ;0,1,2=263,3=0.000000
L 4.49273317 3.03413287 4.4900497 3.0330998 1 P 0 ;0,1,2=263,3=0.000000
L 4.4900497 3.0330998 4.48813346 3.03103356 1 P 0 ;0,1,2=263,3=0.000000
L 4.48813346 3.03103356 4.4865998 3.02793327 1 P 0 ;0,1,2=263,3=0.000000
L 4.4865998 3.02793327 4.48621654 3.02431644 1 P 0 ;0,1,2=263,3=0.000000
L 4.48621654 3.02431644 4.4865998 3.02121614 1 P 0 ;0,1,2=263,3=0.000000
L 4.4865998 3.02121614 4.48813346 3.01811585 1 P 0 ;0,1,2=263,3=0.000000
L 4.48813346 3.01811585 4.49043366 3.01553307 1 P 0 ;0,1,2=263,3=0.000000
L 4.49043366 3.01553307 4.49311644 3.0145 1 P 0 ;0,1,2=263,3=0.000000
L 4.49311644 3.0145 4.49618317 3.01553307 1 P 0 ;0,1,2=263,3=0.000000
L 4.49618317 3.01553307 4.49886663 3.01863238 1 P 0 ;0,1,2=263,3=0.000000
L 4.49886663 3.01863238 4.5004003 3.02328327 1 P 0 ;0,1,2=263,3=0.000000
L 4.5004003 3.02328327 4.50078356 3.0284498 1 P 0 ;0,1,2=263,3=0.000000
L 4.50078356 3.0284498 4.50001713 3.03516594 1 P 0 ;0,1,2=263,3=0.000000
L 4.50001713 3.03516594 4.49886663 3.03878376 1 P 0 ;0,1,2=263,3=0.000000
L 4.49886663 3.03878376 4.49695039 3.0423997 1 P 0 ;0,1,2=263,3=0.000000
L 4.49695039 3.0423997 4.49426693 3.04498337 1 P 0 ;0,1,2=263,3=0.000000
L 4.49426693 3.04498337 4.49158346 3.0455 1 P 0 ;0,1,2=263,3=0.000000
L 4.49158346 3.0455 4.4889 3.04446683 1 P 0 ;0,1,2=263,3=0.000000
L 4.4889 3.04446683 4.48698297 3.04188307 1 P 0 ;0,1,2=263,3=0.000000
L 4.59 2.817 4.59 2.773 1 P 0 
L 4.59 2.773 4.5 2.773 1 P 0 
L 4.5 2.773 4.5 2.817 1 P 0 
L 4.5 2.817 4.59 2.817 1 P 0 
L 4.59416683 2.6945 4.59416683 2.7255 1 P 0 ;0,1,2=264,3=0.000000
L 4.59416683 2.7255 4.58458346 2.7255 1 P 0 ;0,1,2=264,3=0.000000
L 4.58458346 2.7255 4.58151673 2.72394931 1 P 0 ;0,1,2=264,3=0.000000
L 4.58151673 2.72394931 4.5795998 2.72188307 1 P 0 ;0,1,2=264,3=0.000000
L 4.5795998 2.72188307 4.57883327 2.7177497 1 P 0 ;0,1,2=264,3=0.000000
L 4.57883327 2.7177497 4.5795998 2.71361634 1 P 0 ;0,1,2=264,3=0.000000
L 4.5795998 2.71361634 4.5819 2.71103356 1 P 0 ;0,1,2=264,3=0.000000
L 4.5819 2.71103356 4.58458346 2.70948287 1 P 0 ;0,1,2=264,3=0.000000
L 4.58458346 2.70948287 4.59416683 2.70948287 1 P 0 ;0,1,2=264,3=0.000000
L 4.58458346 2.70948287 4.57883327 2.6945 1 P 0 ;0,1,2=264,3=0.000000
L 4.56278356 2.72033346 4.56048337 2.72343278 1 P 0 ;0,1,2=264,3=0.000000
L 4.56048337 2.72343278 4.5577999 2.72498337 1 P 0 ;0,1,2=264,3=0.000000
L 4.5577999 2.72498337 4.55473317 2.7255 1 P 0 ;0,1,2=264,3=0.000000
L 4.55473317 2.7255 4.5509 2.72446683 1 P 0 ;0,1,2=264,3=0.000000
L 4.5509 2.72446683 4.54821654 2.72188307 1 P 0 ;0,1,2=264,3=0.000000
L 4.54821654 2.72188307 4.54745 2.71878376 1 P 0 ;0,1,2=264,3=0.000000
L 4.54745 2.71878376 4.54783327 2.71568258 1 P 0 ;0,1,2=264,3=0.000000
L 4.54783327 2.71568258 4.54936693 2.7130998 1 P 0 ;0,1,2=264,3=0.000000
L 4.54936693 2.7130998 4.55703337 2.70793327 1 P 0 ;0,1,2=264,3=0.000000
L 4.55703337 2.70793327 4.56048337 2.70431644 1 P 0 ;0,1,2=264,3=0.000000
L 4.56048337 2.70431644 4.56278356 2.69914892 1 P 0 ;0,1,2=264,3=0.000000
L 4.56278356 2.69914892 4.5635501 2.6945 1 P 0 ;0,1,2=264,3=0.000000
L 4.5635501 2.6945 4.54745 2.6945 1 P 0 ;0,1,2=264,3=0.000000
L 4.53178356 2.70741575 4.5291001 2.71103356 1 P 0 ;0,1,2=264,3=0.000000
L 4.5291001 2.71103356 4.5267999 2.7130998 1 P 0 ;0,1,2=264,3=0.000000
L 4.5267999 2.7130998 4.52373317 2.71413287 1 P 0 ;0,1,2=264,3=0.000000
L 4.52373317 2.71413287 4.5210497 2.7130998 1 P 0 ;0,1,2=264,3=0.000000
L 4.5210497 2.7130998 4.51913346 2.71103356 1 P 0 ;0,1,2=264,3=0.000000
L 4.51913346 2.71103356 4.5175998 2.70793327 1 P 0 ;0,1,2=264,3=0.000000
L 4.5175998 2.70793327 4.51721654 2.70431644 1 P 0 ;0,1,2=264,3=0.000000
L 4.51721654 2.70431644 4.5175998 2.70121614 1 P 0 ;0,1,2=264,3=0.000000
L 4.5175998 2.70121614 4.51913346 2.69811585 1 P 0 ;0,1,2=264,3=0.000000
L 4.51913346 2.69811585 4.52143366 2.69553307 1 P 0 ;0,1,2=264,3=0.000000
L 4.52143366 2.69553307 4.52411644 2.6945 1 P 0 ;0,1,2=264,3=0.000000
L 4.52411644 2.6945 4.52718317 2.69553307 1 P 0 ;0,1,2=264,3=0.000000
L 4.52718317 2.69553307 4.52986663 2.69863238 1 P 0 ;0,1,2=264,3=0.000000
L 4.52986663 2.69863238 4.5314003 2.70328327 1 P 0 ;0,1,2=264,3=0.000000
L 4.5314003 2.70328327 4.53178356 2.7084498 1 P 0 ;0,1,2=264,3=0.000000
L 4.53178356 2.7084498 4.53101713 2.71516594 1 P 0 ;0,1,2=264,3=0.000000
L 4.53101713 2.71516594 4.52986663 2.71878376 1 P 0 ;0,1,2=264,3=0.000000
L 4.52986663 2.71878376 4.52795039 2.7223997 1 P 0 ;0,1,2=264,3=0.000000
L 4.52795039 2.7223997 4.52526693 2.72498337 1 P 0 ;0,1,2=264,3=0.000000
L 4.52526693 2.72498337 4.52258346 2.7255 1 P 0 ;0,1,2=264,3=0.000000
L 4.52258346 2.7255 4.5199 2.72446683 1 P 0 ;0,1,2=264,3=0.000000
L 4.5199 2.72446683 4.51798297 2.72188307 1 P 0 ;0,1,2=264,3=0.000000
L 4.49350039 2.7255 4.49656713 2.72446683 1 P 0 ;0,1,2=264,3=0.000000
L 4.49656713 2.72446683 4.49886663 2.72188307 1 P 0 ;0,1,2=264,3=0.000000
L 4.49886663 2.72188307 4.5004003 2.71878376 1 P 0 ;0,1,2=264,3=0.000000
L 4.5004003 2.71878376 4.5015501 2.71464941 1 P 0 ;0,1,2=264,3=0.000000
L 4.5015501 2.71464941 4.50193337 2.70999951 1 P 0 ;0,1,2=264,3=0.000000
L 4.50193337 2.70999951 4.5015501 2.70534951 1 P 0 ;0,1,2=264,3=0.000000
L 4.5015501 2.70534951 4.5004003 2.70121614 1 P 0 ;0,1,2=264,3=0.000000
L 4.5004003 2.70121614 4.49886663 2.69811585 1 P 0 ;0,1,2=264,3=0.000000
L 4.49886663 2.69811585 4.49656713 2.69553307 1 P 0 ;0,1,2=264,3=0.000000
L 4.49656713 2.69553307 4.49350039 2.6945 1 P 0 ;0,1,2=264,3=0.000000
L 4.49350039 2.6945 4.49043366 2.69553307 1 P 0 ;0,1,2=264,3=0.000000
L 4.49043366 2.69553307 4.48813346 2.69811585 1 P 0 ;0,1,2=264,3=0.000000
L 4.48813346 2.69811585 4.4865998 2.70121614 1 P 0 ;0,1,2=264,3=0.000000
L 4.4865998 2.70121614 4.48545 2.70534951 1 P 0 ;0,1,2=264,3=0.000000
L 4.48545 2.70534951 4.48506673 2.70999951 1 P 0 ;0,1,2=264,3=0.000000
L 4.48506673 2.70999951 4.48545 2.71464941 1 P 0 ;0,1,2=264,3=0.000000
L 4.48545 2.71464941 4.4865998 2.71878376 1 P 0 ;0,1,2=264,3=0.000000
L 4.4865998 2.71878376 4.48813346 2.72188307 1 P 0 ;0,1,2=264,3=0.000000
L 4.48813346 2.72188307 4.49043366 2.72446683 1 P 0 ;0,1,2=264,3=0.000000
L 4.49043366 2.72446683 4.49350039 2.7255 1 P 0 ;0,1,2=264,3=0.000000
L 3.373 2.93 3.417 2.93 1 P 0 
L 3.373 2.84 3.373 2.93 1 P 0 
L 3.417 2.93 3.417 2.84 1 P 0 
L 3.417 2.84 3.373 2.84 1 P 0 
L 3.3745 2.69083317 3.4055 2.69083317 1 P 0 ;0,1,2=265,3=90.000000
L 3.4055 2.69083317 3.4055 2.70041654 1 P 0 ;0,1,2=265,3=90.000000
L 3.4055 2.70041654 3.40394931 2.70348327 1 P 0 ;0,1,2=265,3=90.000000
L 3.40394931 2.70348327 3.40188307 2.7054002 1 P 0 ;0,1,2=265,3=90.000000
L 3.40188307 2.7054002 3.3977497 2.70616673 1 P 0 ;0,1,2=265,3=90.000000
L 3.3977497 2.70616673 3.39361634 2.7054002 1 P 0 ;0,1,2=265,3=90.000000
L 3.39361634 2.7054002 3.39103356 2.7031 1 P 0 ;0,1,2=265,3=90.000000
L 3.39103356 2.7031 3.38948287 2.70041654 1 P 0 ;0,1,2=265,3=90.000000
L 3.38948287 2.70041654 3.38948287 2.69083317 1 P 0 ;0,1,2=265,3=90.000000
L 3.38948287 2.70041654 3.3745 2.70616673 1 P 0 ;0,1,2=265,3=90.000000
L 3.38069961 2.72106663 3.37708278 2.72336614 1 P 0 ;0,1,2=265,3=90.000000
L 3.37708278 2.72336614 3.37501654 2.72643287 1 P 0 ;0,1,2=265,3=90.000000
L 3.37501654 2.72643287 3.3745 2.72988356 1 P 0 ;0,1,2=265,3=90.000000
L 3.3745 2.72988356 3.37501654 2.7329503 1 P 0 ;0,1,2=265,3=90.000000
L 3.37501654 2.7329503 3.37759931 2.73601703 1 P 0 ;0,1,2=265,3=90.000000
L 3.37759931 2.73601703 3.38069961 2.73793327 1 P 0 ;0,1,2=265,3=90.000000
L 3.38069961 2.73793327 3.3837999 2.73831654 1 P 0 ;0,1,2=265,3=90.000000
L 3.3837999 2.73831654 3.38741575 2.73755 1 P 0 ;0,1,2=265,3=90.000000
L 3.38741575 2.73755 3.38999951 2.73486654 1 P 0 ;0,1,2=265,3=90.000000
L 3.38999951 2.73486654 3.39103356 2.73218307 1 P 0 ;0,1,2=265,3=90.000000
L 3.39103356 2.73218307 3.39103356 2.72873307 1 P 0 ;0,1,2=265,3=90.000000
L 3.39103356 2.73218307 3.39258317 2.73448327 1 P 0 ;0,1,2=265,3=90.000000
L 3.39258317 2.73448327 3.39516594 2.7364002 1 P 0 ;0,1,2=265,3=90.000000
L 3.39516594 2.7364002 3.39826624 2.73716673 1 P 0 ;0,1,2=265,3=90.000000
L 3.39826624 2.73716673 3.40136654 2.7364002 1 P 0 ;0,1,2=265,3=90.000000
L 3.40136654 2.7364002 3.40394931 2.73448327 1 P 0 ;0,1,2=265,3=90.000000
L 3.40394931 2.73448327 3.4055 2.73103327 1 P 0 ;0,1,2=265,3=90.000000
L 3.4055 2.73103327 3.40498337 2.72758337 1 P 0 ;0,1,2=265,3=90.000000
L 3.40498337 2.72758337 3.40291624 2.72413337 1 P 0 ;0,1,2=265,3=90.000000
L 3.3745 2.7651 3.4055 2.7651 1 P 0 ;0,1,2=265,3=90.000000
L 3.4055 2.7651 3.38328327 2.75091624 1 P 0 ;0,1,2=265,3=90.000000
L 3.38328327 2.75091624 3.38328327 2.77008366 1 P 0 ;0,1,2=265,3=90.000000
L 3.40033346 2.78421644 3.40343278 2.78651663 1 P 0 ;0,1,2=265,3=90.000000
L 3.40343278 2.78651663 3.40498337 2.7892001 1 P 0 ;0,1,2=265,3=90.000000
L 3.40498337 2.7892001 3.4055 2.79226683 1 P 0 ;0,1,2=265,3=90.000000
L 3.4055 2.79226683 3.40446683 2.7961 1 P 0 ;0,1,2=265,3=90.000000
L 3.40446683 2.7961 3.40188307 2.79878346 1 P 0 ;0,1,2=265,3=90.000000
L 3.40188307 2.79878346 3.39878376 2.79955 1 P 0 ;0,1,2=265,3=90.000000
L 3.39878376 2.79955 3.39568258 2.79916673 1 P 0 ;0,1,2=265,3=90.000000
L 3.39568258 2.79916673 3.3930998 2.79763307 1 P 0 ;0,1,2=265,3=90.000000
L 3.3930998 2.79763307 3.38793327 2.78996663 1 P 0 ;0,1,2=265,3=90.000000
L 3.38793327 2.78996663 3.38431644 2.78651663 1 P 0 ;0,1,2=265,3=90.000000
L 3.38431644 2.78651663 3.37914892 2.78421644 1 P 0 ;0,1,2=265,3=90.000000
L 3.37914892 2.78421644 3.3745 2.7834499 1 P 0 ;0,1,2=265,3=90.000000
L 3.3745 2.7834499 3.3745 2.79955 1 P 0 ;0,1,2=265,3=90.000000
L 3.328 2.93 3.372 2.93 1 P 0 
L 3.328 2.84 3.328 2.93 1 P 0 
L 3.372 2.93 3.372 2.84 1 P 0 
L 3.372 2.84 3.328 2.84 1 P 0 
L 3.3345 2.69083317 3.3655 2.69083317 1 P 0 ;0,1,2=266,3=90.000000
L 3.3655 2.69083317 3.3655 2.70041654 1 P 0 ;0,1,2=266,3=90.000000
L 3.3655 2.70041654 3.36394931 2.70348327 1 P 0 ;0,1,2=266,3=90.000000
L 3.36394931 2.70348327 3.36188307 2.7054002 1 P 0 ;0,1,2=266,3=90.000000
L 3.36188307 2.7054002 3.3577497 2.70616673 1 P 0 ;0,1,2=266,3=90.000000
L 3.3577497 2.70616673 3.35361634 2.7054002 1 P 0 ;0,1,2=266,3=90.000000
L 3.35361634 2.7054002 3.35103356 2.7031 1 P 0 ;0,1,2=266,3=90.000000
L 3.35103356 2.7031 3.34948287 2.70041654 1 P 0 ;0,1,2=266,3=90.000000
L 3.34948287 2.70041654 3.34948287 2.69083317 1 P 0 ;0,1,2=266,3=90.000000
L 3.34948287 2.70041654 3.3345 2.70616673 1 P 0 ;0,1,2=266,3=90.000000
L 3.34069961 2.72106663 3.33708278 2.72336614 1 P 0 ;0,1,2=266,3=90.000000
L 3.33708278 2.72336614 3.33501654 2.72643287 1 P 0 ;0,1,2=266,3=90.000000
L 3.33501654 2.72643287 3.3345 2.72988356 1 P 0 ;0,1,2=266,3=90.000000
L 3.3345 2.72988356 3.33501654 2.7329503 1 P 0 ;0,1,2=266,3=90.000000
L 3.33501654 2.7329503 3.33759931 2.73601703 1 P 0 ;0,1,2=266,3=90.000000
L 3.33759931 2.73601703 3.34069961 2.73793327 1 P 0 ;0,1,2=266,3=90.000000
L 3.34069961 2.73793327 3.3437999 2.73831654 1 P 0 ;0,1,2=266,3=90.000000
L 3.3437999 2.73831654 3.34741575 2.73755 1 P 0 ;0,1,2=266,3=90.000000
L 3.34741575 2.73755 3.34999951 2.73486654 1 P 0 ;0,1,2=266,3=90.000000
L 3.34999951 2.73486654 3.35103356 2.73218307 1 P 0 ;0,1,2=266,3=90.000000
L 3.35103356 2.73218307 3.35103356 2.72873307 1 P 0 ;0,1,2=266,3=90.000000
L 3.35103356 2.73218307 3.35258317 2.73448327 1 P 0 ;0,1,2=266,3=90.000000
L 3.35258317 2.73448327 3.35516594 2.7364002 1 P 0 ;0,1,2=266,3=90.000000
L 3.35516594 2.7364002 3.35826624 2.73716673 1 P 0 ;0,1,2=266,3=90.000000
L 3.35826624 2.73716673 3.36136654 2.7364002 1 P 0 ;0,1,2=266,3=90.000000
L 3.36136654 2.7364002 3.36394931 2.73448327 1 P 0 ;0,1,2=266,3=90.000000
L 3.36394931 2.73448327 3.3655 2.73103327 1 P 0 ;0,1,2=266,3=90.000000
L 3.3655 2.73103327 3.36498337 2.72758337 1 P 0 ;0,1,2=266,3=90.000000
L 3.36498337 2.72758337 3.36291624 2.72413337 1 P 0 ;0,1,2=266,3=90.000000
L 3.34741575 2.75321644 3.35103356 2.7558999 1 P 0 ;0,1,2=266,3=90.000000
L 3.35103356 2.7558999 3.3530998 2.7582001 1 P 0 ;0,1,2=266,3=90.000000
L 3.3530998 2.7582001 3.35413287 2.76126683 1 P 0 ;0,1,2=266,3=90.000000
L 3.35413287 2.76126683 3.3530998 2.7639503 1 P 0 ;0,1,2=266,3=90.000000
L 3.3530998 2.7639503 3.35103356 2.76586654 1 P 0 ;0,1,2=266,3=90.000000
L 3.35103356 2.76586654 3.34793327 2.7674002 1 P 0 ;0,1,2=266,3=90.000000
L 3.34793327 2.7674002 3.34431644 2.76778346 1 P 0 ;0,1,2=266,3=90.000000
L 3.34431644 2.76778346 3.34121614 2.7674002 1 P 0 ;0,1,2=266,3=90.000000
L 3.34121614 2.7674002 3.33811585 2.76586654 1 P 0 ;0,1,2=266,3=90.000000
L 3.33811585 2.76586654 3.33553307 2.76356634 1 P 0 ;0,1,2=266,3=90.000000
L 3.33553307 2.76356634 3.3345 2.76088356 1 P 0 ;0,1,2=266,3=90.000000
L 3.3345 2.76088356 3.33553307 2.75781683 1 P 0 ;0,1,2=266,3=90.000000
L 3.33553307 2.75781683 3.33863238 2.75513337 1 P 0 ;0,1,2=266,3=90.000000
L 3.33863238 2.75513337 3.34328327 2.7535997 1 P 0 ;0,1,2=266,3=90.000000
L 3.34328327 2.7535997 3.3484498 2.75321644 1 P 0 ;0,1,2=266,3=90.000000
L 3.3484498 2.75321644 3.35516594 2.75398287 1 P 0 ;0,1,2=266,3=90.000000
L 3.35516594 2.75398287 3.35878376 2.75513337 1 P 0 ;0,1,2=266,3=90.000000
L 3.35878376 2.75513337 3.3623997 2.75704961 1 P 0 ;0,1,2=266,3=90.000000
L 3.3623997 2.75704961 3.36498337 2.75973307 1 P 0 ;0,1,2=266,3=90.000000
L 3.36498337 2.75973307 3.3655 2.76241654 1 P 0 ;0,1,2=266,3=90.000000
L 3.3655 2.76241654 3.36446683 2.7651 1 P 0 ;0,1,2=266,3=90.000000
L 3.36446683 2.7651 3.36188307 2.76701703 1 P 0 ;0,1,2=266,3=90.000000
L 3.34069961 2.78306663 3.33708278 2.78536614 1 P 0 ;0,1,2=266,3=90.000000
L 3.33708278 2.78536614 3.33501654 2.78843287 1 P 0 ;0,1,2=266,3=90.000000
L 3.33501654 2.78843287 3.3345 2.79188356 1 P 0 ;0,1,2=266,3=90.000000
L 3.3345 2.79188356 3.33501654 2.7949503 1 P 0 ;0,1,2=266,3=90.000000
L 3.33501654 2.7949503 3.33759931 2.79801703 1 P 0 ;0,1,2=266,3=90.000000
L 3.33759931 2.79801703 3.34069961 2.79993327 1 P 0 ;0,1,2=266,3=90.000000
L 3.34069961 2.79993327 3.3437999 2.80031654 1 P 0 ;0,1,2=266,3=90.000000
L 3.3437999 2.80031654 3.34741575 2.79955 1 P 0 ;0,1,2=266,3=90.000000
L 3.34741575 2.79955 3.34999951 2.79686654 1 P 0 ;0,1,2=266,3=90.000000
L 3.34999951 2.79686654 3.35103356 2.79418307 1 P 0 ;0,1,2=266,3=90.000000
L 3.35103356 2.79418307 3.35103356 2.79073307 1 P 0 ;0,1,2=266,3=90.000000
L 3.35103356 2.79418307 3.35258317 2.79648327 1 P 0 ;0,1,2=266,3=90.000000
L 3.35258317 2.79648327 3.35516594 2.7984002 1 P 0 ;0,1,2=266,3=90.000000
L 3.35516594 2.7984002 3.35826624 2.79916673 1 P 0 ;0,1,2=266,3=90.000000
L 3.35826624 2.79916673 3.36136654 2.7984002 1 P 0 ;0,1,2=266,3=90.000000
L 3.36136654 2.7984002 3.36394931 2.79648327 1 P 0 ;0,1,2=266,3=90.000000
L 3.36394931 2.79648327 3.3655 2.79303327 1 P 0 ;0,1,2=266,3=90.000000
L 3.3655 2.79303327 3.36498337 2.78958337 1 P 0 ;0,1,2=266,3=90.000000
L 3.36498337 2.78958337 3.36291624 2.78613337 1 P 0 ;0,1,2=266,3=90.000000
L 4.553 2.395 4.553 2.485 1 P 0 
L 4.553 2.485 4.597 2.485 1 P 0 
L 4.597 2.485 4.597 2.395 1 P 0 
L 4.597 2.395 4.553 2.395 1 P 0 
L 4.5645 2.52083317 4.5955 2.52083317 1 P 0 ;0,1,2=267,3=90.000000
L 4.5955 2.52083317 4.5955 2.53041654 1 P 0 ;0,1,2=267,3=90.000000
L 4.5955 2.53041654 4.59394931 2.53348327 1 P 0 ;0,1,2=267,3=90.000000
L 4.59394931 2.53348327 4.59188307 2.5354002 1 P 0 ;0,1,2=267,3=90.000000
L 4.59188307 2.5354002 4.5877497 2.53616673 1 P 0 ;0,1,2=267,3=90.000000
L 4.5877497 2.53616673 4.58361634 2.5354002 1 P 0 ;0,1,2=267,3=90.000000
L 4.58361634 2.5354002 4.58103356 2.5331 1 P 0 ;0,1,2=267,3=90.000000
L 4.58103356 2.5331 4.57948287 2.53041654 1 P 0 ;0,1,2=267,3=90.000000
L 4.57948287 2.53041654 4.57948287 2.52083317 1 P 0 ;0,1,2=267,3=90.000000
L 4.57948287 2.53041654 4.5645 2.53616673 1 P 0 ;0,1,2=267,3=90.000000
L 4.59033346 2.55221644 4.59343278 2.55451663 1 P 0 ;0,1,2=267,3=90.000000
L 4.59343278 2.55451663 4.59498337 2.5572001 1 P 0 ;0,1,2=267,3=90.000000
L 4.59498337 2.5572001 4.5955 2.56026683 1 P 0 ;0,1,2=267,3=90.000000
L 4.5955 2.56026683 4.59446683 2.5641 1 P 0 ;0,1,2=267,3=90.000000
L 4.59446683 2.5641 4.59188307 2.56678346 1 P 0 ;0,1,2=267,3=90.000000
L 4.59188307 2.56678346 4.58878376 2.56755 1 P 0 ;0,1,2=267,3=90.000000
L 4.58878376 2.56755 4.58568258 2.56716673 1 P 0 ;0,1,2=267,3=90.000000
L 4.58568258 2.56716673 4.5830998 2.56563307 1 P 0 ;0,1,2=267,3=90.000000
L 4.5830998 2.56563307 4.57793327 2.55796663 1 P 0 ;0,1,2=267,3=90.000000
L 4.57793327 2.55796663 4.57431644 2.55451663 1 P 0 ;0,1,2=267,3=90.000000
L 4.57431644 2.55451663 4.56914892 2.55221644 1 P 0 ;0,1,2=267,3=90.000000
L 4.56914892 2.55221644 4.5645 2.5514499 1 P 0 ;0,1,2=267,3=90.000000
L 4.5645 2.5514499 4.5645 2.56755 1 P 0 ;0,1,2=267,3=90.000000
L 4.59033346 2.58321644 4.59343278 2.58551663 1 P 0 ;0,1,2=267,3=90.000000
L 4.59343278 2.58551663 4.59498337 2.5882001 1 P 0 ;0,1,2=267,3=90.000000
L 4.59498337 2.5882001 4.5955 2.59126683 1 P 0 ;0,1,2=267,3=90.000000
L 4.5955 2.59126683 4.59446683 2.5951 1 P 0 ;0,1,2=267,3=90.000000
L 4.59446683 2.5951 4.59188307 2.59778346 1 P 0 ;0,1,2=267,3=90.000000
L 4.59188307 2.59778346 4.58878376 2.59855 1 P 0 ;0,1,2=267,3=90.000000
L 4.58878376 2.59855 4.58568258 2.59816673 1 P 0 ;0,1,2=267,3=90.000000
L 4.58568258 2.59816673 4.5830998 2.59663307 1 P 0 ;0,1,2=267,3=90.000000
L 4.5830998 2.59663307 4.57793327 2.58896663 1 P 0 ;0,1,2=267,3=90.000000
L 4.57793327 2.58896663 4.57431644 2.58551663 1 P 0 ;0,1,2=267,3=90.000000
L 4.57431644 2.58551663 4.56914892 2.58321644 1 P 0 ;0,1,2=267,3=90.000000
L 4.56914892 2.58321644 4.5645 2.5824499 1 P 0 ;0,1,2=267,3=90.000000
L 4.5645 2.5824499 4.5645 2.59855 1 P 0 ;0,1,2=267,3=90.000000
L 4.57069961 2.61306663 4.56708278 2.61536614 1 P 0 ;0,1,2=267,3=90.000000
L 4.56708278 2.61536614 4.56501654 2.61843287 1 P 0 ;0,1,2=267,3=90.000000
L 4.56501654 2.61843287 4.5645 2.62188356 1 P 0 ;0,1,2=267,3=90.000000
L 4.5645 2.62188356 4.56501654 2.6249503 1 P 0 ;0,1,2=267,3=90.000000
L 4.56501654 2.6249503 4.56759931 2.62801703 1 P 0 ;0,1,2=267,3=90.000000
L 4.56759931 2.62801703 4.57069961 2.62993327 1 P 0 ;0,1,2=267,3=90.000000
L 4.57069961 2.62993327 4.5737999 2.63031654 1 P 0 ;0,1,2=267,3=90.000000
L 4.5737999 2.63031654 4.57741575 2.62955 1 P 0 ;0,1,2=267,3=90.000000
L 4.57741575 2.62955 4.57999951 2.62686654 1 P 0 ;0,1,2=267,3=90.000000
L 4.57999951 2.62686654 4.58103356 2.62418307 1 P 0 ;0,1,2=267,3=90.000000
L 4.58103356 2.62418307 4.58103356 2.62073307 1 P 0 ;0,1,2=267,3=90.000000
L 4.58103356 2.62418307 4.58258317 2.62648327 1 P 0 ;0,1,2=267,3=90.000000
L 4.58258317 2.62648327 4.58516594 2.6284002 1 P 0 ;0,1,2=267,3=90.000000
L 4.58516594 2.6284002 4.58826624 2.62916673 1 P 0 ;0,1,2=267,3=90.000000
L 4.58826624 2.62916673 4.59136654 2.6284002 1 P 0 ;0,1,2=267,3=90.000000
L 4.59136654 2.6284002 4.59394931 2.62648327 1 P 0 ;0,1,2=267,3=90.000000
L 4.59394931 2.62648327 4.5955 2.62303327 1 P 0 ;0,1,2=267,3=90.000000
L 4.5955 2.62303327 4.59498337 2.61958337 1 P 0 ;0,1,2=267,3=90.000000
L 4.59498337 2.61958337 4.59291624 2.61613337 1 P 0 ;0,1,2=267,3=90.000000
L 4.642 2.485 4.642 2.395 1 P 0 
L 4.642 2.395 4.598 2.395 1 P 0 
L 4.598 2.395 4.598 2.485 1 P 0 
L 4.598 2.485 4.642 2.485 1 P 0 
L 4.6095 2.52083317 4.6405 2.52083317 1 P 0 ;0,1,2=268,3=90.000000
L 4.6405 2.52083317 4.6405 2.53041654 1 P 0 ;0,1,2=268,3=90.000000
L 4.6405 2.53041654 4.63894931 2.53348327 1 P 0 ;0,1,2=268,3=90.000000
L 4.63894931 2.53348327 4.63688307 2.5354002 1 P 0 ;0,1,2=268,3=90.000000
L 4.63688307 2.5354002 4.6327497 2.53616673 1 P 0 ;0,1,2=268,3=90.000000
L 4.6327497 2.53616673 4.62861634 2.5354002 1 P 0 ;0,1,2=268,3=90.000000
L 4.62861634 2.5354002 4.62603356 2.5331 1 P 0 ;0,1,2=268,3=90.000000
L 4.62603356 2.5331 4.62448287 2.53041654 1 P 0 ;0,1,2=268,3=90.000000
L 4.62448287 2.53041654 4.62448287 2.52083317 1 P 0 ;0,1,2=268,3=90.000000
L 4.62448287 2.53041654 4.6095 2.53616673 1 P 0 ;0,1,2=268,3=90.000000
L 4.63533346 2.55221644 4.63843278 2.55451663 1 P 0 ;0,1,2=268,3=90.000000
L 4.63843278 2.55451663 4.63998337 2.5572001 1 P 0 ;0,1,2=268,3=90.000000
L 4.63998337 2.5572001 4.6405 2.56026683 1 P 0 ;0,1,2=268,3=90.000000
L 4.6405 2.56026683 4.63946683 2.5641 1 P 0 ;0,1,2=268,3=90.000000
L 4.63946683 2.5641 4.63688307 2.56678346 1 P 0 ;0,1,2=268,3=90.000000
L 4.63688307 2.56678346 4.63378376 2.56755 1 P 0 ;0,1,2=268,3=90.000000
L 4.63378376 2.56755 4.63068258 2.56716673 1 P 0 ;0,1,2=268,3=90.000000
L 4.63068258 2.56716673 4.6280998 2.56563307 1 P 0 ;0,1,2=268,3=90.000000
L 4.6280998 2.56563307 4.62293327 2.55796663 1 P 0 ;0,1,2=268,3=90.000000
L 4.62293327 2.55796663 4.61931644 2.55451663 1 P 0 ;0,1,2=268,3=90.000000
L 4.61931644 2.55451663 4.61414892 2.55221644 1 P 0 ;0,1,2=268,3=90.000000
L 4.61414892 2.55221644 4.6095 2.5514499 1 P 0 ;0,1,2=268,3=90.000000
L 4.6095 2.5514499 4.6095 2.56755 1 P 0 ;0,1,2=268,3=90.000000
L 4.63533346 2.58321644 4.63843278 2.58551663 1 P 0 ;0,1,2=268,3=90.000000
L 4.63843278 2.58551663 4.63998337 2.5882001 1 P 0 ;0,1,2=268,3=90.000000
L 4.63998337 2.5882001 4.6405 2.59126683 1 P 0 ;0,1,2=268,3=90.000000
L 4.6405 2.59126683 4.63946683 2.5951 1 P 0 ;0,1,2=268,3=90.000000
L 4.63946683 2.5951 4.63688307 2.59778346 1 P 0 ;0,1,2=268,3=90.000000
L 4.63688307 2.59778346 4.63378376 2.59855 1 P 0 ;0,1,2=268,3=90.000000
L 4.63378376 2.59855 4.63068258 2.59816673 1 P 0 ;0,1,2=268,3=90.000000
L 4.63068258 2.59816673 4.6280998 2.59663307 1 P 0 ;0,1,2=268,3=90.000000
L 4.6280998 2.59663307 4.62293327 2.58896663 1 P 0 ;0,1,2=268,3=90.000000
L 4.62293327 2.58896663 4.61931644 2.58551663 1 P 0 ;0,1,2=268,3=90.000000
L 4.61931644 2.58551663 4.61414892 2.58321644 1 P 0 ;0,1,2=268,3=90.000000
L 4.61414892 2.58321644 4.6095 2.5824499 1 P 0 ;0,1,2=268,3=90.000000
L 4.6095 2.5824499 4.6095 2.59855 1 P 0 ;0,1,2=268,3=90.000000
L 4.6095 2.6261 4.6405 2.6261 1 P 0 ;0,1,2=268,3=90.000000
L 4.6405 2.6261 4.61828327 2.61191624 1 P 0 ;0,1,2=268,3=90.000000
L 4.61828327 2.61191624 4.61828327 2.63108366 1 P 0 ;0,1,2=268,3=90.000000
L 4.417 2.485 4.417 2.395 1 P 0 
L 4.417 2.395 4.373 2.395 1 P 0 
L 4.373 2.395 4.373 2.485 1 P 0 
L 4.373 2.485 4.417 2.485 1 P 0 
L 4.3795 2.51583317 4.4105 2.51583317 1 P 0 ;0,1,2=269,3=90.000000
L 4.4105 2.51583317 4.4105 2.52541654 1 P 0 ;0,1,2=269,3=90.000000
L 4.4105 2.52541654 4.40894931 2.52848327 1 P 0 ;0,1,2=269,3=90.000000
L 4.40894931 2.52848327 4.40688307 2.5304002 1 P 0 ;0,1,2=269,3=90.000000
L 4.40688307 2.5304002 4.4027497 2.53116673 1 P 0 ;0,1,2=269,3=90.000000
L 4.4027497 2.53116673 4.39861634 2.5304002 1 P 0 ;0,1,2=269,3=90.000000
L 4.39861634 2.5304002 4.39603356 2.5281 1 P 0 ;0,1,2=269,3=90.000000
L 4.39603356 2.5281 4.39448287 2.52541654 1 P 0 ;0,1,2=269,3=90.000000
L 4.39448287 2.52541654 4.39448287 2.51583317 1 P 0 ;0,1,2=269,3=90.000000
L 4.39448287 2.52541654 4.3795 2.53116673 1 P 0 ;0,1,2=269,3=90.000000
L 4.40533346 2.54721644 4.40843278 2.54951663 1 P 0 ;0,1,2=269,3=90.000000
L 4.40843278 2.54951663 4.40998337 2.5522001 1 P 0 ;0,1,2=269,3=90.000000
L 4.40998337 2.5522001 4.4105 2.55526683 1 P 0 ;0,1,2=269,3=90.000000
L 4.4105 2.55526683 4.40946683 2.5591 1 P 0 ;0,1,2=269,3=90.000000
L 4.40946683 2.5591 4.40688307 2.56178346 1 P 0 ;0,1,2=269,3=90.000000
L 4.40688307 2.56178346 4.40378376 2.56255 1 P 0 ;0,1,2=269,3=90.000000
L 4.40378376 2.56255 4.40068258 2.56216673 1 P 0 ;0,1,2=269,3=90.000000
L 4.40068258 2.56216673 4.3980998 2.56063307 1 P 0 ;0,1,2=269,3=90.000000
L 4.3980998 2.56063307 4.39293327 2.55296663 1 P 0 ;0,1,2=269,3=90.000000
L 4.39293327 2.55296663 4.38931644 2.54951663 1 P 0 ;0,1,2=269,3=90.000000
L 4.38931644 2.54951663 4.38414892 2.54721644 1 P 0 ;0,1,2=269,3=90.000000
L 4.38414892 2.54721644 4.3795 2.5464499 1 P 0 ;0,1,2=269,3=90.000000
L 4.3795 2.5464499 4.3795 2.56255 1 P 0 ;0,1,2=269,3=90.000000
L 4.3795 2.58549961 4.4105 2.58549961 1 P 0 ;0,1,2=269,3=90.000000
L 4.4105 2.58549961 4.4043003 2.5808999 1 P 0 ;0,1,2=269,3=90.000000
L 4.3795 2.5808999 4.3795 2.59009931 1 P 0 ;0,1,2=269,3=90.000000
L 4.38311585 2.60998287 4.38053307 2.61266634 1 P 0 ;0,1,2=269,3=90.000000
L 4.38053307 2.61266634 4.3795 2.61573307 1 P 0 ;0,1,2=269,3=90.000000
L 4.3795 2.61573307 4.38053307 2.6187998 1 P 0 ;0,1,2=269,3=90.000000
L 4.38053307 2.6187998 4.38363238 2.62148327 1 P 0 ;0,1,2=269,3=90.000000
L 4.38363238 2.62148327 4.38828327 2.6234002 1 P 0 ;0,1,2=269,3=90.000000
L 4.38828327 2.6234002 4.39293327 2.62416673 1 P 0 ;0,1,2=269,3=90.000000
L 4.39293327 2.62416673 4.39861634 2.62416673 1 P 0 ;0,1,2=269,3=90.000000
L 4.39861634 2.62416673 4.40326624 2.6234002 1 P 0 ;0,1,2=269,3=90.000000
L 4.40326624 2.6234002 4.4073997 2.62148327 1 P 0 ;0,1,2=269,3=90.000000
L 4.4073997 2.62148327 4.40946683 2.61918307 1 P 0 ;0,1,2=269,3=90.000000
L 4.40946683 2.61918307 4.4105 2.61649961 1 P 0 ;0,1,2=269,3=90.000000
L 4.4105 2.61649961 4.40946683 2.61343287 1 P 0 ;0,1,2=269,3=90.000000
L 4.40946683 2.61343287 4.4073997 2.61113337 1 P 0 ;0,1,2=269,3=90.000000
L 4.4073997 2.61113337 4.4043003 2.6095997 1 P 0 ;0,1,2=269,3=90.000000
L 4.4043003 2.6095997 4.40016594 2.60883317 1 P 0 ;0,1,2=269,3=90.000000
L 4.40016594 2.60883317 4.3965501 2.6095997 1 P 0 ;0,1,2=269,3=90.000000
L 4.3965501 2.6095997 4.39293327 2.61151663 1 P 0 ;0,1,2=269,3=90.000000
L 4.39293327 2.61151663 4.39086604 2.61381683 1 P 0 ;0,1,2=269,3=90.000000
L 4.39086604 2.61381683 4.39034951 2.61649961 1 P 0 ;0,1,2=269,3=90.000000
L 4.39034951 2.61649961 4.39138268 2.61956634 1 P 0 ;0,1,2=269,3=90.000000
L 4.39138268 2.61956634 4.39396634 2.62186654 1 P 0 ;0,1,2=269,3=90.000000
L 4.39396634 2.62186654 4.39861634 2.62416673 1 P 0 ;0,1,2=269,3=90.000000
L 4.418 2.395 4.418 2.485 1 P 0 
L 4.418 2.485 4.462 2.485 1 P 0 
L 4.462 2.485 4.462 2.395 1 P 0 
L 4.462 2.395 4.418 2.395 1 P 0 
L 4.4245 2.51583317 4.4555 2.51583317 1 P 0 ;0,1,2=270,3=90.000000
L 4.4555 2.51583317 4.4555 2.52541654 1 P 0 ;0,1,2=270,3=90.000000
L 4.4555 2.52541654 4.45394931 2.52848327 1 P 0 ;0,1,2=270,3=90.000000
L 4.45394931 2.52848327 4.45188307 2.5304002 1 P 0 ;0,1,2=270,3=90.000000
L 4.45188307 2.5304002 4.4477497 2.53116673 1 P 0 ;0,1,2=270,3=90.000000
L 4.4477497 2.53116673 4.44361634 2.5304002 1 P 0 ;0,1,2=270,3=90.000000
L 4.44361634 2.5304002 4.44103356 2.5281 1 P 0 ;0,1,2=270,3=90.000000
L 4.44103356 2.5281 4.43948287 2.52541654 1 P 0 ;0,1,2=270,3=90.000000
L 4.43948287 2.52541654 4.43948287 2.51583317 1 P 0 ;0,1,2=270,3=90.000000
L 4.43948287 2.52541654 4.4245 2.53116673 1 P 0 ;0,1,2=270,3=90.000000
L 4.45033346 2.54721644 4.45343278 2.54951663 1 P 0 ;0,1,2=270,3=90.000000
L 4.45343278 2.54951663 4.45498337 2.5522001 1 P 0 ;0,1,2=270,3=90.000000
L 4.45498337 2.5522001 4.4555 2.55526683 1 P 0 ;0,1,2=270,3=90.000000
L 4.4555 2.55526683 4.45446683 2.5591 1 P 0 ;0,1,2=270,3=90.000000
L 4.45446683 2.5591 4.45188307 2.56178346 1 P 0 ;0,1,2=270,3=90.000000
L 4.45188307 2.56178346 4.44878376 2.56255 1 P 0 ;0,1,2=270,3=90.000000
L 4.44878376 2.56255 4.44568258 2.56216673 1 P 0 ;0,1,2=270,3=90.000000
L 4.44568258 2.56216673 4.4430998 2.56063307 1 P 0 ;0,1,2=270,3=90.000000
L 4.4430998 2.56063307 4.43793327 2.55296663 1 P 0 ;0,1,2=270,3=90.000000
L 4.43793327 2.55296663 4.43431644 2.54951663 1 P 0 ;0,1,2=270,3=90.000000
L 4.43431644 2.54951663 4.42914892 2.54721644 1 P 0 ;0,1,2=270,3=90.000000
L 4.42914892 2.54721644 4.4245 2.5464499 1 P 0 ;0,1,2=270,3=90.000000
L 4.4245 2.5464499 4.4245 2.56255 1 P 0 ;0,1,2=270,3=90.000000
L 4.45033346 2.57821644 4.45343278 2.58051663 1 P 0 ;0,1,2=270,3=90.000000
L 4.45343278 2.58051663 4.45498337 2.5832001 1 P 0 ;0,1,2=270,3=90.000000
L 4.45498337 2.5832001 4.4555 2.58626683 1 P 0 ;0,1,2=270,3=90.000000
L 4.4555 2.58626683 4.45446683 2.5901 1 P 0 ;0,1,2=270,3=90.000000
L 4.45446683 2.5901 4.45188307 2.59278346 1 P 0 ;0,1,2=270,3=90.000000
L 4.45188307 2.59278346 4.44878376 2.59355 1 P 0 ;0,1,2=270,3=90.000000
L 4.44878376 2.59355 4.44568258 2.59316673 1 P 0 ;0,1,2=270,3=90.000000
L 4.44568258 2.59316673 4.4430998 2.59163307 1 P 0 ;0,1,2=270,3=90.000000
L 4.4430998 2.59163307 4.43793327 2.58396663 1 P 0 ;0,1,2=270,3=90.000000
L 4.43793327 2.58396663 4.43431644 2.58051663 1 P 0 ;0,1,2=270,3=90.000000
L 4.43431644 2.58051663 4.42914892 2.57821644 1 P 0 ;0,1,2=270,3=90.000000
L 4.42914892 2.57821644 4.4245 2.5774499 1 P 0 ;0,1,2=270,3=90.000000
L 4.4245 2.5774499 4.4245 2.59355 1 P 0 ;0,1,2=270,3=90.000000
L 4.4555 2.61649961 4.45446683 2.61343287 1 P 0 ;0,1,2=270,3=90.000000
L 4.45446683 2.61343287 4.45188307 2.61113337 1 P 0 ;0,1,2=270,3=90.000000
L 4.45188307 2.61113337 4.44878376 2.6095997 1 P 0 ;0,1,2=270,3=90.000000
L 4.44878376 2.6095997 4.44464941 2.6084499 1 P 0 ;0,1,2=270,3=90.000000
L 4.44464941 2.6084499 4.43999951 2.60806663 1 P 0 ;0,1,2=270,3=90.000000
L 4.43999951 2.60806663 4.43534951 2.6084499 1 P 0 ;0,1,2=270,3=90.000000
L 4.43534951 2.6084499 4.43121614 2.6095997 1 P 0 ;0,1,2=270,3=90.000000
L 4.43121614 2.6095997 4.42811585 2.61113337 1 P 0 ;0,1,2=270,3=90.000000
L 4.42811585 2.61113337 4.42553307 2.61343287 1 P 0 ;0,1,2=270,3=90.000000
L 4.42553307 2.61343287 4.4245 2.61649961 1 P 0 ;0,1,2=270,3=90.000000
L 4.4245 2.61649961 4.42553307 2.61956634 1 P 0 ;0,1,2=270,3=90.000000
L 4.42553307 2.61956634 4.42811585 2.62186654 1 P 0 ;0,1,2=270,3=90.000000
L 4.42811585 2.62186654 4.43121614 2.6234002 1 P 0 ;0,1,2=270,3=90.000000
L 4.43121614 2.6234002 4.43534951 2.62455 1 P 0 ;0,1,2=270,3=90.000000
L 4.43534951 2.62455 4.43999951 2.62493327 1 P 0 ;0,1,2=270,3=90.000000
L 4.43999951 2.62493327 4.44464941 2.62455 1 P 0 ;0,1,2=270,3=90.000000
L 4.44464941 2.62455 4.44878376 2.6234002 1 P 0 ;0,1,2=270,3=90.000000
L 4.44878376 2.6234002 4.45188307 2.62186654 1 P 0 ;0,1,2=270,3=90.000000
L 4.45188307 2.62186654 4.45446683 2.61956634 1 P 0 ;0,1,2=270,3=90.000000
L 4.45446683 2.61956634 4.4555 2.61649961 1 P 0 ;0,1,2=270,3=90.000000
L 4.372 2.485 4.372 2.395 1 P 0 
L 4.328 2.395 4.328 2.485 1 P 0 
L 4.328 2.485 4.372 2.485 1 P 0 
L 4.372 2.395 4.328 2.395 1 P 0 
L 4.3345 2.53583317 4.3655 2.53583317 1 P 0 ;0,1,2=271,3=90.000000
L 4.3655 2.53583317 4.3655 2.54541654 1 P 0 ;0,1,2=271,3=90.000000
L 4.3655 2.54541654 4.36394931 2.54848327 1 P 0 ;0,1,2=271,3=90.000000
L 4.36394931 2.54848327 4.36188307 2.5504002 1 P 0 ;0,1,2=271,3=90.000000
L 4.36188307 2.5504002 4.3577497 2.55116673 1 P 0 ;0,1,2=271,3=90.000000
L 4.3577497 2.55116673 4.35361634 2.5504002 1 P 0 ;0,1,2=271,3=90.000000
L 4.35361634 2.5504002 4.35103356 2.5481 1 P 0 ;0,1,2=271,3=90.000000
L 4.35103356 2.5481 4.34948287 2.54541654 1 P 0 ;0,1,2=271,3=90.000000
L 4.34948287 2.54541654 4.34948287 2.53583317 1 P 0 ;0,1,2=271,3=90.000000
L 4.34948287 2.54541654 4.3345 2.55116673 1 P 0 ;0,1,2=271,3=90.000000
L 4.36033346 2.56721644 4.36343278 2.56951663 1 P 0 ;0,1,2=271,3=90.000000
L 4.36343278 2.56951663 4.36498337 2.5722001 1 P 0 ;0,1,2=271,3=90.000000
L 4.36498337 2.5722001 4.3655 2.57526683 1 P 0 ;0,1,2=271,3=90.000000
L 4.3655 2.57526683 4.36446683 2.5791 1 P 0 ;0,1,2=271,3=90.000000
L 4.36446683 2.5791 4.36188307 2.58178346 1 P 0 ;0,1,2=271,3=90.000000
L 4.36188307 2.58178346 4.35878376 2.58255 1 P 0 ;0,1,2=271,3=90.000000
L 4.35878376 2.58255 4.35568258 2.58216673 1 P 0 ;0,1,2=271,3=90.000000
L 4.35568258 2.58216673 4.3530998 2.58063307 1 P 0 ;0,1,2=271,3=90.000000
L 4.3530998 2.58063307 4.34793327 2.57296663 1 P 0 ;0,1,2=271,3=90.000000
L 4.34793327 2.57296663 4.34431644 2.56951663 1 P 0 ;0,1,2=271,3=90.000000
L 4.34431644 2.56951663 4.33914892 2.56721644 1 P 0 ;0,1,2=271,3=90.000000
L 4.33914892 2.56721644 4.3345 2.5664499 1 P 0 ;0,1,2=271,3=90.000000
L 4.3345 2.5664499 4.3345 2.58255 1 P 0 ;0,1,2=271,3=90.000000
L 4.3655 2.60549961 4.36446683 2.60243287 1 P 0 ;0,1,2=271,3=90.000000
L 4.36446683 2.60243287 4.36188307 2.60013337 1 P 0 ;0,1,2=271,3=90.000000
L 4.36188307 2.60013337 4.35878376 2.5985997 1 P 0 ;0,1,2=271,3=90.000000
L 4.35878376 2.5985997 4.35464941 2.5974499 1 P 0 ;0,1,2=271,3=90.000000
L 4.35464941 2.5974499 4.34999951 2.59706663 1 P 0 ;0,1,2=271,3=90.000000
L 4.34999951 2.59706663 4.34534951 2.5974499 1 P 0 ;0,1,2=271,3=90.000000
L 4.34534951 2.5974499 4.34121614 2.5985997 1 P 0 ;0,1,2=271,3=90.000000
L 4.34121614 2.5985997 4.33811585 2.60013337 1 P 0 ;0,1,2=271,3=90.000000
L 4.33811585 2.60013337 4.33553307 2.60243287 1 P 0 ;0,1,2=271,3=90.000000
L 4.33553307 2.60243287 4.3345 2.60549961 1 P 0 ;0,1,2=271,3=90.000000
L 4.3345 2.60549961 4.33553307 2.60856634 1 P 0 ;0,1,2=271,3=90.000000
L 4.33553307 2.60856634 4.33811585 2.61086654 1 P 0 ;0,1,2=271,3=90.000000
L 4.33811585 2.61086654 4.34121614 2.6124002 1 P 0 ;0,1,2=271,3=90.000000
L 4.34121614 2.6124002 4.34534951 2.61355 1 P 0 ;0,1,2=271,3=90.000000
L 4.34534951 2.61355 4.34999951 2.61393327 1 P 0 ;0,1,2=271,3=90.000000
L 4.34999951 2.61393327 4.35464941 2.61355 1 P 0 ;0,1,2=271,3=90.000000
L 4.35464941 2.61355 4.35878376 2.6124002 1 P 0 ;0,1,2=271,3=90.000000
L 4.35878376 2.6124002 4.36188307 2.61086654 1 P 0 ;0,1,2=271,3=90.000000
L 4.36188307 2.61086654 4.36446683 2.60856634 1 P 0 ;0,1,2=271,3=90.000000
L 4.36446683 2.60856634 4.3655 2.60549961 1 P 0 ;0,1,2=271,3=90.000000
L 4.3345 2.63573307 4.34121614 2.63649961 1 P 0 ;0,1,2=271,3=90.000000
L 4.34121614 2.63649961 4.34689921 2.6376501 1 P 0 ;0,1,2=271,3=90.000000
L 4.34689921 2.6376501 4.35206663 2.63918307 1 P 0 ;0,1,2=271,3=90.000000
L 4.35206663 2.63918307 4.3577497 2.6411 1 P 0 ;0,1,2=271,3=90.000000
L 4.3577497 2.6411 4.3655 2.64416673 1 P 0 ;0,1,2=271,3=90.000000
L 4.3655 2.64416673 4.3655 2.62883317 1 P 0 ;0,1,2=271,3=90.000000
L 4.939 2.752 4.983 2.752 1 P 0 
L 4.939 2.662 4.939 2.752 1 P 0 
L 4.983 2.752 4.983 2.662 1 P 0 
L 4.983 2.662 4.939 2.662 1 P 0 
L 4.8945 2.58583317 4.9255 2.58583317 1 P 0 ;0,1,2=272,3=90.000000
L 4.9255 2.58583317 4.9255 2.59541654 1 P 0 ;0,1,2=272,3=90.000000
L 4.9255 2.59541654 4.92394931 2.59848327 1 P 0 ;0,1,2=272,3=90.000000
L 4.92394931 2.59848327 4.92188307 2.6004002 1 P 0 ;0,1,2=272,3=90.000000
L 4.92188307 2.6004002 4.9177497 2.60116673 1 P 0 ;0,1,2=272,3=90.000000
L 4.9177497 2.60116673 4.91361634 2.6004002 1 P 0 ;0,1,2=272,3=90.000000
L 4.91361634 2.6004002 4.91103356 2.5981 1 P 0 ;0,1,2=272,3=90.000000
L 4.91103356 2.5981 4.90948287 2.59541654 1 P 0 ;0,1,2=272,3=90.000000
L 4.90948287 2.59541654 4.90948287 2.58583317 1 P 0 ;0,1,2=272,3=90.000000
L 4.90948287 2.59541654 4.8945 2.60116673 1 P 0 ;0,1,2=272,3=90.000000
L 4.8945 2.62449961 4.9255 2.62449961 1 P 0 ;0,1,2=272,3=90.000000
L 4.9255 2.62449961 4.9193003 2.6198999 1 P 0 ;0,1,2=272,3=90.000000
L 4.8945 2.6198999 4.8945 2.62909931 1 P 0 ;0,1,2=272,3=90.000000
L 4.8945 2.65473307 4.90121614 2.65549961 1 P 0 ;0,1,2=272,3=90.000000
L 4.90121614 2.65549961 4.90689921 2.6566501 1 P 0 ;0,1,2=272,3=90.000000
L 4.90689921 2.6566501 4.91206663 2.65818307 1 P 0 ;0,1,2=272,3=90.000000
L 4.91206663 2.65818307 4.9177497 2.6601 1 P 0 ;0,1,2=272,3=90.000000
L 4.9177497 2.6601 4.9255 2.66316673 1 P 0 ;0,1,2=272,3=90.000000
L 4.9255 2.66316673 4.9255 2.64783317 1 P 0 ;0,1,2=272,3=90.000000
L 4.8945 2.6911 4.9255 2.6911 1 P 0 ;0,1,2=272,3=90.000000
L 4.9255 2.6911 4.90328327 2.67691624 1 P 0 ;0,1,2=272,3=90.000000
L 4.90328327 2.67691624 4.90328327 2.69608366 1 P 0 ;0,1,2=272,3=90.000000
L 4.42 3.887 4.42 3.843 1 P 0 
L 4.42 3.843 4.33 3.843 1 P 0 
L 4.33 3.843 4.33 3.887 1 P 0 
L 4.33 3.887 4.42 3.887 1 P 0 
L 4.43916683 3.7795 4.43916683 3.8105 1 P 0 ;0,1,2=273,3=0.000000
L 4.43916683 3.8105 4.42958346 3.8105 1 P 0 ;0,1,2=273,3=0.000000
L 4.42958346 3.8105 4.42651673 3.80894931 1 P 0 ;0,1,2=273,3=0.000000
L 4.42651673 3.80894931 4.4245998 3.80688307 1 P 0 ;0,1,2=273,3=0.000000
L 4.4245998 3.80688307 4.42383327 3.8027497 1 P 0 ;0,1,2=273,3=0.000000
L 4.42383327 3.8027497 4.4245998 3.79861634 1 P 0 ;0,1,2=273,3=0.000000
L 4.4245998 3.79861634 4.4269 3.79603356 1 P 0 ;0,1,2=273,3=0.000000
L 4.4269 3.79603356 4.42958346 3.79448287 1 P 0 ;0,1,2=273,3=0.000000
L 4.42958346 3.79448287 4.43916683 3.79448287 1 P 0 ;0,1,2=273,3=0.000000
L 4.42958346 3.79448287 4.42383327 3.7795 1 P 0 ;0,1,2=273,3=0.000000
L 4.40893337 3.78569961 4.40663386 3.78208278 1 P 0 ;0,1,2=273,3=0.000000
L 4.40663386 3.78208278 4.40356713 3.78001654 1 P 0 ;0,1,2=273,3=0.000000
L 4.40356713 3.78001654 4.40011644 3.7795 1 P 0 ;0,1,2=273,3=0.000000
L 4.40011644 3.7795 4.3970497 3.78001654 1 P 0 ;0,1,2=273,3=0.000000
L 4.3970497 3.78001654 4.39398297 3.78259931 1 P 0 ;0,1,2=273,3=0.000000
L 4.39398297 3.78259931 4.39206673 3.78569961 1 P 0 ;0,1,2=273,3=0.000000
L 4.39206673 3.78569961 4.39168346 3.7887999 1 P 0 ;0,1,2=273,3=0.000000
L 4.39168346 3.7887999 4.39245 3.79241575 1 P 0 ;0,1,2=273,3=0.000000
L 4.39245 3.79241575 4.39513346 3.79499951 1 P 0 ;0,1,2=273,3=0.000000
L 4.39513346 3.79499951 4.39781693 3.79603356 1 P 0 ;0,1,2=273,3=0.000000
L 4.39781693 3.79603356 4.40126693 3.79603356 1 P 0 ;0,1,2=273,3=0.000000
L 4.39781693 3.79603356 4.39551673 3.79758317 1 P 0 ;0,1,2=273,3=0.000000
L 4.39551673 3.79758317 4.3935998 3.80016594 1 P 0 ;0,1,2=273,3=0.000000
L 4.3935998 3.80016594 4.39283327 3.80326624 1 P 0 ;0,1,2=273,3=0.000000
L 4.39283327 3.80326624 4.3935998 3.80636654 1 P 0 ;0,1,2=273,3=0.000000
L 4.3935998 3.80636654 4.39551673 3.80894931 1 P 0 ;0,1,2=273,3=0.000000
L 4.39551673 3.80894931 4.39896673 3.8105 1 P 0 ;0,1,2=273,3=0.000000
L 4.39896673 3.8105 4.40241663 3.80998337 1 P 0 ;0,1,2=273,3=0.000000
L 4.40241663 3.80998337 4.40586663 3.80791624 1 P 0 ;0,1,2=273,3=0.000000
L 4.36950039 3.7795 4.36950039 3.8105 1 P 0 ;0,1,2=273,3=0.000000
L 4.36950039 3.8105 4.3741001 3.8043003 1 P 0 ;0,1,2=273,3=0.000000
L 4.3741001 3.7795 4.36490069 3.7795 1 P 0 ;0,1,2=273,3=0.000000
L 4.34501713 3.78311585 4.34233366 3.78053307 1 P 0 ;0,1,2=273,3=0.000000
L 4.34233366 3.78053307 4.33926693 3.7795 1 P 0 ;0,1,2=273,3=0.000000
L 4.33926693 3.7795 4.3362002 3.78053307 1 P 0 ;0,1,2=273,3=0.000000
L 4.3362002 3.78053307 4.33351673 3.78363238 1 P 0 ;0,1,2=273,3=0.000000
L 4.33351673 3.78363238 4.3315998 3.78828327 1 P 0 ;0,1,2=273,3=0.000000
L 4.3315998 3.78828327 4.33083327 3.79293327 1 P 0 ;0,1,2=273,3=0.000000
L 4.33083327 3.79293327 4.33083327 3.79861634 1 P 0 ;0,1,2=273,3=0.000000
L 4.33083327 3.79861634 4.3315998 3.80326624 1 P 0 ;0,1,2=273,3=0.000000
L 4.3315998 3.80326624 4.33351673 3.8073997 1 P 0 ;0,1,2=273,3=0.000000
L 4.33351673 3.8073997 4.33581693 3.80946683 1 P 0 ;0,1,2=273,3=0.000000
L 4.33581693 3.80946683 4.33850039 3.8105 1 P 0 ;0,1,2=273,3=0.000000
L 4.33850039 3.8105 4.34156713 3.80946683 1 P 0 ;0,1,2=273,3=0.000000
L 4.34156713 3.80946683 4.34386663 3.8073997 1 P 0 ;0,1,2=273,3=0.000000
L 4.34386663 3.8073997 4.3454003 3.8043003 1 P 0 ;0,1,2=273,3=0.000000
L 4.3454003 3.8043003 4.34616683 3.80016594 1 P 0 ;0,1,2=273,3=0.000000
L 4.34616683 3.80016594 4.3454003 3.7965501 1 P 0 ;0,1,2=273,3=0.000000
L 4.3454003 3.7965501 4.34348337 3.79293327 1 P 0 ;0,1,2=273,3=0.000000
L 4.34348337 3.79293327 4.34118317 3.79086604 1 P 0 ;0,1,2=273,3=0.000000
L 4.34118317 3.79086604 4.33850039 3.79034951 1 P 0 ;0,1,2=273,3=0.000000
L 4.33850039 3.79034951 4.33543366 3.79138268 1 P 0 ;0,1,2=273,3=0.000000
L 4.33543366 3.79138268 4.33313346 3.79396634 1 P 0 ;0,1,2=273,3=0.000000
L 4.33313346 3.79396634 4.33083327 3.79861634 1 P 0 ;0,1,2=273,3=0.000000
L 3.322 3.227 3.322 3.183 1 P 0 
L 3.232 3.227 3.322 3.227 1 P 0 
L 3.322 3.183 3.232 3.183 1 P 0 
L 3.232 3.183 3.232 3.227 1 P 0 
L 3.32416683 3.1045 3.32416683 3.1355 1 P 0 ;0,1,2=274,3=0.000000
L 3.32416683 3.1355 3.31458346 3.1355 1 P 0 ;0,1,2=274,3=0.000000
L 3.31458346 3.1355 3.31151673 3.13394931 1 P 0 ;0,1,2=274,3=0.000000
L 3.31151673 3.13394931 3.3095998 3.13188307 1 P 0 ;0,1,2=274,3=0.000000
L 3.3095998 3.13188307 3.30883327 3.1277497 1 P 0 ;0,1,2=274,3=0.000000
L 3.30883327 3.1277497 3.3095998 3.12361634 1 P 0 ;0,1,2=274,3=0.000000
L 3.3095998 3.12361634 3.3119 3.12103356 1 P 0 ;0,1,2=274,3=0.000000
L 3.3119 3.12103356 3.31458346 3.11948287 1 P 0 ;0,1,2=274,3=0.000000
L 3.31458346 3.11948287 3.32416683 3.11948287 1 P 0 ;0,1,2=274,3=0.000000
L 3.31458346 3.11948287 3.30883327 3.1045 1 P 0 ;0,1,2=274,3=0.000000
L 3.28550039 3.1045 3.28550039 3.1355 1 P 0 ;0,1,2=274,3=0.000000
L 3.28550039 3.1355 3.2901001 3.1293003 1 P 0 ;0,1,2=274,3=0.000000
L 3.2901001 3.1045 3.28090069 3.1045 1 P 0 ;0,1,2=274,3=0.000000
L 3.2499 3.1045 3.2499 3.1355 1 P 0 ;0,1,2=274,3=0.000000
L 3.2499 3.1355 3.26408376 3.11328327 1 P 0 ;0,1,2=274,3=0.000000
L 3.26408376 3.11328327 3.24491634 3.11328327 1 P 0 ;0,1,2=274,3=0.000000
L 3.23001713 3.10811585 3.22733366 3.10553307 1 P 0 ;0,1,2=274,3=0.000000
L 3.22733366 3.10553307 3.22426693 3.1045 1 P 0 ;0,1,2=274,3=0.000000
L 3.22426693 3.1045 3.2212002 3.10553307 1 P 0 ;0,1,2=274,3=0.000000
L 3.2212002 3.10553307 3.21851673 3.10863238 1 P 0 ;0,1,2=274,3=0.000000
L 3.21851673 3.10863238 3.2165998 3.11328327 1 P 0 ;0,1,2=274,3=0.000000
L 3.2165998 3.11328327 3.21583327 3.11793327 1 P 0 ;0,1,2=274,3=0.000000
L 3.21583327 3.11793327 3.21583327 3.12361634 1 P 0 ;0,1,2=274,3=0.000000
L 3.21583327 3.12361634 3.2165998 3.12826624 1 P 0 ;0,1,2=274,3=0.000000
L 3.2165998 3.12826624 3.21851673 3.1323997 1 P 0 ;0,1,2=274,3=0.000000
L 3.21851673 3.1323997 3.22081693 3.13446683 1 P 0 ;0,1,2=274,3=0.000000
L 3.22081693 3.13446683 3.22350039 3.1355 1 P 0 ;0,1,2=274,3=0.000000
L 3.22350039 3.1355 3.22656713 3.13446683 1 P 0 ;0,1,2=274,3=0.000000
L 3.22656713 3.13446683 3.22886663 3.1323997 1 P 0 ;0,1,2=274,3=0.000000
L 3.22886663 3.1323997 3.2304003 3.1293003 1 P 0 ;0,1,2=274,3=0.000000
L 3.2304003 3.1293003 3.23116683 3.12516594 1 P 0 ;0,1,2=274,3=0.000000
L 3.23116683 3.12516594 3.2304003 3.1215501 1 P 0 ;0,1,2=274,3=0.000000
L 3.2304003 3.1215501 3.22848337 3.11793327 1 P 0 ;0,1,2=274,3=0.000000
L 3.22848337 3.11793327 3.22618317 3.11586604 1 P 0 ;0,1,2=274,3=0.000000
L 3.22618317 3.11586604 3.22350039 3.11534951 1 P 0 ;0,1,2=274,3=0.000000
L 3.22350039 3.11534951 3.22043366 3.11638268 1 P 0 ;0,1,2=274,3=0.000000
L 3.22043366 3.11638268 3.21813346 3.11896634 1 P 0 ;0,1,2=274,3=0.000000
L 3.21813346 3.11896634 3.21583327 3.12361634 1 P 0 ;0,1,2=274,3=0.000000
L 3.322 3.452 3.322 3.408 1 P 0 
L 3.232 3.452 3.322 3.452 1 P 0 
L 3.322 3.408 3.232 3.408 1 P 0 
L 3.232 3.408 3.232 3.452 1 P 0 
L 3.30416683 3.6295 3.30416683 3.6605 1 P 0 ;0,1,2=275,3=0.000000
L 3.30416683 3.6605 3.29458346 3.6605 1 P 0 ;0,1,2=275,3=0.000000
L 3.29458346 3.6605 3.29151673 3.65894931 1 P 0 ;0,1,2=275,3=0.000000
L 3.29151673 3.65894931 3.2895998 3.65688307 1 P 0 ;0,1,2=275,3=0.000000
L 3.2895998 3.65688307 3.28883327 3.6527497 1 P 0 ;0,1,2=275,3=0.000000
L 3.28883327 3.6527497 3.2895998 3.64861634 1 P 0 ;0,1,2=275,3=0.000000
L 3.2895998 3.64861634 3.2919 3.64603356 1 P 0 ;0,1,2=275,3=0.000000
L 3.2919 3.64603356 3.29458346 3.64448287 1 P 0 ;0,1,2=275,3=0.000000
L 3.29458346 3.64448287 3.30416683 3.64448287 1 P 0 ;0,1,2=275,3=0.000000
L 3.29458346 3.64448287 3.28883327 3.6295 1 P 0 ;0,1,2=275,3=0.000000
L 3.26550039 3.6295 3.26550039 3.6605 1 P 0 ;0,1,2=275,3=0.000000
L 3.26550039 3.6605 3.2701001 3.6543003 1 P 0 ;0,1,2=275,3=0.000000
L 3.2701001 3.6295 3.26090069 3.6295 1 P 0 ;0,1,2=275,3=0.000000
L 3.24293337 3.63414892 3.24063386 3.63156614 1 P 0 ;0,1,2=275,3=0.000000
L 3.24063386 3.63156614 3.23795039 3.63001654 1 P 0 ;0,1,2=275,3=0.000000
L 3.23795039 3.63001654 3.23450039 3.6295 1 P 0 ;0,1,2=275,3=0.000000
L 3.23450039 3.6295 3.2310497 3.63053307 1 P 0 ;0,1,2=275,3=0.000000
L 3.2310497 3.63053307 3.22836693 3.63259931 1 P 0 ;0,1,2=275,3=0.000000
L 3.22836693 3.63259931 3.22645 3.63621614 1 P 0 ;0,1,2=275,3=0.000000
L 3.22645 3.63621614 3.22606673 3.64034951 1 P 0 ;0,1,2=275,3=0.000000
L 3.22606673 3.64034951 3.22683327 3.64448287 1 P 0 ;0,1,2=275,3=0.000000
L 3.22683327 3.64448287 3.2287502 3.64706663 1 P 0 ;0,1,2=275,3=0.000000
L 3.2287502 3.64706663 3.23143366 3.64913287 1 P 0 ;0,1,2=275,3=0.000000
L 3.23143366 3.64913287 3.23411644 3.64964941 1 P 0 ;0,1,2=275,3=0.000000
L 3.23411644 3.64964941 3.2367999 3.64913287 1 P 0 ;0,1,2=275,3=0.000000
L 3.2367999 3.64913287 3.2402499 3.64706663 1 P 0 ;0,1,2=275,3=0.000000
L 3.2402499 3.64706663 3.2391001 3.6605 1 P 0 ;0,1,2=275,3=0.000000
L 3.2391001 3.6605 3.2287502 3.6605 1 P 0 ;0,1,2=275,3=0.000000
L 3.21193337 3.63414892 3.20963386 3.63156614 1 P 0 ;0,1,2=275,3=0.000000
L 3.20963386 3.63156614 3.20695039 3.63001654 1 P 0 ;0,1,2=275,3=0.000000
L 3.20695039 3.63001654 3.20350039 3.6295 1 P 0 ;0,1,2=275,3=0.000000
L 3.20350039 3.6295 3.2000497 3.63053307 1 P 0 ;0,1,2=275,3=0.000000
L 3.2000497 3.63053307 3.19736693 3.63259931 1 P 0 ;0,1,2=275,3=0.000000
L 3.19736693 3.63259931 3.19545 3.63621614 1 P 0 ;0,1,2=275,3=0.000000
L 3.19545 3.63621614 3.19506673 3.64034951 1 P 0 ;0,1,2=275,3=0.000000
L 3.19506673 3.64034951 3.19583327 3.64448287 1 P 0 ;0,1,2=275,3=0.000000
L 3.19583327 3.64448287 3.1977502 3.64706663 1 P 0 ;0,1,2=275,3=0.000000
L 3.1977502 3.64706663 3.20043366 3.64913287 1 P 0 ;0,1,2=275,3=0.000000
L 3.20043366 3.64913287 3.20311644 3.64964941 1 P 0 ;0,1,2=275,3=0.000000
L 3.20311644 3.64964941 3.2057999 3.64913287 1 P 0 ;0,1,2=275,3=0.000000
L 3.2057999 3.64913287 3.2092499 3.64706663 1 P 0 ;0,1,2=275,3=0.000000
L 3.2092499 3.64706663 3.2081001 3.6605 1 P 0 ;0,1,2=275,3=0.000000
L 3.2081001 3.6605 3.1977502 3.6605 1 P 0 ;0,1,2=275,3=0.000000
L 3.322 3.272 3.322 3.228 1 P 0 
L 3.232 3.272 3.322 3.272 1 P 0 
L 3.322 3.228 3.232 3.228 1 P 0 
L 3.232 3.228 3.232 3.272 1 P 0 
L 3.32416683 3.1445 3.32416683 3.1755 1 P 0 ;0,1,2=276,3=0.000000
L 3.32416683 3.1755 3.31458346 3.1755 1 P 0 ;0,1,2=276,3=0.000000
L 3.31458346 3.1755 3.31151673 3.17394931 1 P 0 ;0,1,2=276,3=0.000000
L 3.31151673 3.17394931 3.3095998 3.17188307 1 P 0 ;0,1,2=276,3=0.000000
L 3.3095998 3.17188307 3.30883327 3.1677497 1 P 0 ;0,1,2=276,3=0.000000
L 3.30883327 3.1677497 3.3095998 3.16361634 1 P 0 ;0,1,2=276,3=0.000000
L 3.3095998 3.16361634 3.3119 3.16103356 1 P 0 ;0,1,2=276,3=0.000000
L 3.3119 3.16103356 3.31458346 3.15948287 1 P 0 ;0,1,2=276,3=0.000000
L 3.31458346 3.15948287 3.32416683 3.15948287 1 P 0 ;0,1,2=276,3=0.000000
L 3.31458346 3.15948287 3.30883327 3.1445 1 P 0 ;0,1,2=276,3=0.000000
L 3.28550039 3.1445 3.28550039 3.1755 1 P 0 ;0,1,2=276,3=0.000000
L 3.28550039 3.1755 3.2901001 3.1693003 1 P 0 ;0,1,2=276,3=0.000000
L 3.2901001 3.1445 3.28090069 3.1445 1 P 0 ;0,1,2=276,3=0.000000
L 3.26293337 3.14914892 3.26063386 3.14656614 1 P 0 ;0,1,2=276,3=0.000000
L 3.26063386 3.14656614 3.25795039 3.14501654 1 P 0 ;0,1,2=276,3=0.000000
L 3.25795039 3.14501654 3.25450039 3.1445 1 P 0 ;0,1,2=276,3=0.000000
L 3.25450039 3.1445 3.2510497 3.14553307 1 P 0 ;0,1,2=276,3=0.000000
L 3.2510497 3.14553307 3.24836693 3.14759931 1 P 0 ;0,1,2=276,3=0.000000
L 3.24836693 3.14759931 3.24645 3.15121614 1 P 0 ;0,1,2=276,3=0.000000
L 3.24645 3.15121614 3.24606673 3.15534951 1 P 0 ;0,1,2=276,3=0.000000
L 3.24606673 3.15534951 3.24683327 3.15948287 1 P 0 ;0,1,2=276,3=0.000000
L 3.24683327 3.15948287 3.2487502 3.16206663 1 P 0 ;0,1,2=276,3=0.000000
L 3.2487502 3.16206663 3.25143366 3.16413287 1 P 0 ;0,1,2=276,3=0.000000
L 3.25143366 3.16413287 3.25411644 3.16464941 1 P 0 ;0,1,2=276,3=0.000000
L 3.25411644 3.16464941 3.2567999 3.16413287 1 P 0 ;0,1,2=276,3=0.000000
L 3.2567999 3.16413287 3.2602499 3.16206663 1 P 0 ;0,1,2=276,3=0.000000
L 3.2602499 3.16206663 3.2591001 3.1755 1 P 0 ;0,1,2=276,3=0.000000
L 3.2591001 3.1755 3.2487502 3.1755 1 P 0 ;0,1,2=276,3=0.000000
L 3.23078356 3.17033346 3.22848337 3.17343278 1 P 0 ;0,1,2=276,3=0.000000
L 3.22848337 3.17343278 3.2257999 3.17498337 1 P 0 ;0,1,2=276,3=0.000000
L 3.2257999 3.17498337 3.22273317 3.1755 1 P 0 ;0,1,2=276,3=0.000000
L 3.22273317 3.1755 3.2189 3.17446683 1 P 0 ;0,1,2=276,3=0.000000
L 3.2189 3.17446683 3.21621654 3.17188307 1 P 0 ;0,1,2=276,3=0.000000
L 3.21621654 3.17188307 3.21545 3.16878376 1 P 0 ;0,1,2=276,3=0.000000
L 3.21545 3.16878376 3.21583327 3.16568258 1 P 0 ;0,1,2=276,3=0.000000
L 3.21583327 3.16568258 3.21736693 3.1630998 1 P 0 ;0,1,2=276,3=0.000000
L 3.21736693 3.1630998 3.22503337 3.15793327 1 P 0 ;0,1,2=276,3=0.000000
L 3.22503337 3.15793327 3.22848337 3.15431644 1 P 0 ;0,1,2=276,3=0.000000
L 3.22848337 3.15431644 3.23078356 3.14914892 1 P 0 ;0,1,2=276,3=0.000000
L 3.23078356 3.14914892 3.2315501 3.1445 1 P 0 ;0,1,2=276,3=0.000000
L 3.2315501 3.1445 3.21545 3.1445 1 P 0 ;0,1,2=276,3=0.000000
L 3.322 3.407 3.322 3.363 1 P 0 
L 3.232 3.407 3.322 3.407 1 P 0 
L 3.322 3.363 3.232 3.363 1 P 0 
L 3.232 3.363 3.232 3.407 1 P 0 
L 3.30416683 3.5895 3.30416683 3.6205 1 P 0 ;0,1,2=277,3=0.000000
L 3.30416683 3.6205 3.29458346 3.6205 1 P 0 ;0,1,2=277,3=0.000000
L 3.29458346 3.6205 3.29151673 3.61894931 1 P 0 ;0,1,2=277,3=0.000000
L 3.29151673 3.61894931 3.2895998 3.61688307 1 P 0 ;0,1,2=277,3=0.000000
L 3.2895998 3.61688307 3.28883327 3.6127497 1 P 0 ;0,1,2=277,3=0.000000
L 3.28883327 3.6127497 3.2895998 3.60861634 1 P 0 ;0,1,2=277,3=0.000000
L 3.2895998 3.60861634 3.2919 3.60603356 1 P 0 ;0,1,2=277,3=0.000000
L 3.2919 3.60603356 3.29458346 3.60448287 1 P 0 ;0,1,2=277,3=0.000000
L 3.29458346 3.60448287 3.30416683 3.60448287 1 P 0 ;0,1,2=277,3=0.000000
L 3.29458346 3.60448287 3.28883327 3.5895 1 P 0 ;0,1,2=277,3=0.000000
L 3.26550039 3.5895 3.26550039 3.6205 1 P 0 ;0,1,2=277,3=0.000000
L 3.26550039 3.6205 3.2701001 3.6143003 1 P 0 ;0,1,2=277,3=0.000000
L 3.2701001 3.5895 3.26090069 3.5895 1 P 0 ;0,1,2=277,3=0.000000
L 3.2299 3.5895 3.2299 3.6205 1 P 0 ;0,1,2=277,3=0.000000
L 3.2299 3.6205 3.24408376 3.59828327 1 P 0 ;0,1,2=277,3=0.000000
L 3.24408376 3.59828327 3.22491634 3.59828327 1 P 0 ;0,1,2=277,3=0.000000
L 3.21078356 3.60241575 3.2081001 3.60603356 1 P 0 ;0,1,2=277,3=0.000000
L 3.2081001 3.60603356 3.2057999 3.6080998 1 P 0 ;0,1,2=277,3=0.000000
L 3.2057999 3.6080998 3.20273317 3.60913287 1 P 0 ;0,1,2=277,3=0.000000
L 3.20273317 3.60913287 3.2000497 3.6080998 1 P 0 ;0,1,2=277,3=0.000000
L 3.2000497 3.6080998 3.19813346 3.60603356 1 P 0 ;0,1,2=277,3=0.000000
L 3.19813346 3.60603356 3.1965998 3.60293327 1 P 0 ;0,1,2=277,3=0.000000
L 3.1965998 3.60293327 3.19621654 3.59931644 1 P 0 ;0,1,2=277,3=0.000000
L 3.19621654 3.59931644 3.1965998 3.59621614 1 P 0 ;0,1,2=277,3=0.000000
L 3.1965998 3.59621614 3.19813346 3.59311585 1 P 0 ;0,1,2=277,3=0.000000
L 3.19813346 3.59311585 3.20043366 3.59053307 1 P 0 ;0,1,2=277,3=0.000000
L 3.20043366 3.59053307 3.20311644 3.5895 1 P 0 ;0,1,2=277,3=0.000000
L 3.20311644 3.5895 3.20618317 3.59053307 1 P 0 ;0,1,2=277,3=0.000000
L 3.20618317 3.59053307 3.20886663 3.59363238 1 P 0 ;0,1,2=277,3=0.000000
L 3.20886663 3.59363238 3.2104003 3.59828327 1 P 0 ;0,1,2=277,3=0.000000
L 3.2104003 3.59828327 3.21078356 3.6034498 1 P 0 ;0,1,2=277,3=0.000000
L 3.21078356 3.6034498 3.21001713 3.61016594 1 P 0 ;0,1,2=277,3=0.000000
L 3.21001713 3.61016594 3.20886663 3.61378376 1 P 0 ;0,1,2=277,3=0.000000
L 3.20886663 3.61378376 3.20695039 3.6173997 1 P 0 ;0,1,2=277,3=0.000000
L 3.20695039 3.6173997 3.20426693 3.61998337 1 P 0 ;0,1,2=277,3=0.000000
L 3.20426693 3.61998337 3.20158346 3.6205 1 P 0 ;0,1,2=277,3=0.000000
L 3.20158346 3.6205 3.1989 3.61946683 1 P 0 ;0,1,2=277,3=0.000000
L 3.1989 3.61946683 3.19698297 3.61688307 1 P 0 ;0,1,2=277,3=0.000000
L 3.322 3.362 3.322 3.318 1 P 0 
L 3.232 3.362 3.322 3.362 1 P 0 
L 3.322 3.318 3.232 3.318 1 P 0 
L 3.232 3.318 3.232 3.362 1 P 0 
L 3.30416683 3.5495 3.30416683 3.5805 1 P 0 ;0,1,2=278,3=0.000000
L 3.30416683 3.5805 3.29458346 3.5805 1 P 0 ;0,1,2=278,3=0.000000
L 3.29458346 3.5805 3.29151673 3.57894931 1 P 0 ;0,1,2=278,3=0.000000
L 3.29151673 3.57894931 3.2895998 3.57688307 1 P 0 ;0,1,2=278,3=0.000000
L 3.2895998 3.57688307 3.28883327 3.5727497 1 P 0 ;0,1,2=278,3=0.000000
L 3.28883327 3.5727497 3.2895998 3.56861634 1 P 0 ;0,1,2=278,3=0.000000
L 3.2895998 3.56861634 3.2919 3.56603356 1 P 0 ;0,1,2=278,3=0.000000
L 3.2919 3.56603356 3.29458346 3.56448287 1 P 0 ;0,1,2=278,3=0.000000
L 3.29458346 3.56448287 3.30416683 3.56448287 1 P 0 ;0,1,2=278,3=0.000000
L 3.29458346 3.56448287 3.28883327 3.5495 1 P 0 ;0,1,2=278,3=0.000000
L 3.26550039 3.5495 3.26550039 3.5805 1 P 0 ;0,1,2=278,3=0.000000
L 3.26550039 3.5805 3.2701001 3.5743003 1 P 0 ;0,1,2=278,3=0.000000
L 3.2701001 3.5495 3.26090069 3.5495 1 P 0 ;0,1,2=278,3=0.000000
L 3.24293337 3.55414892 3.24063386 3.55156614 1 P 0 ;0,1,2=278,3=0.000000
L 3.24063386 3.55156614 3.23795039 3.55001654 1 P 0 ;0,1,2=278,3=0.000000
L 3.23795039 3.55001654 3.23450039 3.5495 1 P 0 ;0,1,2=278,3=0.000000
L 3.23450039 3.5495 3.2310497 3.55053307 1 P 0 ;0,1,2=278,3=0.000000
L 3.2310497 3.55053307 3.22836693 3.55259931 1 P 0 ;0,1,2=278,3=0.000000
L 3.22836693 3.55259931 3.22645 3.55621614 1 P 0 ;0,1,2=278,3=0.000000
L 3.22645 3.55621614 3.22606673 3.56034951 1 P 0 ;0,1,2=278,3=0.000000
L 3.22606673 3.56034951 3.22683327 3.56448287 1 P 0 ;0,1,2=278,3=0.000000
L 3.22683327 3.56448287 3.2287502 3.56706663 1 P 0 ;0,1,2=278,3=0.000000
L 3.2287502 3.56706663 3.23143366 3.56913287 1 P 0 ;0,1,2=278,3=0.000000
L 3.23143366 3.56913287 3.23411644 3.56964941 1 P 0 ;0,1,2=278,3=0.000000
L 3.23411644 3.56964941 3.2367999 3.56913287 1 P 0 ;0,1,2=278,3=0.000000
L 3.2367999 3.56913287 3.2402499 3.56706663 1 P 0 ;0,1,2=278,3=0.000000
L 3.2402499 3.56706663 3.2391001 3.5805 1 P 0 ;0,1,2=278,3=0.000000
L 3.2391001 3.5805 3.2287502 3.5805 1 P 0 ;0,1,2=278,3=0.000000
L 3.20350039 3.5805 3.20656713 3.57946683 1 P 0 ;0,1,2=278,3=0.000000
L 3.20656713 3.57946683 3.20886663 3.57688307 1 P 0 ;0,1,2=278,3=0.000000
L 3.20886663 3.57688307 3.2104003 3.57378376 1 P 0 ;0,1,2=278,3=0.000000
L 3.2104003 3.57378376 3.2115501 3.56964941 1 P 0 ;0,1,2=278,3=0.000000
L 3.2115501 3.56964941 3.21193337 3.56499951 1 P 0 ;0,1,2=278,3=0.000000
L 3.21193337 3.56499951 3.2115501 3.56034951 1 P 0 ;0,1,2=278,3=0.000000
L 3.2115501 3.56034951 3.2104003 3.55621614 1 P 0 ;0,1,2=278,3=0.000000
L 3.2104003 3.55621614 3.20886663 3.55311585 1 P 0 ;0,1,2=278,3=0.000000
L 3.20886663 3.55311585 3.20656713 3.55053307 1 P 0 ;0,1,2=278,3=0.000000
L 3.20656713 3.55053307 3.20350039 3.5495 1 P 0 ;0,1,2=278,3=0.000000
L 3.20350039 3.5495 3.20043366 3.55053307 1 P 0 ;0,1,2=278,3=0.000000
L 3.20043366 3.55053307 3.19813346 3.55311585 1 P 0 ;0,1,2=278,3=0.000000
L 3.19813346 3.55311585 3.1965998 3.55621614 1 P 0 ;0,1,2=278,3=0.000000
L 3.1965998 3.55621614 3.19545 3.56034951 1 P 0 ;0,1,2=278,3=0.000000
L 3.19545 3.56034951 3.19506673 3.56499951 1 P 0 ;0,1,2=278,3=0.000000
L 3.19506673 3.56499951 3.19545 3.56964941 1 P 0 ;0,1,2=278,3=0.000000
L 3.19545 3.56964941 3.1965998 3.57378376 1 P 0 ;0,1,2=278,3=0.000000
L 3.1965998 3.57378376 3.19813346 3.57688307 1 P 0 ;0,1,2=278,3=0.000000
L 3.19813346 3.57688307 3.20043366 3.57946683 1 P 0 ;0,1,2=278,3=0.000000
L 3.20043366 3.57946683 3.20350039 3.5805 1 P 0 ;0,1,2=278,3=0.000000
L 3.322 3.317 3.322 3.273 1 P 0 
L 3.232 3.317 3.322 3.317 1 P 0 
L 3.322 3.273 3.232 3.273 1 P 0 
L 3.232 3.273 3.232 3.317 1 P 0 
L 3.30416683 3.5045 3.30416683 3.5355 1 P 0 ;0,1,2=279,3=0.000000
L 3.30416683 3.5355 3.29458346 3.5355 1 P 0 ;0,1,2=279,3=0.000000
L 3.29458346 3.5355 3.29151673 3.53394931 1 P 0 ;0,1,2=279,3=0.000000
L 3.29151673 3.53394931 3.2895998 3.53188307 1 P 0 ;0,1,2=279,3=0.000000
L 3.2895998 3.53188307 3.28883327 3.5277497 1 P 0 ;0,1,2=279,3=0.000000
L 3.28883327 3.5277497 3.2895998 3.52361634 1 P 0 ;0,1,2=279,3=0.000000
L 3.2895998 3.52361634 3.2919 3.52103356 1 P 0 ;0,1,2=279,3=0.000000
L 3.2919 3.52103356 3.29458346 3.51948287 1 P 0 ;0,1,2=279,3=0.000000
L 3.29458346 3.51948287 3.30416683 3.51948287 1 P 0 ;0,1,2=279,3=0.000000
L 3.29458346 3.51948287 3.28883327 3.5045 1 P 0 ;0,1,2=279,3=0.000000
L 3.26550039 3.5045 3.26550039 3.5355 1 P 0 ;0,1,2=279,3=0.000000
L 3.26550039 3.5355 3.2701001 3.5293003 1 P 0 ;0,1,2=279,3=0.000000
L 3.2701001 3.5045 3.26090069 3.5045 1 P 0 ;0,1,2=279,3=0.000000
L 3.24293337 3.50914892 3.24063386 3.50656614 1 P 0 ;0,1,2=279,3=0.000000
L 3.24063386 3.50656614 3.23795039 3.50501654 1 P 0 ;0,1,2=279,3=0.000000
L 3.23795039 3.50501654 3.23450039 3.5045 1 P 0 ;0,1,2=279,3=0.000000
L 3.23450039 3.5045 3.2310497 3.50553307 1 P 0 ;0,1,2=279,3=0.000000
L 3.2310497 3.50553307 3.22836693 3.50759931 1 P 0 ;0,1,2=279,3=0.000000
L 3.22836693 3.50759931 3.22645 3.51121614 1 P 0 ;0,1,2=279,3=0.000000
L 3.22645 3.51121614 3.22606673 3.51534951 1 P 0 ;0,1,2=279,3=0.000000
L 3.22606673 3.51534951 3.22683327 3.51948287 1 P 0 ;0,1,2=279,3=0.000000
L 3.22683327 3.51948287 3.2287502 3.52206663 1 P 0 ;0,1,2=279,3=0.000000
L 3.2287502 3.52206663 3.23143366 3.52413287 1 P 0 ;0,1,2=279,3=0.000000
L 3.23143366 3.52413287 3.23411644 3.52464941 1 P 0 ;0,1,2=279,3=0.000000
L 3.23411644 3.52464941 3.2367999 3.52413287 1 P 0 ;0,1,2=279,3=0.000000
L 3.2367999 3.52413287 3.2402499 3.52206663 1 P 0 ;0,1,2=279,3=0.000000
L 3.2402499 3.52206663 3.2391001 3.5355 1 P 0 ;0,1,2=279,3=0.000000
L 3.2391001 3.5355 3.2287502 3.5355 1 P 0 ;0,1,2=279,3=0.000000
L 3.21193337 3.51069961 3.20963386 3.50708278 1 P 0 ;0,1,2=279,3=0.000000
L 3.20963386 3.50708278 3.20656713 3.50501654 1 P 0 ;0,1,2=279,3=0.000000
L 3.20656713 3.50501654 3.20311644 3.5045 1 P 0 ;0,1,2=279,3=0.000000
L 3.20311644 3.5045 3.2000497 3.50501654 1 P 0 ;0,1,2=279,3=0.000000
L 3.2000497 3.50501654 3.19698297 3.50759931 1 P 0 ;0,1,2=279,3=0.000000
L 3.19698297 3.50759931 3.19506673 3.51069961 1 P 0 ;0,1,2=279,3=0.000000
L 3.19506673 3.51069961 3.19468346 3.5137999 1 P 0 ;0,1,2=279,3=0.000000
L 3.19468346 3.5137999 3.19545 3.51741575 1 P 0 ;0,1,2=279,3=0.000000
L 3.19545 3.51741575 3.19813346 3.51999951 1 P 0 ;0,1,2=279,3=0.000000
L 3.19813346 3.51999951 3.20081693 3.52103356 1 P 0 ;0,1,2=279,3=0.000000
L 3.20081693 3.52103356 3.20426693 3.52103356 1 P 0 ;0,1,2=279,3=0.000000
L 3.20081693 3.52103356 3.19851673 3.52258317 1 P 0 ;0,1,2=279,3=0.000000
L 3.19851673 3.52258317 3.1965998 3.52516594 1 P 0 ;0,1,2=279,3=0.000000
L 3.1965998 3.52516594 3.19583327 3.52826624 1 P 0 ;0,1,2=279,3=0.000000
L 3.19583327 3.52826624 3.1965998 3.53136654 1 P 0 ;0,1,2=279,3=0.000000
L 3.1965998 3.53136654 3.19851673 3.53394931 1 P 0 ;0,1,2=279,3=0.000000
L 3.19851673 3.53394931 3.20196673 3.5355 1 P 0 ;0,1,2=279,3=0.000000
L 3.20196673 3.5355 3.20541663 3.53498337 1 P 0 ;0,1,2=279,3=0.000000
L 3.20541663 3.53498337 3.20886663 3.53291624 1 P 0 ;0,1,2=279,3=0.000000
L 3.322 3.497 3.322 3.453 1 P 0 
L 3.232 3.497 3.322 3.497 1 P 0 
L 3.322 3.453 3.232 3.453 1 P 0 
L 3.232 3.453 3.232 3.497 1 P 0 
L 3.30366683 3.6695 3.30366683 3.7005 1 P 0 ;0,1,2=280,3=0.000000
L 3.30366683 3.7005 3.29408346 3.7005 1 P 0 ;0,1,2=280,3=0.000000
L 3.29408346 3.7005 3.29101673 3.69894931 1 P 0 ;0,1,2=280,3=0.000000
L 3.29101673 3.69894931 3.2890998 3.69688307 1 P 0 ;0,1,2=280,3=0.000000
L 3.2890998 3.69688307 3.28833327 3.6927497 1 P 0 ;0,1,2=280,3=0.000000
L 3.28833327 3.6927497 3.2890998 3.68861634 1 P 0 ;0,1,2=280,3=0.000000
L 3.2890998 3.68861634 3.2914 3.68603356 1 P 0 ;0,1,2=280,3=0.000000
L 3.2914 3.68603356 3.29408346 3.68448287 1 P 0 ;0,1,2=280,3=0.000000
L 3.29408346 3.68448287 3.30366683 3.68448287 1 P 0 ;0,1,2=280,3=0.000000
L 3.29408346 3.68448287 3.28833327 3.6695 1 P 0 ;0,1,2=280,3=0.000000
L 3.27228356 3.68241575 3.2696001 3.68603356 1 P 0 ;0,1,2=280,3=0.000000
L 3.2696001 3.68603356 3.2672999 3.6880998 1 P 0 ;0,1,2=280,3=0.000000
L 3.2672999 3.6880998 3.26423317 3.68913287 1 P 0 ;0,1,2=280,3=0.000000
L 3.26423317 3.68913287 3.2615497 3.6880998 1 P 0 ;0,1,2=280,3=0.000000
L 3.2615497 3.6880998 3.25963346 3.68603356 1 P 0 ;0,1,2=280,3=0.000000
L 3.25963346 3.68603356 3.2580998 3.68293327 1 P 0 ;0,1,2=280,3=0.000000
L 3.2580998 3.68293327 3.25771654 3.67931644 1 P 0 ;0,1,2=280,3=0.000000
L 3.25771654 3.67931644 3.2580998 3.67621614 1 P 0 ;0,1,2=280,3=0.000000
L 3.2580998 3.67621614 3.25963346 3.67311585 1 P 0 ;0,1,2=280,3=0.000000
L 3.25963346 3.67311585 3.26193366 3.67053307 1 P 0 ;0,1,2=280,3=0.000000
L 3.26193366 3.67053307 3.26461644 3.6695 1 P 0 ;0,1,2=280,3=0.000000
L 3.26461644 3.6695 3.26768317 3.67053307 1 P 0 ;0,1,2=280,3=0.000000
L 3.26768317 3.67053307 3.27036663 3.67363238 1 P 0 ;0,1,2=280,3=0.000000
L 3.27036663 3.67363238 3.2719003 3.67828327 1 P 0 ;0,1,2=280,3=0.000000
L 3.2719003 3.67828327 3.27228356 3.6834498 1 P 0 ;0,1,2=280,3=0.000000
L 3.27228356 3.6834498 3.27151713 3.69016594 1 P 0 ;0,1,2=280,3=0.000000
L 3.27151713 3.69016594 3.27036663 3.69378376 1 P 0 ;0,1,2=280,3=0.000000
L 3.27036663 3.69378376 3.26845039 3.6973997 1 P 0 ;0,1,2=280,3=0.000000
L 3.26845039 3.6973997 3.26576693 3.69998337 1 P 0 ;0,1,2=280,3=0.000000
L 3.26576693 3.69998337 3.26308346 3.7005 1 P 0 ;0,1,2=280,3=0.000000
L 3.26308346 3.7005 3.2604 3.69946683 1 P 0 ;0,1,2=280,3=0.000000
L 3.2604 3.69946683 3.25848297 3.69688307 1 P 0 ;0,1,2=280,3=0.000000
L 3.23400039 3.7005 3.23706713 3.69946683 1 P 0 ;0,1,2=280,3=0.000000
L 3.23706713 3.69946683 3.23936663 3.69688307 1 P 0 ;0,1,2=280,3=0.000000
L 3.23936663 3.69688307 3.2409003 3.69378376 1 P 0 ;0,1,2=280,3=0.000000
L 3.2409003 3.69378376 3.2420501 3.68964941 1 P 0 ;0,1,2=280,3=0.000000
L 3.2420501 3.68964941 3.24243337 3.68499951 1 P 0 ;0,1,2=280,3=0.000000
L 3.24243337 3.68499951 3.2420501 3.68034951 1 P 0 ;0,1,2=280,3=0.000000
L 3.2420501 3.68034951 3.2409003 3.67621614 1 P 0 ;0,1,2=280,3=0.000000
L 3.2409003 3.67621614 3.23936663 3.67311585 1 P 0 ;0,1,2=280,3=0.000000
L 3.23936663 3.67311585 3.23706713 3.67053307 1 P 0 ;0,1,2=280,3=0.000000
L 3.23706713 3.67053307 3.23400039 3.6695 1 P 0 ;0,1,2=280,3=0.000000
L 3.23400039 3.6695 3.23093366 3.67053307 1 P 0 ;0,1,2=280,3=0.000000
L 3.23093366 3.67053307 3.22863346 3.67311585 1 P 0 ;0,1,2=280,3=0.000000
L 3.22863346 3.67311585 3.2270998 3.67621614 1 P 0 ;0,1,2=280,3=0.000000
L 3.2270998 3.67621614 3.22595 3.68034951 1 P 0 ;0,1,2=280,3=0.000000
L 3.22595 3.68034951 3.22556673 3.68499951 1 P 0 ;0,1,2=280,3=0.000000
L 3.22556673 3.68499951 3.22595 3.68964941 1 P 0 ;0,1,2=280,3=0.000000
L 3.22595 3.68964941 3.2270998 3.69378376 1 P 0 ;0,1,2=280,3=0.000000
L 3.2270998 3.69378376 3.22863346 3.69688307 1 P 0 ;0,1,2=280,3=0.000000
L 3.22863346 3.69688307 3.23093366 3.69946683 1 P 0 ;0,1,2=280,3=0.000000
L 3.23093366 3.69946683 3.23400039 3.7005 1 P 0 ;0,1,2=280,3=0.000000
L 3.092 3.328 3.002 3.328 1 P 0 
L 3.002 3.328 3.002 3.372 1 P 0 
L 3.002 3.372 3.092 3.372 1 P 0 
L 3.092 3.372 3.092 3.328 1 P 0 
L 3.05416683 3.4245 3.05416683 3.4555 1 P 0 ;0,1,2=281,3=0.000000
L 3.05416683 3.4555 3.04458346 3.4555 1 P 0 ;0,1,2=281,3=0.000000
L 3.04458346 3.4555 3.04151673 3.45394931 1 P 0 ;0,1,2=281,3=0.000000
L 3.04151673 3.45394931 3.0395998 3.45188307 1 P 0 ;0,1,2=281,3=0.000000
L 3.0395998 3.45188307 3.03883327 3.4477497 1 P 0 ;0,1,2=281,3=0.000000
L 3.03883327 3.4477497 3.0395998 3.44361634 1 P 0 ;0,1,2=281,3=0.000000
L 3.0395998 3.44361634 3.0419 3.44103356 1 P 0 ;0,1,2=281,3=0.000000
L 3.0419 3.44103356 3.04458346 3.43948287 1 P 0 ;0,1,2=281,3=0.000000
L 3.04458346 3.43948287 3.05416683 3.43948287 1 P 0 ;0,1,2=281,3=0.000000
L 3.04458346 3.43948287 3.03883327 3.4245 1 P 0 ;0,1,2=281,3=0.000000
L 3.01550039 3.4245 3.01550039 3.4555 1 P 0 ;0,1,2=281,3=0.000000
L 3.01550039 3.4555 3.0201001 3.4493003 1 P 0 ;0,1,2=281,3=0.000000
L 3.0201001 3.4245 3.01090069 3.4245 1 P 0 ;0,1,2=281,3=0.000000
L 2.99293337 3.42914892 2.99063386 3.42656614 1 P 0 ;0,1,2=281,3=0.000000
L 2.99063386 3.42656614 2.98795039 3.42501654 1 P 0 ;0,1,2=281,3=0.000000
L 2.98795039 3.42501654 2.98450039 3.4245 1 P 0 ;0,1,2=281,3=0.000000
L 2.98450039 3.4245 2.9810497 3.42553307 1 P 0 ;0,1,2=281,3=0.000000
L 2.9810497 3.42553307 2.97836693 3.42759931 1 P 0 ;0,1,2=281,3=0.000000
L 2.97836693 3.42759931 2.97645 3.43121614 1 P 0 ;0,1,2=281,3=0.000000
L 2.97645 3.43121614 2.97606673 3.43534951 1 P 0 ;0,1,2=281,3=0.000000
L 2.97606673 3.43534951 2.97683327 3.43948287 1 P 0 ;0,1,2=281,3=0.000000
L 2.97683327 3.43948287 2.9787502 3.44206663 1 P 0 ;0,1,2=281,3=0.000000
L 2.9787502 3.44206663 2.98143366 3.44413287 1 P 0 ;0,1,2=281,3=0.000000
L 2.98143366 3.44413287 2.98411644 3.44464941 1 P 0 ;0,1,2=281,3=0.000000
L 2.98411644 3.44464941 2.9867999 3.44413287 1 P 0 ;0,1,2=281,3=0.000000
L 2.9867999 3.44413287 2.9902499 3.44206663 1 P 0 ;0,1,2=281,3=0.000000
L 2.9902499 3.44206663 2.9891001 3.4555 1 P 0 ;0,1,2=281,3=0.000000
L 2.9891001 3.4555 2.9787502 3.4555 1 P 0 ;0,1,2=281,3=0.000000
L 2.95350039 3.4245 2.95350039 3.4555 1 P 0 ;0,1,2=281,3=0.000000
L 2.95350039 3.4555 2.9581001 3.4493003 1 P 0 ;0,1,2=281,3=0.000000
L 2.9581001 3.4245 2.94890069 3.4245 1 P 0 ;0,1,2=281,3=0.000000
L 3.092 3.283 3.002 3.283 1 P 0 
L 3.002 3.283 3.002 3.327 1 P 0 
L 3.002 3.327 3.092 3.327 1 P 0 
L 3.092 3.327 3.092 3.283 1 P 0 
L 3.05416683 3.3845 3.05416683 3.4155 1 P 0 ;0,1,2=282,3=0.000000
L 3.05416683 3.4155 3.04458346 3.4155 1 P 0 ;0,1,2=282,3=0.000000
L 3.04458346 3.4155 3.04151673 3.41394931 1 P 0 ;0,1,2=282,3=0.000000
L 3.04151673 3.41394931 3.0395998 3.41188307 1 P 0 ;0,1,2=282,3=0.000000
L 3.0395998 3.41188307 3.03883327 3.4077497 1 P 0 ;0,1,2=282,3=0.000000
L 3.03883327 3.4077497 3.0395998 3.40361634 1 P 0 ;0,1,2=282,3=0.000000
L 3.0395998 3.40361634 3.0419 3.40103356 1 P 0 ;0,1,2=282,3=0.000000
L 3.0419 3.40103356 3.04458346 3.39948287 1 P 0 ;0,1,2=282,3=0.000000
L 3.04458346 3.39948287 3.05416683 3.39948287 1 P 0 ;0,1,2=282,3=0.000000
L 3.04458346 3.39948287 3.03883327 3.3845 1 P 0 ;0,1,2=282,3=0.000000
L 3.01550039 3.3845 3.01550039 3.4155 1 P 0 ;0,1,2=282,3=0.000000
L 3.01550039 3.4155 3.0201001 3.4093003 1 P 0 ;0,1,2=282,3=0.000000
L 3.0201001 3.3845 3.01090069 3.3845 1 P 0 ;0,1,2=282,3=0.000000
L 2.99293337 3.38914892 2.99063386 3.38656614 1 P 0 ;0,1,2=282,3=0.000000
L 2.99063386 3.38656614 2.98795039 3.38501654 1 P 0 ;0,1,2=282,3=0.000000
L 2.98795039 3.38501654 2.98450039 3.3845 1 P 0 ;0,1,2=282,3=0.000000
L 2.98450039 3.3845 2.9810497 3.38553307 1 P 0 ;0,1,2=282,3=0.000000
L 2.9810497 3.38553307 2.97836693 3.38759931 1 P 0 ;0,1,2=282,3=0.000000
L 2.97836693 3.38759931 2.97645 3.39121614 1 P 0 ;0,1,2=282,3=0.000000
L 2.97645 3.39121614 2.97606673 3.39534951 1 P 0 ;0,1,2=282,3=0.000000
L 2.97606673 3.39534951 2.97683327 3.39948287 1 P 0 ;0,1,2=282,3=0.000000
L 2.97683327 3.39948287 2.9787502 3.40206663 1 P 0 ;0,1,2=282,3=0.000000
L 2.9787502 3.40206663 2.98143366 3.40413287 1 P 0 ;0,1,2=282,3=0.000000
L 2.98143366 3.40413287 2.98411644 3.40464941 1 P 0 ;0,1,2=282,3=0.000000
L 2.98411644 3.40464941 2.9867999 3.40413287 1 P 0 ;0,1,2=282,3=0.000000
L 2.9867999 3.40413287 2.9902499 3.40206663 1 P 0 ;0,1,2=282,3=0.000000
L 2.9902499 3.40206663 2.9891001 3.4155 1 P 0 ;0,1,2=282,3=0.000000
L 2.9891001 3.4155 2.9787502 3.4155 1 P 0 ;0,1,2=282,3=0.000000
L 2.9489 3.3845 2.9489 3.4155 1 P 0 ;0,1,2=282,3=0.000000
L 2.9489 3.4155 2.96308376 3.39328327 1 P 0 ;0,1,2=282,3=0.000000
L 2.96308376 3.39328327 2.94391634 3.39328327 1 P 0 ;0,1,2=282,3=0.000000
L 3.867 3.114 3.957 3.114 1 P 0 
L 3.957 3.114 3.957 3.07 1 P 0 
L 3.957 3.07 3.867 3.07 1 P 0 
L 3.867 3.07 3.867 3.114 1 P 0 
L 3.98916683 2.9845 3.98916683 3.0155 1 P 0 ;0,1,2=283,3=0.000000
L 3.98916683 3.0155 3.97958346 3.0155 1 P 0 ;0,1,2=283,3=0.000000
L 3.97958346 3.0155 3.97651673 3.01394931 1 P 0 ;0,1,2=283,3=0.000000
L 3.97651673 3.01394931 3.9745998 3.01188307 1 P 0 ;0,1,2=283,3=0.000000
L 3.9745998 3.01188307 3.97383327 3.0077497 1 P 0 ;0,1,2=283,3=0.000000
L 3.97383327 3.0077497 3.9745998 3.00361634 1 P 0 ;0,1,2=283,3=0.000000
L 3.9745998 3.00361634 3.9769 3.00103356 1 P 0 ;0,1,2=283,3=0.000000
L 3.9769 3.00103356 3.97958346 2.99948287 1 P 0 ;0,1,2=283,3=0.000000
L 3.97958346 2.99948287 3.98916683 2.99948287 1 P 0 ;0,1,2=283,3=0.000000
L 3.97958346 2.99948287 3.97383327 2.9845 1 P 0 ;0,1,2=283,3=0.000000
L 3.95050039 2.9845 3.95050039 3.0155 1 P 0 ;0,1,2=283,3=0.000000
L 3.95050039 3.0155 3.9551001 3.0093003 1 P 0 ;0,1,2=283,3=0.000000
L 3.9551001 2.9845 3.94590069 2.9845 1 P 0 ;0,1,2=283,3=0.000000
L 3.92678356 2.99741575 3.9241001 3.00103356 1 P 0 ;0,1,2=283,3=0.000000
L 3.9241001 3.00103356 3.9217999 3.0030998 1 P 0 ;0,1,2=283,3=0.000000
L 3.9217999 3.0030998 3.91873317 3.00413287 1 P 0 ;0,1,2=283,3=0.000000
L 3.91873317 3.00413287 3.9160497 3.0030998 1 P 0 ;0,1,2=283,3=0.000000
L 3.9160497 3.0030998 3.91413346 3.00103356 1 P 0 ;0,1,2=283,3=0.000000
L 3.91413346 3.00103356 3.9125998 2.99793327 1 P 0 ;0,1,2=283,3=0.000000
L 3.9125998 2.99793327 3.91221654 2.99431644 1 P 0 ;0,1,2=283,3=0.000000
L 3.91221654 2.99431644 3.9125998 2.99121614 1 P 0 ;0,1,2=283,3=0.000000
L 3.9125998 2.99121614 3.91413346 2.98811585 1 P 0 ;0,1,2=283,3=0.000000
L 3.91413346 2.98811585 3.91643366 2.98553307 1 P 0 ;0,1,2=283,3=0.000000
L 3.91643366 2.98553307 3.91911644 2.9845 1 P 0 ;0,1,2=283,3=0.000000
L 3.91911644 2.9845 3.92218317 2.98553307 1 P 0 ;0,1,2=283,3=0.000000
L 3.92218317 2.98553307 3.92486663 2.98863238 1 P 0 ;0,1,2=283,3=0.000000
L 3.92486663 2.98863238 3.9264003 2.99328327 1 P 0 ;0,1,2=283,3=0.000000
L 3.9264003 2.99328327 3.92678356 2.9984498 1 P 0 ;0,1,2=283,3=0.000000
L 3.92678356 2.9984498 3.92601713 3.00516594 1 P 0 ;0,1,2=283,3=0.000000
L 3.92601713 3.00516594 3.92486663 3.00878376 1 P 0 ;0,1,2=283,3=0.000000
L 3.92486663 3.00878376 3.92295039 3.0123997 1 P 0 ;0,1,2=283,3=0.000000
L 3.92295039 3.0123997 3.92026693 3.01498337 1 P 0 ;0,1,2=283,3=0.000000
L 3.92026693 3.01498337 3.91758346 3.0155 1 P 0 ;0,1,2=283,3=0.000000
L 3.91758346 3.0155 3.9149 3.01446683 1 P 0 ;0,1,2=283,3=0.000000
L 3.9149 3.01446683 3.91298297 3.01188307 1 P 0 ;0,1,2=283,3=0.000000
L 3.89693337 2.98914892 3.89463386 2.98656614 1 P 0 ;0,1,2=283,3=0.000000
L 3.89463386 2.98656614 3.89195039 2.98501654 1 P 0 ;0,1,2=283,3=0.000000
L 3.89195039 2.98501654 3.88850039 2.9845 1 P 0 ;0,1,2=283,3=0.000000
L 3.88850039 2.9845 3.8850497 2.98553307 1 P 0 ;0,1,2=283,3=0.000000
L 3.8850497 2.98553307 3.88236693 2.98759931 1 P 0 ;0,1,2=283,3=0.000000
L 3.88236693 2.98759931 3.88045 2.99121614 1 P 0 ;0,1,2=283,3=0.000000
L 3.88045 2.99121614 3.88006673 2.99534951 1 P 0 ;0,1,2=283,3=0.000000
L 3.88006673 2.99534951 3.88083327 2.99948287 1 P 0 ;0,1,2=283,3=0.000000
L 3.88083327 2.99948287 3.8827502 3.00206663 1 P 0 ;0,1,2=283,3=0.000000
L 3.8827502 3.00206663 3.88543366 3.00413287 1 P 0 ;0,1,2=283,3=0.000000
L 3.88543366 3.00413287 3.88811644 3.00464941 1 P 0 ;0,1,2=283,3=0.000000
L 3.88811644 3.00464941 3.8907999 3.00413287 1 P 0 ;0,1,2=283,3=0.000000
L 3.8907999 3.00413287 3.8942499 3.00206663 1 P 0 ;0,1,2=283,3=0.000000
L 3.8942499 3.00206663 3.8931001 3.0155 1 P 0 ;0,1,2=283,3=0.000000
L 3.8931001 3.0155 3.8827502 3.0155 1 P 0 ;0,1,2=283,3=0.000000
L 3.618 4.175 3.528 4.175 1 P 0 
L 3.528 4.219 3.618 4.219 1 P 0 
L 3.618 4.219 3.618 4.175 1 P 0 
L 3.528 4.175 3.528 4.219 1 P 0 
L 3.60416683 4.2695 3.60416683 4.3005 1 P 0 ;0,1,2=284,3=0.000000
L 3.60416683 4.3005 3.59458346 4.3005 1 P 0 ;0,1,2=284,3=0.000000
L 3.59458346 4.3005 3.59151673 4.29894931 1 P 0 ;0,1,2=284,3=0.000000
L 3.59151673 4.29894931 3.5895998 4.29688307 1 P 0 ;0,1,2=284,3=0.000000
L 3.5895998 4.29688307 3.58883327 4.2927497 1 P 0 ;0,1,2=284,3=0.000000
L 3.58883327 4.2927497 3.5895998 4.28861634 1 P 0 ;0,1,2=284,3=0.000000
L 3.5895998 4.28861634 3.5919 4.28603356 1 P 0 ;0,1,2=284,3=0.000000
L 3.5919 4.28603356 3.59458346 4.28448287 1 P 0 ;0,1,2=284,3=0.000000
L 3.59458346 4.28448287 3.60416683 4.28448287 1 P 0 ;0,1,2=284,3=0.000000
L 3.59458346 4.28448287 3.58883327 4.2695 1 P 0 ;0,1,2=284,3=0.000000
L 3.57278356 4.29533346 3.57048337 4.29843278 1 P 0 ;0,1,2=284,3=0.000000
L 3.57048337 4.29843278 3.5677999 4.29998337 1 P 0 ;0,1,2=284,3=0.000000
L 3.5677999 4.29998337 3.56473317 4.3005 1 P 0 ;0,1,2=284,3=0.000000
L 3.56473317 4.3005 3.5609 4.29946683 1 P 0 ;0,1,2=284,3=0.000000
L 3.5609 4.29946683 3.55821654 4.29688307 1 P 0 ;0,1,2=284,3=0.000000
L 3.55821654 4.29688307 3.55745 4.29378376 1 P 0 ;0,1,2=284,3=0.000000
L 3.55745 4.29378376 3.55783327 4.29068258 1 P 0 ;0,1,2=284,3=0.000000
L 3.55783327 4.29068258 3.55936693 4.2880998 1 P 0 ;0,1,2=284,3=0.000000
L 3.55936693 4.2880998 3.56703337 4.28293327 1 P 0 ;0,1,2=284,3=0.000000
L 3.56703337 4.28293327 3.57048337 4.27931644 1 P 0 ;0,1,2=284,3=0.000000
L 3.57048337 4.27931644 3.57278356 4.27414892 1 P 0 ;0,1,2=284,3=0.000000
L 3.57278356 4.27414892 3.5735501 4.2695 1 P 0 ;0,1,2=284,3=0.000000
L 3.5735501 4.2695 3.55745 4.2695 1 P 0 ;0,1,2=284,3=0.000000
L 3.54178356 4.28241575 3.5391001 4.28603356 1 P 0 ;0,1,2=284,3=0.000000
L 3.5391001 4.28603356 3.5367999 4.2880998 1 P 0 ;0,1,2=284,3=0.000000
L 3.5367999 4.2880998 3.53373317 4.28913287 1 P 0 ;0,1,2=284,3=0.000000
L 3.53373317 4.28913287 3.5310497 4.2880998 1 P 0 ;0,1,2=284,3=0.000000
L 3.5310497 4.2880998 3.52913346 4.28603356 1 P 0 ;0,1,2=284,3=0.000000
L 3.52913346 4.28603356 3.5275998 4.28293327 1 P 0 ;0,1,2=284,3=0.000000
L 3.5275998 4.28293327 3.52721654 4.27931644 1 P 0 ;0,1,2=284,3=0.000000
L 3.52721654 4.27931644 3.5275998 4.27621614 1 P 0 ;0,1,2=284,3=0.000000
L 3.5275998 4.27621614 3.52913346 4.27311585 1 P 0 ;0,1,2=284,3=0.000000
L 3.52913346 4.27311585 3.53143366 4.27053307 1 P 0 ;0,1,2=284,3=0.000000
L 3.53143366 4.27053307 3.53411644 4.2695 1 P 0 ;0,1,2=284,3=0.000000
L 3.53411644 4.2695 3.53718317 4.27053307 1 P 0 ;0,1,2=284,3=0.000000
L 3.53718317 4.27053307 3.53986663 4.27363238 1 P 0 ;0,1,2=284,3=0.000000
L 3.53986663 4.27363238 3.5414003 4.27828327 1 P 0 ;0,1,2=284,3=0.000000
L 3.5414003 4.27828327 3.54178356 4.2834498 1 P 0 ;0,1,2=284,3=0.000000
L 3.54178356 4.2834498 3.54101713 4.29016594 1 P 0 ;0,1,2=284,3=0.000000
L 3.54101713 4.29016594 3.53986663 4.29378376 1 P 0 ;0,1,2=284,3=0.000000
L 3.53986663 4.29378376 3.53795039 4.2973997 1 P 0 ;0,1,2=284,3=0.000000
L 3.53795039 4.2973997 3.53526693 4.29998337 1 P 0 ;0,1,2=284,3=0.000000
L 3.53526693 4.29998337 3.53258346 4.3005 1 P 0 ;0,1,2=284,3=0.000000
L 3.53258346 4.3005 3.5299 4.29946683 1 P 0 ;0,1,2=284,3=0.000000
L 3.5299 4.29946683 3.52798297 4.29688307 1 P 0 ;0,1,2=284,3=0.000000
L 3.51193337 4.27569961 3.50963386 4.27208278 1 P 0 ;0,1,2=284,3=0.000000
L 3.50963386 4.27208278 3.50656713 4.27001654 1 P 0 ;0,1,2=284,3=0.000000
L 3.50656713 4.27001654 3.50311644 4.2695 1 P 0 ;0,1,2=284,3=0.000000
L 3.50311644 4.2695 3.5000497 4.27001654 1 P 0 ;0,1,2=284,3=0.000000
L 3.5000497 4.27001654 3.49698297 4.27259931 1 P 0 ;0,1,2=284,3=0.000000
L 3.49698297 4.27259931 3.49506673 4.27569961 1 P 0 ;0,1,2=284,3=0.000000
L 3.49506673 4.27569961 3.49468346 4.2787999 1 P 0 ;0,1,2=284,3=0.000000
L 3.49468346 4.2787999 3.49545 4.28241575 1 P 0 ;0,1,2=284,3=0.000000
L 3.49545 4.28241575 3.49813346 4.28499951 1 P 0 ;0,1,2=284,3=0.000000
L 3.49813346 4.28499951 3.50081693 4.28603356 1 P 0 ;0,1,2=284,3=0.000000
L 3.50081693 4.28603356 3.50426693 4.28603356 1 P 0 ;0,1,2=284,3=0.000000
L 3.50081693 4.28603356 3.49851673 4.28758317 1 P 0 ;0,1,2=284,3=0.000000
L 3.49851673 4.28758317 3.4965998 4.29016594 1 P 0 ;0,1,2=284,3=0.000000
L 3.4965998 4.29016594 3.49583327 4.29326624 1 P 0 ;0,1,2=284,3=0.000000
L 3.49583327 4.29326624 3.4965998 4.29636654 1 P 0 ;0,1,2=284,3=0.000000
L 3.4965998 4.29636654 3.49851673 4.29894931 1 P 0 ;0,1,2=284,3=0.000000
L 3.49851673 4.29894931 3.50196673 4.3005 1 P 0 ;0,1,2=284,3=0.000000
L 3.50196673 4.3005 3.50541663 4.29998337 1 P 0 ;0,1,2=284,3=0.000000
L 3.50541663 4.29998337 3.50886663 4.29791624 1 P 0 ;0,1,2=284,3=0.000000
L 3.498 4.009 3.588 4.009 1 P 0 
L 3.588 4.009 3.588 3.965 1 P 0 
L 3.588 3.965 3.498 3.965 1 P 0 
L 3.498 3.965 3.498 4.009 1 P 0 
L 3.72666683 3.9715 3.72666683 4.0025 1 P 0 ;0,1,2=285,3=0.000000
L 3.72666683 4.0025 3.71708346 4.0025 1 P 0 ;0,1,2=285,3=0.000000
L 3.71708346 4.0025 3.71401673 4.00094931 1 P 0 ;0,1,2=285,3=0.000000
L 3.71401673 4.00094931 3.7120998 3.99888307 1 P 0 ;0,1,2=285,3=0.000000
L 3.7120998 3.99888307 3.71133327 3.9947497 1 P 0 ;0,1,2=285,3=0.000000
L 3.71133327 3.9947497 3.7120998 3.99061634 1 P 0 ;0,1,2=285,3=0.000000
L 3.7120998 3.99061634 3.7144 3.98803356 1 P 0 ;0,1,2=285,3=0.000000
L 3.7144 3.98803356 3.71708346 3.98648287 1 P 0 ;0,1,2=285,3=0.000000
L 3.71708346 3.98648287 3.72666683 3.98648287 1 P 0 ;0,1,2=285,3=0.000000
L 3.71708346 3.98648287 3.71133327 3.9715 1 P 0 ;0,1,2=285,3=0.000000
L 3.69643337 3.97769961 3.69413386 3.97408278 1 P 0 ;0,1,2=285,3=0.000000
L 3.69413386 3.97408278 3.69106713 3.97201654 1 P 0 ;0,1,2=285,3=0.000000
L 3.69106713 3.97201654 3.68761644 3.9715 1 P 0 ;0,1,2=285,3=0.000000
L 3.68761644 3.9715 3.6845497 3.97201654 1 P 0 ;0,1,2=285,3=0.000000
L 3.6845497 3.97201654 3.68148297 3.97459931 1 P 0 ;0,1,2=285,3=0.000000
L 3.68148297 3.97459931 3.67956673 3.97769961 1 P 0 ;0,1,2=285,3=0.000000
L 3.67956673 3.97769961 3.67918346 3.9807999 1 P 0 ;0,1,2=285,3=0.000000
L 3.67918346 3.9807999 3.67995 3.98441575 1 P 0 ;0,1,2=285,3=0.000000
L 3.67995 3.98441575 3.68263346 3.98699951 1 P 0 ;0,1,2=285,3=0.000000
L 3.68263346 3.98699951 3.68531693 3.98803356 1 P 0 ;0,1,2=285,3=0.000000
L 3.68531693 3.98803356 3.68876693 3.98803356 1 P 0 ;0,1,2=285,3=0.000000
L 3.68531693 3.98803356 3.68301673 3.98958317 1 P 0 ;0,1,2=285,3=0.000000
L 3.68301673 3.98958317 3.6810998 3.99216594 1 P 0 ;0,1,2=285,3=0.000000
L 3.6810998 3.99216594 3.68033327 3.99526624 1 P 0 ;0,1,2=285,3=0.000000
L 3.68033327 3.99526624 3.6810998 3.99836654 1 P 0 ;0,1,2=285,3=0.000000
L 3.6810998 3.99836654 3.68301673 4.00094931 1 P 0 ;0,1,2=285,3=0.000000
L 3.68301673 4.00094931 3.68646673 4.0025 1 P 0 ;0,1,2=285,3=0.000000
L 3.68646673 4.0025 3.68991663 4.00198337 1 P 0 ;0,1,2=285,3=0.000000
L 3.68991663 4.00198337 3.69336663 3.99991624 1 P 0 ;0,1,2=285,3=0.000000
L 3.66428356 3.98441575 3.6616001 3.98803356 1 P 0 ;0,1,2=285,3=0.000000
L 3.6616001 3.98803356 3.6592999 3.9900998 1 P 0 ;0,1,2=285,3=0.000000
L 3.6592999 3.9900998 3.65623317 3.99113287 1 P 0 ;0,1,2=285,3=0.000000
L 3.65623317 3.99113287 3.6535497 3.9900998 1 P 0 ;0,1,2=285,3=0.000000
L 3.6535497 3.9900998 3.65163346 3.98803356 1 P 0 ;0,1,2=285,3=0.000000
L 3.65163346 3.98803356 3.6500998 3.98493327 1 P 0 ;0,1,2=285,3=0.000000
L 3.6500998 3.98493327 3.64971654 3.98131644 1 P 0 ;0,1,2=285,3=0.000000
L 3.64971654 3.98131644 3.6500998 3.97821614 1 P 0 ;0,1,2=285,3=0.000000
L 3.6500998 3.97821614 3.65163346 3.97511585 1 P 0 ;0,1,2=285,3=0.000000
L 3.65163346 3.97511585 3.65393366 3.97253307 1 P 0 ;0,1,2=285,3=0.000000
L 3.65393366 3.97253307 3.65661644 3.9715 1 P 0 ;0,1,2=285,3=0.000000
L 3.65661644 3.9715 3.65968317 3.97253307 1 P 0 ;0,1,2=285,3=0.000000
L 3.65968317 3.97253307 3.66236663 3.97563238 1 P 0 ;0,1,2=285,3=0.000000
L 3.66236663 3.97563238 3.6639003 3.98028327 1 P 0 ;0,1,2=285,3=0.000000
L 3.6639003 3.98028327 3.66428356 3.9854498 1 P 0 ;0,1,2=285,3=0.000000
L 3.66428356 3.9854498 3.66351713 3.99216594 1 P 0 ;0,1,2=285,3=0.000000
L 3.66351713 3.99216594 3.66236663 3.99578376 1 P 0 ;0,1,2=285,3=0.000000
L 3.66236663 3.99578376 3.66045039 3.9993997 1 P 0 ;0,1,2=285,3=0.000000
L 3.66045039 3.9993997 3.65776693 4.00198337 1 P 0 ;0,1,2=285,3=0.000000
L 3.65776693 4.00198337 3.65508346 4.0025 1 P 0 ;0,1,2=285,3=0.000000
L 3.65508346 4.0025 3.6524 4.00146683 1 P 0 ;0,1,2=285,3=0.000000
L 3.6524 4.00146683 3.65048297 3.99888307 1 P 0 ;0,1,2=285,3=0.000000
L 3.498 4.099 3.588 4.099 1 P 0 
L 3.588 4.055 3.498 4.055 1 P 0 
L 3.498 4.055 3.498 4.099 1 P 0 
L 3.588 4.099 3.588 4.055 1 P 0 
L 3.72866683 4.0595 3.72866683 4.0905 1 P 0 ;0,1,2=286,3=0.000000
L 3.72866683 4.0905 3.71908346 4.0905 1 P 0 ;0,1,2=286,3=0.000000
L 3.71908346 4.0905 3.71601673 4.08894931 1 P 0 ;0,1,2=286,3=0.000000
L 3.71601673 4.08894931 3.7140998 4.08688307 1 P 0 ;0,1,2=286,3=0.000000
L 3.7140998 4.08688307 3.71333327 4.0827497 1 P 0 ;0,1,2=286,3=0.000000
L 3.71333327 4.0827497 3.7140998 4.07861634 1 P 0 ;0,1,2=286,3=0.000000
L 3.7140998 4.07861634 3.7164 4.07603356 1 P 0 ;0,1,2=286,3=0.000000
L 3.7164 4.07603356 3.71908346 4.07448287 1 P 0 ;0,1,2=286,3=0.000000
L 3.71908346 4.07448287 3.72866683 4.07448287 1 P 0 ;0,1,2=286,3=0.000000
L 3.71908346 4.07448287 3.71333327 4.0595 1 P 0 ;0,1,2=286,3=0.000000
L 3.69843337 4.06414892 3.69613386 4.06156614 1 P 0 ;0,1,2=286,3=0.000000
L 3.69613386 4.06156614 3.69345039 4.06001654 1 P 0 ;0,1,2=286,3=0.000000
L 3.69345039 4.06001654 3.69000039 4.0595 1 P 0 ;0,1,2=286,3=0.000000
L 3.69000039 4.0595 3.6865497 4.06053307 1 P 0 ;0,1,2=286,3=0.000000
L 3.6865497 4.06053307 3.68386693 4.06259931 1 P 0 ;0,1,2=286,3=0.000000
L 3.68386693 4.06259931 3.68195 4.06621614 1 P 0 ;0,1,2=286,3=0.000000
L 3.68195 4.06621614 3.68156673 4.07034951 1 P 0 ;0,1,2=286,3=0.000000
L 3.68156673 4.07034951 3.68233327 4.07448287 1 P 0 ;0,1,2=286,3=0.000000
L 3.68233327 4.07448287 3.6842502 4.07706663 1 P 0 ;0,1,2=286,3=0.000000
L 3.6842502 4.07706663 3.68693366 4.07913287 1 P 0 ;0,1,2=286,3=0.000000
L 3.68693366 4.07913287 3.68961644 4.07964941 1 P 0 ;0,1,2=286,3=0.000000
L 3.68961644 4.07964941 3.6922999 4.07913287 1 P 0 ;0,1,2=286,3=0.000000
L 3.6922999 4.07913287 3.6957499 4.07706663 1 P 0 ;0,1,2=286,3=0.000000
L 3.6957499 4.07706663 3.6946001 4.0905 1 P 0 ;0,1,2=286,3=0.000000
L 3.6946001 4.0905 3.6842502 4.0905 1 P 0 ;0,1,2=286,3=0.000000
L 3.66743337 4.06569961 3.66513386 4.06208278 1 P 0 ;0,1,2=286,3=0.000000
L 3.66513386 4.06208278 3.66206713 4.06001654 1 P 0 ;0,1,2=286,3=0.000000
L 3.66206713 4.06001654 3.65861644 4.0595 1 P 0 ;0,1,2=286,3=0.000000
L 3.65861644 4.0595 3.6555497 4.06001654 1 P 0 ;0,1,2=286,3=0.000000
L 3.6555497 4.06001654 3.65248297 4.06259931 1 P 0 ;0,1,2=286,3=0.000000
L 3.65248297 4.06259931 3.65056673 4.06569961 1 P 0 ;0,1,2=286,3=0.000000
L 3.65056673 4.06569961 3.65018346 4.0687999 1 P 0 ;0,1,2=286,3=0.000000
L 3.65018346 4.0687999 3.65095 4.07241575 1 P 0 ;0,1,2=286,3=0.000000
L 3.65095 4.07241575 3.65363346 4.07499951 1 P 0 ;0,1,2=286,3=0.000000
L 3.65363346 4.07499951 3.65631693 4.07603356 1 P 0 ;0,1,2=286,3=0.000000
L 3.65631693 4.07603356 3.65976693 4.07603356 1 P 0 ;0,1,2=286,3=0.000000
L 3.65631693 4.07603356 3.65401673 4.07758317 1 P 0 ;0,1,2=286,3=0.000000
L 3.65401673 4.07758317 3.6520998 4.08016594 1 P 0 ;0,1,2=286,3=0.000000
L 3.6520998 4.08016594 3.65133327 4.08326624 1 P 0 ;0,1,2=286,3=0.000000
L 3.65133327 4.08326624 3.6520998 4.08636654 1 P 0 ;0,1,2=286,3=0.000000
L 3.6520998 4.08636654 3.65401673 4.08894931 1 P 0 ;0,1,2=286,3=0.000000
L 3.65401673 4.08894931 3.65746673 4.0905 1 P 0 ;0,1,2=286,3=0.000000
L 3.65746673 4.0905 3.66091663 4.08998337 1 P 0 ;0,1,2=286,3=0.000000
L 3.66091663 4.08998337 3.66436663 4.08791624 1 P 0 ;0,1,2=286,3=0.000000
L 3.72 3.392 3.81 3.392 1 P 0 
L 3.81 3.348 3.72 3.348 1 P 0 
L 3.72 3.348 3.72 3.392 1 P 0 
L 3.81 3.392 3.81 3.348 1 P 0 
L 3.80916683 3.5745 3.80916683 3.6055 1 P 0 ;0,1,2=287,3=0.000000
L 3.80916683 3.6055 3.79958346 3.6055 1 P 0 ;0,1,2=287,3=0.000000
L 3.79958346 3.6055 3.79651673 3.60394931 1 P 0 ;0,1,2=287,3=0.000000
L 3.79651673 3.60394931 3.7945998 3.60188307 1 P 0 ;0,1,2=287,3=0.000000
L 3.7945998 3.60188307 3.79383327 3.5977497 1 P 0 ;0,1,2=287,3=0.000000
L 3.79383327 3.5977497 3.7945998 3.59361634 1 P 0 ;0,1,2=287,3=0.000000
L 3.7945998 3.59361634 3.7969 3.59103356 1 P 0 ;0,1,2=287,3=0.000000
L 3.7969 3.59103356 3.79958346 3.58948287 1 P 0 ;0,1,2=287,3=0.000000
L 3.79958346 3.58948287 3.80916683 3.58948287 1 P 0 ;0,1,2=287,3=0.000000
L 3.79958346 3.58948287 3.79383327 3.5745 1 P 0 ;0,1,2=287,3=0.000000
L 3.77778356 3.60033346 3.77548337 3.60343278 1 P 0 ;0,1,2=287,3=0.000000
L 3.77548337 3.60343278 3.7727999 3.60498337 1 P 0 ;0,1,2=287,3=0.000000
L 3.7727999 3.60498337 3.76973317 3.6055 1 P 0 ;0,1,2=287,3=0.000000
L 3.76973317 3.6055 3.7659 3.60446683 1 P 0 ;0,1,2=287,3=0.000000
L 3.7659 3.60446683 3.76321654 3.60188307 1 P 0 ;0,1,2=287,3=0.000000
L 3.76321654 3.60188307 3.76245 3.59878376 1 P 0 ;0,1,2=287,3=0.000000
L 3.76245 3.59878376 3.76283327 3.59568258 1 P 0 ;0,1,2=287,3=0.000000
L 3.76283327 3.59568258 3.76436693 3.5930998 1 P 0 ;0,1,2=287,3=0.000000
L 3.76436693 3.5930998 3.77203337 3.58793327 1 P 0 ;0,1,2=287,3=0.000000
L 3.77203337 3.58793327 3.77548337 3.58431644 1 P 0 ;0,1,2=287,3=0.000000
L 3.77548337 3.58431644 3.77778356 3.57914892 1 P 0 ;0,1,2=287,3=0.000000
L 3.77778356 3.57914892 3.7785501 3.5745 1 P 0 ;0,1,2=287,3=0.000000
L 3.7785501 3.5745 3.76245 3.5745 1 P 0 ;0,1,2=287,3=0.000000
L 3.73950039 3.6055 3.74256713 3.60446683 1 P 0 ;0,1,2=287,3=0.000000
L 3.74256713 3.60446683 3.74486663 3.60188307 1 P 0 ;0,1,2=287,3=0.000000
L 3.74486663 3.60188307 3.7464003 3.59878376 1 P 0 ;0,1,2=287,3=0.000000
L 3.7464003 3.59878376 3.7475501 3.59464941 1 P 0 ;0,1,2=287,3=0.000000
L 3.7475501 3.59464941 3.74793337 3.58999951 1 P 0 ;0,1,2=287,3=0.000000
L 3.74793337 3.58999951 3.7475501 3.58534951 1 P 0 ;0,1,2=287,3=0.000000
L 3.7475501 3.58534951 3.7464003 3.58121614 1 P 0 ;0,1,2=287,3=0.000000
L 3.7464003 3.58121614 3.74486663 3.57811585 1 P 0 ;0,1,2=287,3=0.000000
L 3.74486663 3.57811585 3.74256713 3.57553307 1 P 0 ;0,1,2=287,3=0.000000
L 3.74256713 3.57553307 3.73950039 3.5745 1 P 0 ;0,1,2=287,3=0.000000
L 3.73950039 3.5745 3.73643366 3.57553307 1 P 0 ;0,1,2=287,3=0.000000
L 3.73643366 3.57553307 3.73413346 3.57811585 1 P 0 ;0,1,2=287,3=0.000000
L 3.73413346 3.57811585 3.7325998 3.58121614 1 P 0 ;0,1,2=287,3=0.000000
L 3.7325998 3.58121614 3.73145 3.58534951 1 P 0 ;0,1,2=287,3=0.000000
L 3.73145 3.58534951 3.73106673 3.58999951 1 P 0 ;0,1,2=287,3=0.000000
L 3.73106673 3.58999951 3.73145 3.59464941 1 P 0 ;0,1,2=287,3=0.000000
L 3.73145 3.59464941 3.7325998 3.59878376 1 P 0 ;0,1,2=287,3=0.000000
L 3.7325998 3.59878376 3.73413346 3.60188307 1 P 0 ;0,1,2=287,3=0.000000
L 3.73413346 3.60188307 3.73643366 3.60446683 1 P 0 ;0,1,2=287,3=0.000000
L 3.73643366 3.60446683 3.73950039 3.6055 1 P 0 ;0,1,2=287,3=0.000000
L 3.70850039 3.5745 3.70850039 3.6055 1 P 0 ;0,1,2=287,3=0.000000
L 3.70850039 3.6055 3.7131001 3.5993003 1 P 0 ;0,1,2=287,3=0.000000
L 3.7131001 3.5745 3.70390069 3.5745 1 P 0 ;0,1,2=287,3=0.000000
L 3.81 3.393 3.72 3.393 1 P 0 
L 3.72 3.393 3.72 3.437 1 P 0 
L 3.72 3.437 3.81 3.437 1 P 0 
L 3.81 3.437 3.81 3.393 1 P 0 
L 3.80916683 3.6195 3.80916683 3.6505 1 P 0 ;0,1,2=288,3=0.000000
L 3.80916683 3.6505 3.79958346 3.6505 1 P 0 ;0,1,2=288,3=0.000000
L 3.79958346 3.6505 3.79651673 3.64894931 1 P 0 ;0,1,2=288,3=0.000000
L 3.79651673 3.64894931 3.7945998 3.64688307 1 P 0 ;0,1,2=288,3=0.000000
L 3.7945998 3.64688307 3.79383327 3.6427497 1 P 0 ;0,1,2=288,3=0.000000
L 3.79383327 3.6427497 3.7945998 3.63861634 1 P 0 ;0,1,2=288,3=0.000000
L 3.7945998 3.63861634 3.7969 3.63603356 1 P 0 ;0,1,2=288,3=0.000000
L 3.7969 3.63603356 3.79958346 3.63448287 1 P 0 ;0,1,2=288,3=0.000000
L 3.79958346 3.63448287 3.80916683 3.63448287 1 P 0 ;0,1,2=288,3=0.000000
L 3.79958346 3.63448287 3.79383327 3.6195 1 P 0 ;0,1,2=288,3=0.000000
L 3.77778356 3.64533346 3.77548337 3.64843278 1 P 0 ;0,1,2=288,3=0.000000
L 3.77548337 3.64843278 3.7727999 3.64998337 1 P 0 ;0,1,2=288,3=0.000000
L 3.7727999 3.64998337 3.76973317 3.6505 1 P 0 ;0,1,2=288,3=0.000000
L 3.76973317 3.6505 3.7659 3.64946683 1 P 0 ;0,1,2=288,3=0.000000
L 3.7659 3.64946683 3.76321654 3.64688307 1 P 0 ;0,1,2=288,3=0.000000
L 3.76321654 3.64688307 3.76245 3.64378376 1 P 0 ;0,1,2=288,3=0.000000
L 3.76245 3.64378376 3.76283327 3.64068258 1 P 0 ;0,1,2=288,3=0.000000
L 3.76283327 3.64068258 3.76436693 3.6380998 1 P 0 ;0,1,2=288,3=0.000000
L 3.76436693 3.6380998 3.77203337 3.63293327 1 P 0 ;0,1,2=288,3=0.000000
L 3.77203337 3.63293327 3.77548337 3.62931644 1 P 0 ;0,1,2=288,3=0.000000
L 3.77548337 3.62931644 3.77778356 3.62414892 1 P 0 ;0,1,2=288,3=0.000000
L 3.77778356 3.62414892 3.7785501 3.6195 1 P 0 ;0,1,2=288,3=0.000000
L 3.7785501 3.6195 3.76245 3.6195 1 P 0 ;0,1,2=288,3=0.000000
L 3.73950039 3.6505 3.74256713 3.64946683 1 P 0 ;0,1,2=288,3=0.000000
L 3.74256713 3.64946683 3.74486663 3.64688307 1 P 0 ;0,1,2=288,3=0.000000
L 3.74486663 3.64688307 3.7464003 3.64378376 1 P 0 ;0,1,2=288,3=0.000000
L 3.7464003 3.64378376 3.7475501 3.63964941 1 P 0 ;0,1,2=288,3=0.000000
L 3.7475501 3.63964941 3.74793337 3.63499951 1 P 0 ;0,1,2=288,3=0.000000
L 3.74793337 3.63499951 3.7475501 3.63034951 1 P 0 ;0,1,2=288,3=0.000000
L 3.7475501 3.63034951 3.7464003 3.62621614 1 P 0 ;0,1,2=288,3=0.000000
L 3.7464003 3.62621614 3.74486663 3.62311585 1 P 0 ;0,1,2=288,3=0.000000
L 3.74486663 3.62311585 3.74256713 3.62053307 1 P 0 ;0,1,2=288,3=0.000000
L 3.74256713 3.62053307 3.73950039 3.6195 1 P 0 ;0,1,2=288,3=0.000000
L 3.73950039 3.6195 3.73643366 3.62053307 1 P 0 ;0,1,2=288,3=0.000000
L 3.73643366 3.62053307 3.73413346 3.62311585 1 P 0 ;0,1,2=288,3=0.000000
L 3.73413346 3.62311585 3.7325998 3.62621614 1 P 0 ;0,1,2=288,3=0.000000
L 3.7325998 3.62621614 3.73145 3.63034951 1 P 0 ;0,1,2=288,3=0.000000
L 3.73145 3.63034951 3.73106673 3.63499951 1 P 0 ;0,1,2=288,3=0.000000
L 3.73106673 3.63499951 3.73145 3.63964941 1 P 0 ;0,1,2=288,3=0.000000
L 3.73145 3.63964941 3.7325998 3.64378376 1 P 0 ;0,1,2=288,3=0.000000
L 3.7325998 3.64378376 3.73413346 3.64688307 1 P 0 ;0,1,2=288,3=0.000000
L 3.73413346 3.64688307 3.73643366 3.64946683 1 P 0 ;0,1,2=288,3=0.000000
L 3.73643366 3.64946683 3.73950039 3.6505 1 P 0 ;0,1,2=288,3=0.000000
L 3.71693337 3.62414892 3.71463386 3.62156614 1 P 0 ;0,1,2=288,3=0.000000
L 3.71463386 3.62156614 3.71195039 3.62001654 1 P 0 ;0,1,2=288,3=0.000000
L 3.71195039 3.62001654 3.70850039 3.6195 1 P 0 ;0,1,2=288,3=0.000000
L 3.70850039 3.6195 3.7050497 3.62053307 1 P 0 ;0,1,2=288,3=0.000000
L 3.7050497 3.62053307 3.70236693 3.62259931 1 P 0 ;0,1,2=288,3=0.000000
L 3.70236693 3.62259931 3.70045 3.62621614 1 P 0 ;0,1,2=288,3=0.000000
L 3.70045 3.62621614 3.70006673 3.63034951 1 P 0 ;0,1,2=288,3=0.000000
L 3.70006673 3.63034951 3.70083327 3.63448287 1 P 0 ;0,1,2=288,3=0.000000
L 3.70083327 3.63448287 3.7027502 3.63706663 1 P 0 ;0,1,2=288,3=0.000000
L 3.7027502 3.63706663 3.70543366 3.63913287 1 P 0 ;0,1,2=288,3=0.000000
L 3.70543366 3.63913287 3.70811644 3.63964941 1 P 0 ;0,1,2=288,3=0.000000
L 3.70811644 3.63964941 3.7107999 3.63913287 1 P 0 ;0,1,2=288,3=0.000000
L 3.7107999 3.63913287 3.7142499 3.63706663 1 P 0 ;0,1,2=288,3=0.000000
L 3.7142499 3.63706663 3.7131001 3.6505 1 P 0 ;0,1,2=288,3=0.000000
L 3.7131001 3.6505 3.7027502 3.6505 1 P 0 ;0,1,2=288,3=0.000000
L 3.81 3.303 3.72 3.303 1 P 0 
L 3.72 3.303 3.72 3.347 1 P 0 
L 3.72 3.347 3.81 3.347 1 P 0 
L 3.81 3.347 3.81 3.303 1 P 0 
L 3.80916683 3.5295 3.80916683 3.5605 1 P 0 ;0,1,2=289,3=0.000000
L 3.80916683 3.5605 3.79958346 3.5605 1 P 0 ;0,1,2=289,3=0.000000
L 3.79958346 3.5605 3.79651673 3.55894931 1 P 0 ;0,1,2=289,3=0.000000
L 3.79651673 3.55894931 3.7945998 3.55688307 1 P 0 ;0,1,2=289,3=0.000000
L 3.7945998 3.55688307 3.79383327 3.5527497 1 P 0 ;0,1,2=289,3=0.000000
L 3.79383327 3.5527497 3.7945998 3.54861634 1 P 0 ;0,1,2=289,3=0.000000
L 3.7945998 3.54861634 3.7969 3.54603356 1 P 0 ;0,1,2=289,3=0.000000
L 3.7969 3.54603356 3.79958346 3.54448287 1 P 0 ;0,1,2=289,3=0.000000
L 3.79958346 3.54448287 3.80916683 3.54448287 1 P 0 ;0,1,2=289,3=0.000000
L 3.79958346 3.54448287 3.79383327 3.5295 1 P 0 ;0,1,2=289,3=0.000000
L 3.77778356 3.55533346 3.77548337 3.55843278 1 P 0 ;0,1,2=289,3=0.000000
L 3.77548337 3.55843278 3.7727999 3.55998337 1 P 0 ;0,1,2=289,3=0.000000
L 3.7727999 3.55998337 3.76973317 3.5605 1 P 0 ;0,1,2=289,3=0.000000
L 3.76973317 3.5605 3.7659 3.55946683 1 P 0 ;0,1,2=289,3=0.000000
L 3.7659 3.55946683 3.76321654 3.55688307 1 P 0 ;0,1,2=289,3=0.000000
L 3.76321654 3.55688307 3.76245 3.55378376 1 P 0 ;0,1,2=289,3=0.000000
L 3.76245 3.55378376 3.76283327 3.55068258 1 P 0 ;0,1,2=289,3=0.000000
L 3.76283327 3.55068258 3.76436693 3.5480998 1 P 0 ;0,1,2=289,3=0.000000
L 3.76436693 3.5480998 3.77203337 3.54293327 1 P 0 ;0,1,2=289,3=0.000000
L 3.77203337 3.54293327 3.77548337 3.53931644 1 P 0 ;0,1,2=289,3=0.000000
L 3.77548337 3.53931644 3.77778356 3.53414892 1 P 0 ;0,1,2=289,3=0.000000
L 3.77778356 3.53414892 3.7785501 3.5295 1 P 0 ;0,1,2=289,3=0.000000
L 3.7785501 3.5295 3.76245 3.5295 1 P 0 ;0,1,2=289,3=0.000000
L 3.73950039 3.5605 3.74256713 3.55946683 1 P 0 ;0,1,2=289,3=0.000000
L 3.74256713 3.55946683 3.74486663 3.55688307 1 P 0 ;0,1,2=289,3=0.000000
L 3.74486663 3.55688307 3.7464003 3.55378376 1 P 0 ;0,1,2=289,3=0.000000
L 3.7464003 3.55378376 3.7475501 3.54964941 1 P 0 ;0,1,2=289,3=0.000000
L 3.7475501 3.54964941 3.74793337 3.54499951 1 P 0 ;0,1,2=289,3=0.000000
L 3.74793337 3.54499951 3.7475501 3.54034951 1 P 0 ;0,1,2=289,3=0.000000
L 3.7475501 3.54034951 3.7464003 3.53621614 1 P 0 ;0,1,2=289,3=0.000000
L 3.7464003 3.53621614 3.74486663 3.53311585 1 P 0 ;0,1,2=289,3=0.000000
L 3.74486663 3.53311585 3.74256713 3.53053307 1 P 0 ;0,1,2=289,3=0.000000
L 3.74256713 3.53053307 3.73950039 3.5295 1 P 0 ;0,1,2=289,3=0.000000
L 3.73950039 3.5295 3.73643366 3.53053307 1 P 0 ;0,1,2=289,3=0.000000
L 3.73643366 3.53053307 3.73413346 3.53311585 1 P 0 ;0,1,2=289,3=0.000000
L 3.73413346 3.53311585 3.7325998 3.53621614 1 P 0 ;0,1,2=289,3=0.000000
L 3.7325998 3.53621614 3.73145 3.54034951 1 P 0 ;0,1,2=289,3=0.000000
L 3.73145 3.54034951 3.73106673 3.54499951 1 P 0 ;0,1,2=289,3=0.000000
L 3.73106673 3.54499951 3.73145 3.54964941 1 P 0 ;0,1,2=289,3=0.000000
L 3.73145 3.54964941 3.7325998 3.55378376 1 P 0 ;0,1,2=289,3=0.000000
L 3.7325998 3.55378376 3.73413346 3.55688307 1 P 0 ;0,1,2=289,3=0.000000
L 3.73413346 3.55688307 3.73643366 3.55946683 1 P 0 ;0,1,2=289,3=0.000000
L 3.73643366 3.55946683 3.73950039 3.5605 1 P 0 ;0,1,2=289,3=0.000000
L 3.7039 3.5295 3.7039 3.5605 1 P 0 ;0,1,2=289,3=0.000000
L 3.7039 3.5605 3.71808376 3.53828327 1 P 0 ;0,1,2=289,3=0.000000
L 3.71808376 3.53828327 3.69891634 3.53828327 1 P 0 ;0,1,2=289,3=0.000000
L 3.81 3.258 3.72 3.258 1 P 0 
L 3.72 3.258 3.72 3.302 1 P 0 
L 3.72 3.302 3.81 3.302 1 P 0 
L 3.81 3.302 3.81 3.258 1 P 0 
L 3.80916683 3.4845 3.80916683 3.5155 1 P 0 ;0,1,2=290,3=0.000000
L 3.80916683 3.5155 3.79958346 3.5155 1 P 0 ;0,1,2=290,3=0.000000
L 3.79958346 3.5155 3.79651673 3.51394931 1 P 0 ;0,1,2=290,3=0.000000
L 3.79651673 3.51394931 3.7945998 3.51188307 1 P 0 ;0,1,2=290,3=0.000000
L 3.7945998 3.51188307 3.79383327 3.5077497 1 P 0 ;0,1,2=290,3=0.000000
L 3.79383327 3.5077497 3.7945998 3.50361634 1 P 0 ;0,1,2=290,3=0.000000
L 3.7945998 3.50361634 3.7969 3.50103356 1 P 0 ;0,1,2=290,3=0.000000
L 3.7969 3.50103356 3.79958346 3.49948287 1 P 0 ;0,1,2=290,3=0.000000
L 3.79958346 3.49948287 3.80916683 3.49948287 1 P 0 ;0,1,2=290,3=0.000000
L 3.79958346 3.49948287 3.79383327 3.4845 1 P 0 ;0,1,2=290,3=0.000000
L 3.77778356 3.51033346 3.77548337 3.51343278 1 P 0 ;0,1,2=290,3=0.000000
L 3.77548337 3.51343278 3.7727999 3.51498337 1 P 0 ;0,1,2=290,3=0.000000
L 3.7727999 3.51498337 3.76973317 3.5155 1 P 0 ;0,1,2=290,3=0.000000
L 3.76973317 3.5155 3.7659 3.51446683 1 P 0 ;0,1,2=290,3=0.000000
L 3.7659 3.51446683 3.76321654 3.51188307 1 P 0 ;0,1,2=290,3=0.000000
L 3.76321654 3.51188307 3.76245 3.50878376 1 P 0 ;0,1,2=290,3=0.000000
L 3.76245 3.50878376 3.76283327 3.50568258 1 P 0 ;0,1,2=290,3=0.000000
L 3.76283327 3.50568258 3.76436693 3.5030998 1 P 0 ;0,1,2=290,3=0.000000
L 3.76436693 3.5030998 3.77203337 3.49793327 1 P 0 ;0,1,2=290,3=0.000000
L 3.77203337 3.49793327 3.77548337 3.49431644 1 P 0 ;0,1,2=290,3=0.000000
L 3.77548337 3.49431644 3.77778356 3.48914892 1 P 0 ;0,1,2=290,3=0.000000
L 3.77778356 3.48914892 3.7785501 3.4845 1 P 0 ;0,1,2=290,3=0.000000
L 3.7785501 3.4845 3.76245 3.4845 1 P 0 ;0,1,2=290,3=0.000000
L 3.73950039 3.5155 3.74256713 3.51446683 1 P 0 ;0,1,2=290,3=0.000000
L 3.74256713 3.51446683 3.74486663 3.51188307 1 P 0 ;0,1,2=290,3=0.000000
L 3.74486663 3.51188307 3.7464003 3.50878376 1 P 0 ;0,1,2=290,3=0.000000
L 3.7464003 3.50878376 3.7475501 3.50464941 1 P 0 ;0,1,2=290,3=0.000000
L 3.7475501 3.50464941 3.74793337 3.49999951 1 P 0 ;0,1,2=290,3=0.000000
L 3.74793337 3.49999951 3.7475501 3.49534951 1 P 0 ;0,1,2=290,3=0.000000
L 3.7475501 3.49534951 3.7464003 3.49121614 1 P 0 ;0,1,2=290,3=0.000000
L 3.7464003 3.49121614 3.74486663 3.48811585 1 P 0 ;0,1,2=290,3=0.000000
L 3.74486663 3.48811585 3.74256713 3.48553307 1 P 0 ;0,1,2=290,3=0.000000
L 3.74256713 3.48553307 3.73950039 3.4845 1 P 0 ;0,1,2=290,3=0.000000
L 3.73950039 3.4845 3.73643366 3.48553307 1 P 0 ;0,1,2=290,3=0.000000
L 3.73643366 3.48553307 3.73413346 3.48811585 1 P 0 ;0,1,2=290,3=0.000000
L 3.73413346 3.48811585 3.7325998 3.49121614 1 P 0 ;0,1,2=290,3=0.000000
L 3.7325998 3.49121614 3.73145 3.49534951 1 P 0 ;0,1,2=290,3=0.000000
L 3.73145 3.49534951 3.73106673 3.49999951 1 P 0 ;0,1,2=290,3=0.000000
L 3.73106673 3.49999951 3.73145 3.50464941 1 P 0 ;0,1,2=290,3=0.000000
L 3.73145 3.50464941 3.7325998 3.50878376 1 P 0 ;0,1,2=290,3=0.000000
L 3.7325998 3.50878376 3.73413346 3.51188307 1 P 0 ;0,1,2=290,3=0.000000
L 3.73413346 3.51188307 3.73643366 3.51446683 1 P 0 ;0,1,2=290,3=0.000000
L 3.73643366 3.51446683 3.73950039 3.5155 1 P 0 ;0,1,2=290,3=0.000000
L 3.70850039 3.5155 3.71156713 3.51446683 1 P 0 ;0,1,2=290,3=0.000000
L 3.71156713 3.51446683 3.71386663 3.51188307 1 P 0 ;0,1,2=290,3=0.000000
L 3.71386663 3.51188307 3.7154003 3.50878376 1 P 0 ;0,1,2=290,3=0.000000
L 3.7154003 3.50878376 3.7165501 3.50464941 1 P 0 ;0,1,2=290,3=0.000000
L 3.7165501 3.50464941 3.71693337 3.49999951 1 P 0 ;0,1,2=290,3=0.000000
L 3.71693337 3.49999951 3.7165501 3.49534951 1 P 0 ;0,1,2=290,3=0.000000
L 3.7165501 3.49534951 3.7154003 3.49121614 1 P 0 ;0,1,2=290,3=0.000000
L 3.7154003 3.49121614 3.71386663 3.48811585 1 P 0 ;0,1,2=290,3=0.000000
L 3.71386663 3.48811585 3.71156713 3.48553307 1 P 0 ;0,1,2=290,3=0.000000
L 3.71156713 3.48553307 3.70850039 3.4845 1 P 0 ;0,1,2=290,3=0.000000
L 3.70850039 3.4845 3.70543366 3.48553307 1 P 0 ;0,1,2=290,3=0.000000
L 3.70543366 3.48553307 3.70313346 3.48811585 1 P 0 ;0,1,2=290,3=0.000000
L 3.70313346 3.48811585 3.7015998 3.49121614 1 P 0 ;0,1,2=290,3=0.000000
L 3.7015998 3.49121614 3.70045 3.49534951 1 P 0 ;0,1,2=290,3=0.000000
L 3.70045 3.49534951 3.70006673 3.49999951 1 P 0 ;0,1,2=290,3=0.000000
L 3.70006673 3.49999951 3.70045 3.50464941 1 P 0 ;0,1,2=290,3=0.000000
L 3.70045 3.50464941 3.7015998 3.50878376 1 P 0 ;0,1,2=290,3=0.000000
L 3.7015998 3.50878376 3.70313346 3.51188307 1 P 0 ;0,1,2=290,3=0.000000
L 3.70313346 3.51188307 3.70543366 3.51446683 1 P 0 ;0,1,2=290,3=0.000000
L 3.70543366 3.51446683 3.70850039 3.5155 1 P 0 ;0,1,2=290,3=0.000000
L 3.72 3.257 3.81 3.257 1 P 0 
L 3.81 3.257 3.81 3.213 1 P 0 
L 3.81 3.213 3.72 3.213 1 P 0 
L 3.72 3.213 3.72 3.257 1 P 0 
L 3.80916683 3.4445 3.80916683 3.4755 1 P 0 ;0,1,2=291,3=0.000000
L 3.80916683 3.4755 3.79958346 3.4755 1 P 0 ;0,1,2=291,3=0.000000
L 3.79958346 3.4755 3.79651673 3.47394931 1 P 0 ;0,1,2=291,3=0.000000
L 3.79651673 3.47394931 3.7945998 3.47188307 1 P 0 ;0,1,2=291,3=0.000000
L 3.7945998 3.47188307 3.79383327 3.4677497 1 P 0 ;0,1,2=291,3=0.000000
L 3.79383327 3.4677497 3.7945998 3.46361634 1 P 0 ;0,1,2=291,3=0.000000
L 3.7945998 3.46361634 3.7969 3.46103356 1 P 0 ;0,1,2=291,3=0.000000
L 3.7969 3.46103356 3.79958346 3.45948287 1 P 0 ;0,1,2=291,3=0.000000
L 3.79958346 3.45948287 3.80916683 3.45948287 1 P 0 ;0,1,2=291,3=0.000000
L 3.79958346 3.45948287 3.79383327 3.4445 1 P 0 ;0,1,2=291,3=0.000000
L 3.77050039 3.4445 3.77050039 3.4755 1 P 0 ;0,1,2=291,3=0.000000
L 3.77050039 3.4755 3.7751001 3.4693003 1 P 0 ;0,1,2=291,3=0.000000
L 3.7751001 3.4445 3.76590069 3.4445 1 P 0 ;0,1,2=291,3=0.000000
L 3.74601713 3.44811585 3.74333366 3.44553307 1 P 0 ;0,1,2=291,3=0.000000
L 3.74333366 3.44553307 3.74026693 3.4445 1 P 0 ;0,1,2=291,3=0.000000
L 3.74026693 3.4445 3.7372002 3.44553307 1 P 0 ;0,1,2=291,3=0.000000
L 3.7372002 3.44553307 3.73451673 3.44863238 1 P 0 ;0,1,2=291,3=0.000000
L 3.73451673 3.44863238 3.7325998 3.45328327 1 P 0 ;0,1,2=291,3=0.000000
L 3.7325998 3.45328327 3.73183327 3.45793327 1 P 0 ;0,1,2=291,3=0.000000
L 3.73183327 3.45793327 3.73183327 3.46361634 1 P 0 ;0,1,2=291,3=0.000000
L 3.73183327 3.46361634 3.7325998 3.46826624 1 P 0 ;0,1,2=291,3=0.000000
L 3.7325998 3.46826624 3.73451673 3.4723997 1 P 0 ;0,1,2=291,3=0.000000
L 3.73451673 3.4723997 3.73681693 3.47446683 1 P 0 ;0,1,2=291,3=0.000000
L 3.73681693 3.47446683 3.73950039 3.4755 1 P 0 ;0,1,2=291,3=0.000000
L 3.73950039 3.4755 3.74256713 3.47446683 1 P 0 ;0,1,2=291,3=0.000000
L 3.74256713 3.47446683 3.74486663 3.4723997 1 P 0 ;0,1,2=291,3=0.000000
L 3.74486663 3.4723997 3.7464003 3.4693003 1 P 0 ;0,1,2=291,3=0.000000
L 3.7464003 3.4693003 3.74716683 3.46516594 1 P 0 ;0,1,2=291,3=0.000000
L 3.74716683 3.46516594 3.7464003 3.4615501 1 P 0 ;0,1,2=291,3=0.000000
L 3.7464003 3.4615501 3.74448337 3.45793327 1 P 0 ;0,1,2=291,3=0.000000
L 3.74448337 3.45793327 3.74218317 3.45586604 1 P 0 ;0,1,2=291,3=0.000000
L 3.74218317 3.45586604 3.73950039 3.45534951 1 P 0 ;0,1,2=291,3=0.000000
L 3.73950039 3.45534951 3.73643366 3.45638268 1 P 0 ;0,1,2=291,3=0.000000
L 3.73643366 3.45638268 3.73413346 3.45896634 1 P 0 ;0,1,2=291,3=0.000000
L 3.73413346 3.45896634 3.73183327 3.46361634 1 P 0 ;0,1,2=291,3=0.000000
L 3.70850039 3.4445 3.70850039 3.4755 1 P 0 ;0,1,2=291,3=0.000000
L 3.70850039 3.4755 3.7131001 3.4693003 1 P 0 ;0,1,2=291,3=0.000000
L 3.7131001 3.4445 3.70390069 3.4445 1 P 0 ;0,1,2=291,3=0.000000
L 3.53 3.257 3.53 3.213 1 P 0 
L 3.44 3.257 3.53 3.257 1 P 0 
L 3.53 3.213 3.44 3.213 1 P 0 
L 3.44 3.213 3.44 3.257 1 P 0 
L 3.54916683 3.4445 3.54916683 3.4755 1 P 0 ;0,1,2=292,3=0.000000
L 3.54916683 3.4755 3.53958346 3.4755 1 P 0 ;0,1,2=292,3=0.000000
L 3.53958346 3.4755 3.53651673 3.47394931 1 P 0 ;0,1,2=292,3=0.000000
L 3.53651673 3.47394931 3.5345998 3.47188307 1 P 0 ;0,1,2=292,3=0.000000
L 3.5345998 3.47188307 3.53383327 3.4677497 1 P 0 ;0,1,2=292,3=0.000000
L 3.53383327 3.4677497 3.5345998 3.46361634 1 P 0 ;0,1,2=292,3=0.000000
L 3.5345998 3.46361634 3.5369 3.46103356 1 P 0 ;0,1,2=292,3=0.000000
L 3.5369 3.46103356 3.53958346 3.45948287 1 P 0 ;0,1,2=292,3=0.000000
L 3.53958346 3.45948287 3.54916683 3.45948287 1 P 0 ;0,1,2=292,3=0.000000
L 3.53958346 3.45948287 3.53383327 3.4445 1 P 0 ;0,1,2=292,3=0.000000
L 3.51778356 3.47033346 3.51548337 3.47343278 1 P 0 ;0,1,2=292,3=0.000000
L 3.51548337 3.47343278 3.5127999 3.47498337 1 P 0 ;0,1,2=292,3=0.000000
L 3.5127999 3.47498337 3.50973317 3.4755 1 P 0 ;0,1,2=292,3=0.000000
L 3.50973317 3.4755 3.5059 3.47446683 1 P 0 ;0,1,2=292,3=0.000000
L 3.5059 3.47446683 3.50321654 3.47188307 1 P 0 ;0,1,2=292,3=0.000000
L 3.50321654 3.47188307 3.50245 3.46878376 1 P 0 ;0,1,2=292,3=0.000000
L 3.50245 3.46878376 3.50283327 3.46568258 1 P 0 ;0,1,2=292,3=0.000000
L 3.50283327 3.46568258 3.50436693 3.4630998 1 P 0 ;0,1,2=292,3=0.000000
L 3.50436693 3.4630998 3.51203337 3.45793327 1 P 0 ;0,1,2=292,3=0.000000
L 3.51203337 3.45793327 3.51548337 3.45431644 1 P 0 ;0,1,2=292,3=0.000000
L 3.51548337 3.45431644 3.51778356 3.44914892 1 P 0 ;0,1,2=292,3=0.000000
L 3.51778356 3.44914892 3.5185501 3.4445 1 P 0 ;0,1,2=292,3=0.000000
L 3.5185501 3.4445 3.50245 3.4445 1 P 0 ;0,1,2=292,3=0.000000
L 3.47950039 3.4755 3.48256713 3.47446683 1 P 0 ;0,1,2=292,3=0.000000
L 3.48256713 3.47446683 3.48486663 3.47188307 1 P 0 ;0,1,2=292,3=0.000000
L 3.48486663 3.47188307 3.4864003 3.46878376 1 P 0 ;0,1,2=292,3=0.000000
L 3.4864003 3.46878376 3.4875501 3.46464941 1 P 0 ;0,1,2=292,3=0.000000
L 3.4875501 3.46464941 3.48793337 3.45999951 1 P 0 ;0,1,2=292,3=0.000000
L 3.48793337 3.45999951 3.4875501 3.45534951 1 P 0 ;0,1,2=292,3=0.000000
L 3.4875501 3.45534951 3.4864003 3.45121614 1 P 0 ;0,1,2=292,3=0.000000
L 3.4864003 3.45121614 3.48486663 3.44811585 1 P 0 ;0,1,2=292,3=0.000000
L 3.48486663 3.44811585 3.48256713 3.44553307 1 P 0 ;0,1,2=292,3=0.000000
L 3.48256713 3.44553307 3.47950039 3.4445 1 P 0 ;0,1,2=292,3=0.000000
L 3.47950039 3.4445 3.47643366 3.44553307 1 P 0 ;0,1,2=292,3=0.000000
L 3.47643366 3.44553307 3.47413346 3.44811585 1 P 0 ;0,1,2=292,3=0.000000
L 3.47413346 3.44811585 3.4725998 3.45121614 1 P 0 ;0,1,2=292,3=0.000000
L 3.4725998 3.45121614 3.47145 3.45534951 1 P 0 ;0,1,2=292,3=0.000000
L 3.47145 3.45534951 3.47106673 3.45999951 1 P 0 ;0,1,2=292,3=0.000000
L 3.47106673 3.45999951 3.47145 3.46464941 1 P 0 ;0,1,2=292,3=0.000000
L 3.47145 3.46464941 3.4725998 3.46878376 1 P 0 ;0,1,2=292,3=0.000000
L 3.4725998 3.46878376 3.47413346 3.47188307 1 P 0 ;0,1,2=292,3=0.000000
L 3.47413346 3.47188307 3.47643366 3.47446683 1 P 0 ;0,1,2=292,3=0.000000
L 3.47643366 3.47446683 3.47950039 3.4755 1 P 0 ;0,1,2=292,3=0.000000
L 3.45578356 3.45741575 3.4531001 3.46103356 1 P 0 ;0,1,2=292,3=0.000000
L 3.4531001 3.46103356 3.4507999 3.4630998 1 P 0 ;0,1,2=292,3=0.000000
L 3.4507999 3.4630998 3.44773317 3.46413287 1 P 0 ;0,1,2=292,3=0.000000
L 3.44773317 3.46413287 3.4450497 3.4630998 1 P 0 ;0,1,2=292,3=0.000000
L 3.4450497 3.4630998 3.44313346 3.46103356 1 P 0 ;0,1,2=292,3=0.000000
L 3.44313346 3.46103356 3.4415998 3.45793327 1 P 0 ;0,1,2=292,3=0.000000
L 3.4415998 3.45793327 3.44121654 3.45431644 1 P 0 ;0,1,2=292,3=0.000000
L 3.44121654 3.45431644 3.4415998 3.45121614 1 P 0 ;0,1,2=292,3=0.000000
L 3.4415998 3.45121614 3.44313346 3.44811585 1 P 0 ;0,1,2=292,3=0.000000
L 3.44313346 3.44811585 3.44543366 3.44553307 1 P 0 ;0,1,2=292,3=0.000000
L 3.44543366 3.44553307 3.44811644 3.4445 1 P 0 ;0,1,2=292,3=0.000000
L 3.44811644 3.4445 3.45118317 3.44553307 1 P 0 ;0,1,2=292,3=0.000000
L 3.45118317 3.44553307 3.45386663 3.44863238 1 P 0 ;0,1,2=292,3=0.000000
L 3.45386663 3.44863238 3.4554003 3.45328327 1 P 0 ;0,1,2=292,3=0.000000
L 3.4554003 3.45328327 3.45578356 3.4584498 1 P 0 ;0,1,2=292,3=0.000000
L 3.45578356 3.4584498 3.45501713 3.46516594 1 P 0 ;0,1,2=292,3=0.000000
L 3.45501713 3.46516594 3.45386663 3.46878376 1 P 0 ;0,1,2=292,3=0.000000
L 3.45386663 3.46878376 3.45195039 3.4723997 1 P 0 ;0,1,2=292,3=0.000000
L 3.45195039 3.4723997 3.44926693 3.47498337 1 P 0 ;0,1,2=292,3=0.000000
L 3.44926693 3.47498337 3.44658346 3.4755 1 P 0 ;0,1,2=292,3=0.000000
L 3.44658346 3.4755 3.4439 3.47446683 1 P 0 ;0,1,2=292,3=0.000000
L 3.4439 3.47446683 3.44198297 3.47188307 1 P 0 ;0,1,2=292,3=0.000000
L 3.53 3.302 3.53 3.258 1 P 0 
L 3.44 3.302 3.53 3.302 1 P 0 
L 3.53 3.258 3.44 3.258 1 P 0 
L 3.44 3.258 3.44 3.302 1 P 0 
L 3.54916683 3.4845 3.54916683 3.5155 1 P 0 ;0,1,2=293,3=0.000000
L 3.54916683 3.5155 3.53958346 3.5155 1 P 0 ;0,1,2=293,3=0.000000
L 3.53958346 3.5155 3.53651673 3.51394931 1 P 0 ;0,1,2=293,3=0.000000
L 3.53651673 3.51394931 3.5345998 3.51188307 1 P 0 ;0,1,2=293,3=0.000000
L 3.5345998 3.51188307 3.53383327 3.5077497 1 P 0 ;0,1,2=293,3=0.000000
L 3.53383327 3.5077497 3.5345998 3.50361634 1 P 0 ;0,1,2=293,3=0.000000
L 3.5345998 3.50361634 3.5369 3.50103356 1 P 0 ;0,1,2=293,3=0.000000
L 3.5369 3.50103356 3.53958346 3.49948287 1 P 0 ;0,1,2=293,3=0.000000
L 3.53958346 3.49948287 3.54916683 3.49948287 1 P 0 ;0,1,2=293,3=0.000000
L 3.53958346 3.49948287 3.53383327 3.4845 1 P 0 ;0,1,2=293,3=0.000000
L 3.51778356 3.51033346 3.51548337 3.51343278 1 P 0 ;0,1,2=293,3=0.000000
L 3.51548337 3.51343278 3.5127999 3.51498337 1 P 0 ;0,1,2=293,3=0.000000
L 3.5127999 3.51498337 3.50973317 3.5155 1 P 0 ;0,1,2=293,3=0.000000
L 3.50973317 3.5155 3.5059 3.51446683 1 P 0 ;0,1,2=293,3=0.000000
L 3.5059 3.51446683 3.50321654 3.51188307 1 P 0 ;0,1,2=293,3=0.000000
L 3.50321654 3.51188307 3.50245 3.50878376 1 P 0 ;0,1,2=293,3=0.000000
L 3.50245 3.50878376 3.50283327 3.50568258 1 P 0 ;0,1,2=293,3=0.000000
L 3.50283327 3.50568258 3.50436693 3.5030998 1 P 0 ;0,1,2=293,3=0.000000
L 3.50436693 3.5030998 3.51203337 3.49793327 1 P 0 ;0,1,2=293,3=0.000000
L 3.51203337 3.49793327 3.51548337 3.49431644 1 P 0 ;0,1,2=293,3=0.000000
L 3.51548337 3.49431644 3.51778356 3.48914892 1 P 0 ;0,1,2=293,3=0.000000
L 3.51778356 3.48914892 3.5185501 3.4845 1 P 0 ;0,1,2=293,3=0.000000
L 3.5185501 3.4845 3.50245 3.4845 1 P 0 ;0,1,2=293,3=0.000000
L 3.47950039 3.5155 3.48256713 3.51446683 1 P 0 ;0,1,2=293,3=0.000000
L 3.48256713 3.51446683 3.48486663 3.51188307 1 P 0 ;0,1,2=293,3=0.000000
L 3.48486663 3.51188307 3.4864003 3.50878376 1 P 0 ;0,1,2=293,3=0.000000
L 3.4864003 3.50878376 3.4875501 3.50464941 1 P 0 ;0,1,2=293,3=0.000000
L 3.4875501 3.50464941 3.48793337 3.49999951 1 P 0 ;0,1,2=293,3=0.000000
L 3.48793337 3.49999951 3.4875501 3.49534951 1 P 0 ;0,1,2=293,3=0.000000
L 3.4875501 3.49534951 3.4864003 3.49121614 1 P 0 ;0,1,2=293,3=0.000000
L 3.4864003 3.49121614 3.48486663 3.48811585 1 P 0 ;0,1,2=293,3=0.000000
L 3.48486663 3.48811585 3.48256713 3.48553307 1 P 0 ;0,1,2=293,3=0.000000
L 3.48256713 3.48553307 3.47950039 3.4845 1 P 0 ;0,1,2=293,3=0.000000
L 3.47950039 3.4845 3.47643366 3.48553307 1 P 0 ;0,1,2=293,3=0.000000
L 3.47643366 3.48553307 3.47413346 3.48811585 1 P 0 ;0,1,2=293,3=0.000000
L 3.47413346 3.48811585 3.4725998 3.49121614 1 P 0 ;0,1,2=293,3=0.000000
L 3.4725998 3.49121614 3.47145 3.49534951 1 P 0 ;0,1,2=293,3=0.000000
L 3.47145 3.49534951 3.47106673 3.49999951 1 P 0 ;0,1,2=293,3=0.000000
L 3.47106673 3.49999951 3.47145 3.50464941 1 P 0 ;0,1,2=293,3=0.000000
L 3.47145 3.50464941 3.4725998 3.50878376 1 P 0 ;0,1,2=293,3=0.000000
L 3.4725998 3.50878376 3.47413346 3.51188307 1 P 0 ;0,1,2=293,3=0.000000
L 3.47413346 3.51188307 3.47643366 3.51446683 1 P 0 ;0,1,2=293,3=0.000000
L 3.47643366 3.51446683 3.47950039 3.5155 1 P 0 ;0,1,2=293,3=0.000000
L 3.45578356 3.51033346 3.45348337 3.51343278 1 P 0 ;0,1,2=293,3=0.000000
L 3.45348337 3.51343278 3.4507999 3.51498337 1 P 0 ;0,1,2=293,3=0.000000
L 3.4507999 3.51498337 3.44773317 3.5155 1 P 0 ;0,1,2=293,3=0.000000
L 3.44773317 3.5155 3.4439 3.51446683 1 P 0 ;0,1,2=293,3=0.000000
L 3.4439 3.51446683 3.44121654 3.51188307 1 P 0 ;0,1,2=293,3=0.000000
L 3.44121654 3.51188307 3.44045 3.50878376 1 P 0 ;0,1,2=293,3=0.000000
L 3.44045 3.50878376 3.44083327 3.50568258 1 P 0 ;0,1,2=293,3=0.000000
L 3.44083327 3.50568258 3.44236693 3.5030998 1 P 0 ;0,1,2=293,3=0.000000
L 3.44236693 3.5030998 3.45003337 3.49793327 1 P 0 ;0,1,2=293,3=0.000000
L 3.45003337 3.49793327 3.45348337 3.49431644 1 P 0 ;0,1,2=293,3=0.000000
L 3.45348337 3.49431644 3.45578356 3.48914892 1 P 0 ;0,1,2=293,3=0.000000
L 3.45578356 3.48914892 3.4565501 3.4845 1 P 0 ;0,1,2=293,3=0.000000
L 3.4565501 3.4845 3.44045 3.4845 1 P 0 ;0,1,2=293,3=0.000000
L 3.53 3.437 3.53 3.393 1 P 0 
L 3.44 3.437 3.53 3.437 1 P 0 
L 3.53 3.393 3.44 3.393 1 P 0 
L 3.44 3.393 3.44 3.437 1 P 0 
L 3.54916683 3.6295 3.54916683 3.6605 1 P 0 ;0,1,2=294,3=0.000000
L 3.54916683 3.6605 3.53958346 3.6605 1 P 0 ;0,1,2=294,3=0.000000
L 3.53958346 3.6605 3.53651673 3.65894931 1 P 0 ;0,1,2=294,3=0.000000
L 3.53651673 3.65894931 3.5345998 3.65688307 1 P 0 ;0,1,2=294,3=0.000000
L 3.5345998 3.65688307 3.53383327 3.6527497 1 P 0 ;0,1,2=294,3=0.000000
L 3.53383327 3.6527497 3.5345998 3.64861634 1 P 0 ;0,1,2=294,3=0.000000
L 3.5345998 3.64861634 3.5369 3.64603356 1 P 0 ;0,1,2=294,3=0.000000
L 3.5369 3.64603356 3.53958346 3.64448287 1 P 0 ;0,1,2=294,3=0.000000
L 3.53958346 3.64448287 3.54916683 3.64448287 1 P 0 ;0,1,2=294,3=0.000000
L 3.53958346 3.64448287 3.53383327 3.6295 1 P 0 ;0,1,2=294,3=0.000000
L 3.51778356 3.65533346 3.51548337 3.65843278 1 P 0 ;0,1,2=294,3=0.000000
L 3.51548337 3.65843278 3.5127999 3.65998337 1 P 0 ;0,1,2=294,3=0.000000
L 3.5127999 3.65998337 3.50973317 3.6605 1 P 0 ;0,1,2=294,3=0.000000
L 3.50973317 3.6605 3.5059 3.65946683 1 P 0 ;0,1,2=294,3=0.000000
L 3.5059 3.65946683 3.50321654 3.65688307 1 P 0 ;0,1,2=294,3=0.000000
L 3.50321654 3.65688307 3.50245 3.65378376 1 P 0 ;0,1,2=294,3=0.000000
L 3.50245 3.65378376 3.50283327 3.65068258 1 P 0 ;0,1,2=294,3=0.000000
L 3.50283327 3.65068258 3.50436693 3.6480998 1 P 0 ;0,1,2=294,3=0.000000
L 3.50436693 3.6480998 3.51203337 3.64293327 1 P 0 ;0,1,2=294,3=0.000000
L 3.51203337 3.64293327 3.51548337 3.63931644 1 P 0 ;0,1,2=294,3=0.000000
L 3.51548337 3.63931644 3.51778356 3.63414892 1 P 0 ;0,1,2=294,3=0.000000
L 3.51778356 3.63414892 3.5185501 3.6295 1 P 0 ;0,1,2=294,3=0.000000
L 3.5185501 3.6295 3.50245 3.6295 1 P 0 ;0,1,2=294,3=0.000000
L 3.47950039 3.6605 3.48256713 3.65946683 1 P 0 ;0,1,2=294,3=0.000000
L 3.48256713 3.65946683 3.48486663 3.65688307 1 P 0 ;0,1,2=294,3=0.000000
L 3.48486663 3.65688307 3.4864003 3.65378376 1 P 0 ;0,1,2=294,3=0.000000
L 3.4864003 3.65378376 3.4875501 3.64964941 1 P 0 ;0,1,2=294,3=0.000000
L 3.4875501 3.64964941 3.48793337 3.64499951 1 P 0 ;0,1,2=294,3=0.000000
L 3.48793337 3.64499951 3.4875501 3.64034951 1 P 0 ;0,1,2=294,3=0.000000
L 3.4875501 3.64034951 3.4864003 3.63621614 1 P 0 ;0,1,2=294,3=0.000000
L 3.4864003 3.63621614 3.48486663 3.63311585 1 P 0 ;0,1,2=294,3=0.000000
L 3.48486663 3.63311585 3.48256713 3.63053307 1 P 0 ;0,1,2=294,3=0.000000
L 3.48256713 3.63053307 3.47950039 3.6295 1 P 0 ;0,1,2=294,3=0.000000
L 3.47950039 3.6295 3.47643366 3.63053307 1 P 0 ;0,1,2=294,3=0.000000
L 3.47643366 3.63053307 3.47413346 3.63311585 1 P 0 ;0,1,2=294,3=0.000000
L 3.47413346 3.63311585 3.4725998 3.63621614 1 P 0 ;0,1,2=294,3=0.000000
L 3.4725998 3.63621614 3.47145 3.64034951 1 P 0 ;0,1,2=294,3=0.000000
L 3.47145 3.64034951 3.47106673 3.64499951 1 P 0 ;0,1,2=294,3=0.000000
L 3.47106673 3.64499951 3.47145 3.64964941 1 P 0 ;0,1,2=294,3=0.000000
L 3.47145 3.64964941 3.4725998 3.65378376 1 P 0 ;0,1,2=294,3=0.000000
L 3.4725998 3.65378376 3.47413346 3.65688307 1 P 0 ;0,1,2=294,3=0.000000
L 3.47413346 3.65688307 3.47643366 3.65946683 1 P 0 ;0,1,2=294,3=0.000000
L 3.47643366 3.65946683 3.47950039 3.6605 1 P 0 ;0,1,2=294,3=0.000000
L 3.45693337 3.63569961 3.45463386 3.63208278 1 P 0 ;0,1,2=294,3=0.000000
L 3.45463386 3.63208278 3.45156713 3.63001654 1 P 0 ;0,1,2=294,3=0.000000
L 3.45156713 3.63001654 3.44811644 3.6295 1 P 0 ;0,1,2=294,3=0.000000
L 3.44811644 3.6295 3.4450497 3.63001654 1 P 0 ;0,1,2=294,3=0.000000
L 3.4450497 3.63001654 3.44198297 3.63259931 1 P 0 ;0,1,2=294,3=0.000000
L 3.44198297 3.63259931 3.44006673 3.63569961 1 P 0 ;0,1,2=294,3=0.000000
L 3.44006673 3.63569961 3.43968346 3.6387999 1 P 0 ;0,1,2=294,3=0.000000
L 3.43968346 3.6387999 3.44045 3.64241575 1 P 0 ;0,1,2=294,3=0.000000
L 3.44045 3.64241575 3.44313346 3.64499951 1 P 0 ;0,1,2=294,3=0.000000
L 3.44313346 3.64499951 3.44581693 3.64603356 1 P 0 ;0,1,2=294,3=0.000000
L 3.44581693 3.64603356 3.44926693 3.64603356 1 P 0 ;0,1,2=294,3=0.000000
L 3.44581693 3.64603356 3.44351673 3.64758317 1 P 0 ;0,1,2=294,3=0.000000
L 3.44351673 3.64758317 3.4415998 3.65016594 1 P 0 ;0,1,2=294,3=0.000000
L 3.4415998 3.65016594 3.44083327 3.65326624 1 P 0 ;0,1,2=294,3=0.000000
L 3.44083327 3.65326624 3.4415998 3.65636654 1 P 0 ;0,1,2=294,3=0.000000
L 3.4415998 3.65636654 3.44351673 3.65894931 1 P 0 ;0,1,2=294,3=0.000000
L 3.44351673 3.65894931 3.44696673 3.6605 1 P 0 ;0,1,2=294,3=0.000000
L 3.44696673 3.6605 3.45041663 3.65998337 1 P 0 ;0,1,2=294,3=0.000000
L 3.45041663 3.65998337 3.45386663 3.65791624 1 P 0 ;0,1,2=294,3=0.000000
L 3.53 3.347 3.53 3.303 1 P 0 
L 3.44 3.347 3.53 3.347 1 P 0 
L 3.53 3.303 3.44 3.303 1 P 0 
L 3.44 3.303 3.44 3.347 1 P 0 
L 3.54916683 3.5295 3.54916683 3.5605 1 P 0 ;0,1,2=295,3=0.000000
L 3.54916683 3.5605 3.53958346 3.5605 1 P 0 ;0,1,2=295,3=0.000000
L 3.53958346 3.5605 3.53651673 3.55894931 1 P 0 ;0,1,2=295,3=0.000000
L 3.53651673 3.55894931 3.5345998 3.55688307 1 P 0 ;0,1,2=295,3=0.000000
L 3.5345998 3.55688307 3.53383327 3.5527497 1 P 0 ;0,1,2=295,3=0.000000
L 3.53383327 3.5527497 3.5345998 3.54861634 1 P 0 ;0,1,2=295,3=0.000000
L 3.5345998 3.54861634 3.5369 3.54603356 1 P 0 ;0,1,2=295,3=0.000000
L 3.5369 3.54603356 3.53958346 3.54448287 1 P 0 ;0,1,2=295,3=0.000000
L 3.53958346 3.54448287 3.54916683 3.54448287 1 P 0 ;0,1,2=295,3=0.000000
L 3.53958346 3.54448287 3.53383327 3.5295 1 P 0 ;0,1,2=295,3=0.000000
L 3.51050039 3.5295 3.51050039 3.5605 1 P 0 ;0,1,2=295,3=0.000000
L 3.51050039 3.5605 3.5151001 3.5543003 1 P 0 ;0,1,2=295,3=0.000000
L 3.5151001 3.5295 3.50590069 3.5295 1 P 0 ;0,1,2=295,3=0.000000
L 3.48601713 3.53311585 3.48333366 3.53053307 1 P 0 ;0,1,2=295,3=0.000000
L 3.48333366 3.53053307 3.48026693 3.5295 1 P 0 ;0,1,2=295,3=0.000000
L 3.48026693 3.5295 3.4772002 3.53053307 1 P 0 ;0,1,2=295,3=0.000000
L 3.4772002 3.53053307 3.47451673 3.53363238 1 P 0 ;0,1,2=295,3=0.000000
L 3.47451673 3.53363238 3.4725998 3.53828327 1 P 0 ;0,1,2=295,3=0.000000
L 3.4725998 3.53828327 3.47183327 3.54293327 1 P 0 ;0,1,2=295,3=0.000000
L 3.47183327 3.54293327 3.47183327 3.54861634 1 P 0 ;0,1,2=295,3=0.000000
L 3.47183327 3.54861634 3.4725998 3.55326624 1 P 0 ;0,1,2=295,3=0.000000
L 3.4725998 3.55326624 3.47451673 3.5573997 1 P 0 ;0,1,2=295,3=0.000000
L 3.47451673 3.5573997 3.47681693 3.55946683 1 P 0 ;0,1,2=295,3=0.000000
L 3.47681693 3.55946683 3.47950039 3.5605 1 P 0 ;0,1,2=295,3=0.000000
L 3.47950039 3.5605 3.48256713 3.55946683 1 P 0 ;0,1,2=295,3=0.000000
L 3.48256713 3.55946683 3.48486663 3.5573997 1 P 0 ;0,1,2=295,3=0.000000
L 3.48486663 3.5573997 3.4864003 3.5543003 1 P 0 ;0,1,2=295,3=0.000000
L 3.4864003 3.5543003 3.48716683 3.55016594 1 P 0 ;0,1,2=295,3=0.000000
L 3.48716683 3.55016594 3.4864003 3.5465501 1 P 0 ;0,1,2=295,3=0.000000
L 3.4864003 3.5465501 3.48448337 3.54293327 1 P 0 ;0,1,2=295,3=0.000000
L 3.48448337 3.54293327 3.48218317 3.54086604 1 P 0 ;0,1,2=295,3=0.000000
L 3.48218317 3.54086604 3.47950039 3.54034951 1 P 0 ;0,1,2=295,3=0.000000
L 3.47950039 3.54034951 3.47643366 3.54138268 1 P 0 ;0,1,2=295,3=0.000000
L 3.47643366 3.54138268 3.47413346 3.54396634 1 P 0 ;0,1,2=295,3=0.000000
L 3.47413346 3.54396634 3.47183327 3.54861634 1 P 0 ;0,1,2=295,3=0.000000
L 3.45578356 3.55533346 3.45348337 3.55843278 1 P 0 ;0,1,2=295,3=0.000000
L 3.45348337 3.55843278 3.4507999 3.55998337 1 P 0 ;0,1,2=295,3=0.000000
L 3.4507999 3.55998337 3.44773317 3.5605 1 P 0 ;0,1,2=295,3=0.000000
L 3.44773317 3.5605 3.4439 3.55946683 1 P 0 ;0,1,2=295,3=0.000000
L 3.4439 3.55946683 3.44121654 3.55688307 1 P 0 ;0,1,2=295,3=0.000000
L 3.44121654 3.55688307 3.44045 3.55378376 1 P 0 ;0,1,2=295,3=0.000000
L 3.44045 3.55378376 3.44083327 3.55068258 1 P 0 ;0,1,2=295,3=0.000000
L 3.44083327 3.55068258 3.44236693 3.5480998 1 P 0 ;0,1,2=295,3=0.000000
L 3.44236693 3.5480998 3.45003337 3.54293327 1 P 0 ;0,1,2=295,3=0.000000
L 3.45003337 3.54293327 3.45348337 3.53931644 1 P 0 ;0,1,2=295,3=0.000000
L 3.45348337 3.53931644 3.45578356 3.53414892 1 P 0 ;0,1,2=295,3=0.000000
L 3.45578356 3.53414892 3.4565501 3.5295 1 P 0 ;0,1,2=295,3=0.000000
L 3.4565501 3.5295 3.44045 3.5295 1 P 0 ;0,1,2=295,3=0.000000
L 3.53 3.392 3.53 3.348 1 P 0 
L 3.44 3.392 3.53 3.392 1 P 0 
L 3.53 3.348 3.44 3.348 1 P 0 
L 3.44 3.348 3.44 3.392 1 P 0 
L 3.54916683 3.5695 3.54916683 3.6005 1 P 0 ;0,1,2=296,3=0.000000
L 3.54916683 3.6005 3.53958346 3.6005 1 P 0 ;0,1,2=296,3=0.000000
L 3.53958346 3.6005 3.53651673 3.59894931 1 P 0 ;0,1,2=296,3=0.000000
L 3.53651673 3.59894931 3.5345998 3.59688307 1 P 0 ;0,1,2=296,3=0.000000
L 3.5345998 3.59688307 3.53383327 3.5927497 1 P 0 ;0,1,2=296,3=0.000000
L 3.53383327 3.5927497 3.5345998 3.58861634 1 P 0 ;0,1,2=296,3=0.000000
L 3.5345998 3.58861634 3.5369 3.58603356 1 P 0 ;0,1,2=296,3=0.000000
L 3.5369 3.58603356 3.53958346 3.58448287 1 P 0 ;0,1,2=296,3=0.000000
L 3.53958346 3.58448287 3.54916683 3.58448287 1 P 0 ;0,1,2=296,3=0.000000
L 3.53958346 3.58448287 3.53383327 3.5695 1 P 0 ;0,1,2=296,3=0.000000
L 3.51050039 3.5695 3.51050039 3.6005 1 P 0 ;0,1,2=296,3=0.000000
L 3.51050039 3.6005 3.5151001 3.5943003 1 P 0 ;0,1,2=296,3=0.000000
L 3.5151001 3.5695 3.50590069 3.5695 1 P 0 ;0,1,2=296,3=0.000000
L 3.48601713 3.57311585 3.48333366 3.57053307 1 P 0 ;0,1,2=296,3=0.000000
L 3.48333366 3.57053307 3.48026693 3.5695 1 P 0 ;0,1,2=296,3=0.000000
L 3.48026693 3.5695 3.4772002 3.57053307 1 P 0 ;0,1,2=296,3=0.000000
L 3.4772002 3.57053307 3.47451673 3.57363238 1 P 0 ;0,1,2=296,3=0.000000
L 3.47451673 3.57363238 3.4725998 3.57828327 1 P 0 ;0,1,2=296,3=0.000000
L 3.4725998 3.57828327 3.47183327 3.58293327 1 P 0 ;0,1,2=296,3=0.000000
L 3.47183327 3.58293327 3.47183327 3.58861634 1 P 0 ;0,1,2=296,3=0.000000
L 3.47183327 3.58861634 3.4725998 3.59326624 1 P 0 ;0,1,2=296,3=0.000000
L 3.4725998 3.59326624 3.47451673 3.5973997 1 P 0 ;0,1,2=296,3=0.000000
L 3.47451673 3.5973997 3.47681693 3.59946683 1 P 0 ;0,1,2=296,3=0.000000
L 3.47681693 3.59946683 3.47950039 3.6005 1 P 0 ;0,1,2=296,3=0.000000
L 3.47950039 3.6005 3.48256713 3.59946683 1 P 0 ;0,1,2=296,3=0.000000
L 3.48256713 3.59946683 3.48486663 3.5973997 1 P 0 ;0,1,2=296,3=0.000000
L 3.48486663 3.5973997 3.4864003 3.5943003 1 P 0 ;0,1,2=296,3=0.000000
L 3.4864003 3.5943003 3.48716683 3.59016594 1 P 0 ;0,1,2=296,3=0.000000
L 3.48716683 3.59016594 3.4864003 3.5865501 1 P 0 ;0,1,2=296,3=0.000000
L 3.4864003 3.5865501 3.48448337 3.58293327 1 P 0 ;0,1,2=296,3=0.000000
L 3.48448337 3.58293327 3.48218317 3.58086604 1 P 0 ;0,1,2=296,3=0.000000
L 3.48218317 3.58086604 3.47950039 3.58034951 1 P 0 ;0,1,2=296,3=0.000000
L 3.47950039 3.58034951 3.47643366 3.58138268 1 P 0 ;0,1,2=296,3=0.000000
L 3.47643366 3.58138268 3.47413346 3.58396634 1 P 0 ;0,1,2=296,3=0.000000
L 3.47413346 3.58396634 3.47183327 3.58861634 1 P 0 ;0,1,2=296,3=0.000000
L 3.45501713 3.57311585 3.45233366 3.57053307 1 P 0 ;0,1,2=296,3=0.000000
L 3.45233366 3.57053307 3.44926693 3.5695 1 P 0 ;0,1,2=296,3=0.000000
L 3.44926693 3.5695 3.4462002 3.57053307 1 P 0 ;0,1,2=296,3=0.000000
L 3.4462002 3.57053307 3.44351673 3.57363238 1 P 0 ;0,1,2=296,3=0.000000
L 3.44351673 3.57363238 3.4415998 3.57828327 1 P 0 ;0,1,2=296,3=0.000000
L 3.4415998 3.57828327 3.44083327 3.58293327 1 P 0 ;0,1,2=296,3=0.000000
L 3.44083327 3.58293327 3.44083327 3.58861634 1 P 0 ;0,1,2=296,3=0.000000
L 3.44083327 3.58861634 3.4415998 3.59326624 1 P 0 ;0,1,2=296,3=0.000000
L 3.4415998 3.59326624 3.44351673 3.5973997 1 P 0 ;0,1,2=296,3=0.000000
L 3.44351673 3.5973997 3.44581693 3.59946683 1 P 0 ;0,1,2=296,3=0.000000
L 3.44581693 3.59946683 3.44850039 3.6005 1 P 0 ;0,1,2=296,3=0.000000
L 3.44850039 3.6005 3.45156713 3.59946683 1 P 0 ;0,1,2=296,3=0.000000
L 3.45156713 3.59946683 3.45386663 3.5973997 1 P 0 ;0,1,2=296,3=0.000000
L 3.45386663 3.5973997 3.4554003 3.5943003 1 P 0 ;0,1,2=296,3=0.000000
L 3.4554003 3.5943003 3.45616683 3.59016594 1 P 0 ;0,1,2=296,3=0.000000
L 3.45616683 3.59016594 3.4554003 3.5865501 1 P 0 ;0,1,2=296,3=0.000000
L 3.4554003 3.5865501 3.45348337 3.58293327 1 P 0 ;0,1,2=296,3=0.000000
L 3.45348337 3.58293327 3.45118317 3.58086604 1 P 0 ;0,1,2=296,3=0.000000
L 3.45118317 3.58086604 3.44850039 3.58034951 1 P 0 ;0,1,2=296,3=0.000000
L 3.44850039 3.58034951 3.44543366 3.58138268 1 P 0 ;0,1,2=296,3=0.000000
L 3.44543366 3.58138268 3.44313346 3.58396634 1 P 0 ;0,1,2=296,3=0.000000
L 3.44313346 3.58396634 3.44083327 3.58861634 1 P 0 ;0,1,2=296,3=0.000000
L 3.507 2.93 3.507 2.84 1 P 0 
L 3.463 2.93 3.507 2.93 1 P 0 
L 3.507 2.84 3.463 2.84 1 P 0 
L 3.463 2.84 3.463 2.93 1 P 0 
L 3.4645 2.69083317 3.4955 2.69083317 1 P 0 ;0,1,2=297,3=90.000000
L 3.4955 2.69083317 3.4955 2.70041654 1 P 0 ;0,1,2=297,3=90.000000
L 3.4955 2.70041654 3.49394931 2.70348327 1 P 0 ;0,1,2=297,3=90.000000
L 3.49394931 2.70348327 3.49188307 2.7054002 1 P 0 ;0,1,2=297,3=90.000000
L 3.49188307 2.7054002 3.4877497 2.70616673 1 P 0 ;0,1,2=297,3=90.000000
L 3.4877497 2.70616673 3.48361634 2.7054002 1 P 0 ;0,1,2=297,3=90.000000
L 3.48361634 2.7054002 3.48103356 2.7031 1 P 0 ;0,1,2=297,3=90.000000
L 3.48103356 2.7031 3.47948287 2.70041654 1 P 0 ;0,1,2=297,3=90.000000
L 3.47948287 2.70041654 3.47948287 2.69083317 1 P 0 ;0,1,2=297,3=90.000000
L 3.47948287 2.70041654 3.4645 2.70616673 1 P 0 ;0,1,2=297,3=90.000000
L 3.47069961 2.72106663 3.46708278 2.72336614 1 P 0 ;0,1,2=297,3=90.000000
L 3.46708278 2.72336614 3.46501654 2.72643287 1 P 0 ;0,1,2=297,3=90.000000
L 3.46501654 2.72643287 3.4645 2.72988356 1 P 0 ;0,1,2=297,3=90.000000
L 3.4645 2.72988356 3.46501654 2.7329503 1 P 0 ;0,1,2=297,3=90.000000
L 3.46501654 2.7329503 3.46759931 2.73601703 1 P 0 ;0,1,2=297,3=90.000000
L 3.46759931 2.73601703 3.47069961 2.73793327 1 P 0 ;0,1,2=297,3=90.000000
L 3.47069961 2.73793327 3.4737999 2.73831654 1 P 0 ;0,1,2=297,3=90.000000
L 3.4737999 2.73831654 3.47741575 2.73755 1 P 0 ;0,1,2=297,3=90.000000
L 3.47741575 2.73755 3.47999951 2.73486654 1 P 0 ;0,1,2=297,3=90.000000
L 3.47999951 2.73486654 3.48103356 2.73218307 1 P 0 ;0,1,2=297,3=90.000000
L 3.48103356 2.73218307 3.48103356 2.72873307 1 P 0 ;0,1,2=297,3=90.000000
L 3.48103356 2.73218307 3.48258317 2.73448327 1 P 0 ;0,1,2=297,3=90.000000
L 3.48258317 2.73448327 3.48516594 2.7364002 1 P 0 ;0,1,2=297,3=90.000000
L 3.48516594 2.7364002 3.48826624 2.73716673 1 P 0 ;0,1,2=297,3=90.000000
L 3.48826624 2.73716673 3.49136654 2.7364002 1 P 0 ;0,1,2=297,3=90.000000
L 3.49136654 2.7364002 3.49394931 2.73448327 1 P 0 ;0,1,2=297,3=90.000000
L 3.49394931 2.73448327 3.4955 2.73103327 1 P 0 ;0,1,2=297,3=90.000000
L 3.4955 2.73103327 3.49498337 2.72758337 1 P 0 ;0,1,2=297,3=90.000000
L 3.49498337 2.72758337 3.49291624 2.72413337 1 P 0 ;0,1,2=297,3=90.000000
L 3.4645 2.7651 3.4955 2.7651 1 P 0 ;0,1,2=297,3=90.000000
L 3.4955 2.7651 3.47328327 2.75091624 1 P 0 ;0,1,2=297,3=90.000000
L 3.47328327 2.75091624 3.47328327 2.77008366 1 P 0 ;0,1,2=297,3=90.000000
L 3.4645 2.79149961 3.4955 2.79149961 1 P 0 ;0,1,2=297,3=90.000000
L 3.4955 2.79149961 3.4893003 2.7868999 1 P 0 ;0,1,2=297,3=90.000000
L 3.4645 2.7868999 3.4645 2.79609931 1 P 0 ;0,1,2=297,3=90.000000
L 3.418 2.93 3.462 2.93 1 P 0 
L 3.462 2.93 3.462 2.84 1 P 0 
L 3.462 2.84 3.418 2.84 1 P 0 
L 3.418 2.84 3.418 2.93 1 P 0 
L 3.4195 2.69083317 3.4505 2.69083317 1 P 0 ;0,1,2=298,3=90.000000
L 3.4505 2.69083317 3.4505 2.70041654 1 P 0 ;0,1,2=298,3=90.000000
L 3.4505 2.70041654 3.44894931 2.70348327 1 P 0 ;0,1,2=298,3=90.000000
L 3.44894931 2.70348327 3.44688307 2.7054002 1 P 0 ;0,1,2=298,3=90.000000
L 3.44688307 2.7054002 3.4427497 2.70616673 1 P 0 ;0,1,2=298,3=90.000000
L 3.4427497 2.70616673 3.43861634 2.7054002 1 P 0 ;0,1,2=298,3=90.000000
L 3.43861634 2.7054002 3.43603356 2.7031 1 P 0 ;0,1,2=298,3=90.000000
L 3.43603356 2.7031 3.43448287 2.70041654 1 P 0 ;0,1,2=298,3=90.000000
L 3.43448287 2.70041654 3.43448287 2.69083317 1 P 0 ;0,1,2=298,3=90.000000
L 3.43448287 2.70041654 3.4195 2.70616673 1 P 0 ;0,1,2=298,3=90.000000
L 3.42569961 2.72106663 3.42208278 2.72336614 1 P 0 ;0,1,2=298,3=90.000000
L 3.42208278 2.72336614 3.42001654 2.72643287 1 P 0 ;0,1,2=298,3=90.000000
L 3.42001654 2.72643287 3.4195 2.72988356 1 P 0 ;0,1,2=298,3=90.000000
L 3.4195 2.72988356 3.42001654 2.7329503 1 P 0 ;0,1,2=298,3=90.000000
L 3.42001654 2.7329503 3.42259931 2.73601703 1 P 0 ;0,1,2=298,3=90.000000
L 3.42259931 2.73601703 3.42569961 2.73793327 1 P 0 ;0,1,2=298,3=90.000000
L 3.42569961 2.73793327 3.4287999 2.73831654 1 P 0 ;0,1,2=298,3=90.000000
L 3.4287999 2.73831654 3.43241575 2.73755 1 P 0 ;0,1,2=298,3=90.000000
L 3.43241575 2.73755 3.43499951 2.73486654 1 P 0 ;0,1,2=298,3=90.000000
L 3.43499951 2.73486654 3.43603356 2.73218307 1 P 0 ;0,1,2=298,3=90.000000
L 3.43603356 2.73218307 3.43603356 2.72873307 1 P 0 ;0,1,2=298,3=90.000000
L 3.43603356 2.73218307 3.43758317 2.73448327 1 P 0 ;0,1,2=298,3=90.000000
L 3.43758317 2.73448327 3.44016594 2.7364002 1 P 0 ;0,1,2=298,3=90.000000
L 3.44016594 2.7364002 3.44326624 2.73716673 1 P 0 ;0,1,2=298,3=90.000000
L 3.44326624 2.73716673 3.44636654 2.7364002 1 P 0 ;0,1,2=298,3=90.000000
L 3.44636654 2.7364002 3.44894931 2.73448327 1 P 0 ;0,1,2=298,3=90.000000
L 3.44894931 2.73448327 3.4505 2.73103327 1 P 0 ;0,1,2=298,3=90.000000
L 3.4505 2.73103327 3.44998337 2.72758337 1 P 0 ;0,1,2=298,3=90.000000
L 3.44998337 2.72758337 3.44791624 2.72413337 1 P 0 ;0,1,2=298,3=90.000000
L 3.42569961 2.75206663 3.42208278 2.75436614 1 P 0 ;0,1,2=298,3=90.000000
L 3.42208278 2.75436614 3.42001654 2.75743287 1 P 0 ;0,1,2=298,3=90.000000
L 3.42001654 2.75743287 3.4195 2.76088356 1 P 0 ;0,1,2=298,3=90.000000
L 3.4195 2.76088356 3.42001654 2.7639503 1 P 0 ;0,1,2=298,3=90.000000
L 3.42001654 2.7639503 3.42259931 2.76701703 1 P 0 ;0,1,2=298,3=90.000000
L 3.42259931 2.76701703 3.42569961 2.76893327 1 P 0 ;0,1,2=298,3=90.000000
L 3.42569961 2.76893327 3.4287999 2.76931654 1 P 0 ;0,1,2=298,3=90.000000
L 3.4287999 2.76931654 3.43241575 2.76855 1 P 0 ;0,1,2=298,3=90.000000
L 3.43241575 2.76855 3.43499951 2.76586654 1 P 0 ;0,1,2=298,3=90.000000
L 3.43499951 2.76586654 3.43603356 2.76318307 1 P 0 ;0,1,2=298,3=90.000000
L 3.43603356 2.76318307 3.43603356 2.75973307 1 P 0 ;0,1,2=298,3=90.000000
L 3.43603356 2.76318307 3.43758317 2.76548327 1 P 0 ;0,1,2=298,3=90.000000
L 3.43758317 2.76548327 3.44016594 2.7674002 1 P 0 ;0,1,2=298,3=90.000000
L 3.44016594 2.7674002 3.44326624 2.76816673 1 P 0 ;0,1,2=298,3=90.000000
L 3.44326624 2.76816673 3.44636654 2.7674002 1 P 0 ;0,1,2=298,3=90.000000
L 3.44636654 2.7674002 3.44894931 2.76548327 1 P 0 ;0,1,2=298,3=90.000000
L 3.44894931 2.76548327 3.4505 2.76203327 1 P 0 ;0,1,2=298,3=90.000000
L 3.4505 2.76203327 3.44998337 2.75858337 1 P 0 ;0,1,2=298,3=90.000000
L 3.44998337 2.75858337 3.44791624 2.75513337 1 P 0 ;0,1,2=298,3=90.000000
L 3.4505 2.79149961 3.44946683 2.78843287 1 P 0 ;0,1,2=298,3=90.000000
L 3.44946683 2.78843287 3.44688307 2.78613337 1 P 0 ;0,1,2=298,3=90.000000
L 3.44688307 2.78613337 3.44378376 2.7845997 1 P 0 ;0,1,2=298,3=90.000000
L 3.44378376 2.7845997 3.43964941 2.7834499 1 P 0 ;0,1,2=298,3=90.000000
L 3.43964941 2.7834499 3.43499951 2.78306663 1 P 0 ;0,1,2=298,3=90.000000
L 3.43499951 2.78306663 3.43034951 2.7834499 1 P 0 ;0,1,2=298,3=90.000000
L 3.43034951 2.7834499 3.42621614 2.7845997 1 P 0 ;0,1,2=298,3=90.000000
L 3.42621614 2.7845997 3.42311585 2.78613337 1 P 0 ;0,1,2=298,3=90.000000
L 3.42311585 2.78613337 3.42053307 2.78843287 1 P 0 ;0,1,2=298,3=90.000000
L 3.42053307 2.78843287 3.4195 2.79149961 1 P 0 ;0,1,2=298,3=90.000000
L 3.4195 2.79149961 3.42053307 2.79456634 1 P 0 ;0,1,2=298,3=90.000000
L 3.42053307 2.79456634 3.42311585 2.79686654 1 P 0 ;0,1,2=298,3=90.000000
L 3.42311585 2.79686654 3.42621614 2.7984002 1 P 0 ;0,1,2=298,3=90.000000
L 3.42621614 2.7984002 3.43034951 2.79955 1 P 0 ;0,1,2=298,3=90.000000
L 3.43034951 2.79955 3.43499951 2.79993327 1 P 0 ;0,1,2=298,3=90.000000
L 3.43499951 2.79993327 3.43964941 2.79955 1 P 0 ;0,1,2=298,3=90.000000
L 3.43964941 2.79955 3.44378376 2.7984002 1 P 0 ;0,1,2=298,3=90.000000
L 3.44378376 2.7984002 3.44688307 2.79686654 1 P 0 ;0,1,2=298,3=90.000000
L 3.44688307 2.79686654 3.44946683 2.79456634 1 P 0 ;0,1,2=298,3=90.000000
L 3.44946683 2.79456634 3.4505 2.79149961 1 P 0 ;0,1,2=298,3=90.000000
L 4.913 3.57 4.957 3.57 1 P 0 
L 4.913 3.48 4.913 3.57 1 P 0 
L 4.957 3.57 4.957 3.48 1 P 0 
L 4.957 3.48 4.913 3.48 1 P 0 
L 4.9245 3.61583317 4.9555 3.61583317 1 P 0 ;0,1,2=299,3=90.000000
L 4.9555 3.61583317 4.9555 3.62541654 1 P 0 ;0,1,2=299,3=90.000000
L 4.9555 3.62541654 4.95394931 3.62848327 1 P 0 ;0,1,2=299,3=90.000000
L 4.95394931 3.62848327 4.95188307 3.6304002 1 P 0 ;0,1,2=299,3=90.000000
L 4.95188307 3.6304002 4.9477497 3.63116673 1 P 0 ;0,1,2=299,3=90.000000
L 4.9477497 3.63116673 4.94361634 3.6304002 1 P 0 ;0,1,2=299,3=90.000000
L 4.94361634 3.6304002 4.94103356 3.6281 1 P 0 ;0,1,2=299,3=90.000000
L 4.94103356 3.6281 4.93948287 3.62541654 1 P 0 ;0,1,2=299,3=90.000000
L 4.93948287 3.62541654 4.93948287 3.61583317 1 P 0 ;0,1,2=299,3=90.000000
L 4.93948287 3.62541654 4.9245 3.63116673 1 P 0 ;0,1,2=299,3=90.000000
L 4.9245 3.65449961 4.9555 3.65449961 1 P 0 ;0,1,2=299,3=90.000000
L 4.9555 3.65449961 4.9493003 3.6498999 1 P 0 ;0,1,2=299,3=90.000000
L 4.9245 3.6498999 4.9245 3.65909931 1 P 0 ;0,1,2=299,3=90.000000
L 4.9245 3.68549961 4.9555 3.68549961 1 P 0 ;0,1,2=299,3=90.000000
L 4.9555 3.68549961 4.9493003 3.6808999 1 P 0 ;0,1,2=299,3=90.000000
L 4.9245 3.6808999 4.9245 3.69009931 1 P 0 ;0,1,2=299,3=90.000000
L 4.9555 3.71649961 4.95446683 3.71343287 1 P 0 ;0,1,2=299,3=90.000000
L 4.95446683 3.71343287 4.95188307 3.71113337 1 P 0 ;0,1,2=299,3=90.000000
L 4.95188307 3.71113337 4.94878376 3.7095997 1 P 0 ;0,1,2=299,3=90.000000
L 4.94878376 3.7095997 4.94464941 3.7084499 1 P 0 ;0,1,2=299,3=90.000000
L 4.94464941 3.7084499 4.93999951 3.70806663 1 P 0 ;0,1,2=299,3=90.000000
L 4.93999951 3.70806663 4.93534951 3.7084499 1 P 0 ;0,1,2=299,3=90.000000
L 4.93534951 3.7084499 4.93121614 3.7095997 1 P 0 ;0,1,2=299,3=90.000000
L 4.93121614 3.7095997 4.92811585 3.71113337 1 P 0 ;0,1,2=299,3=90.000000
L 4.92811585 3.71113337 4.92553307 3.71343287 1 P 0 ;0,1,2=299,3=90.000000
L 4.92553307 3.71343287 4.9245 3.71649961 1 P 0 ;0,1,2=299,3=90.000000
L 4.9245 3.71649961 4.92553307 3.71956634 1 P 0 ;0,1,2=299,3=90.000000
L 4.92553307 3.71956634 4.92811585 3.72186654 1 P 0 ;0,1,2=299,3=90.000000
L 4.92811585 3.72186654 4.93121614 3.7234002 1 P 0 ;0,1,2=299,3=90.000000
L 4.93121614 3.7234002 4.93534951 3.72455 1 P 0 ;0,1,2=299,3=90.000000
L 4.93534951 3.72455 4.93999951 3.72493327 1 P 0 ;0,1,2=299,3=90.000000
L 4.93999951 3.72493327 4.94464941 3.72455 1 P 0 ;0,1,2=299,3=90.000000
L 4.94464941 3.72455 4.94878376 3.7234002 1 P 0 ;0,1,2=299,3=90.000000
L 4.94878376 3.7234002 4.95188307 3.72186654 1 P 0 ;0,1,2=299,3=90.000000
L 4.95188307 3.72186654 4.95446683 3.71956634 1 P 0 ;0,1,2=299,3=90.000000
L 4.95446683 3.71956634 4.9555 3.71649961 1 P 0 ;0,1,2=299,3=90.000000
L 5.055 3.477 5.055 3.433 1 P 0 
L 4.965 3.477 5.055 3.477 1 P 0 
L 5.055 3.433 4.965 3.433 1 P 0 
L 4.965 3.433 4.965 3.477 1 P 0 
L 5.17416683 3.4345 5.17416683 3.4655 1 P 0 ;0,1,2=300,3=0.000000
L 5.17416683 3.4655 5.16458346 3.4655 1 P 0 ;0,1,2=300,3=0.000000
L 5.16458346 3.4655 5.16151673 3.46394931 1 P 0 ;0,1,2=300,3=0.000000
L 5.16151673 3.46394931 5.1595998 3.46188307 1 P 0 ;0,1,2=300,3=0.000000
L 5.1595998 3.46188307 5.15883327 3.4577497 1 P 0 ;0,1,2=300,3=0.000000
L 5.15883327 3.4577497 5.1595998 3.45361634 1 P 0 ;0,1,2=300,3=0.000000
L 5.1595998 3.45361634 5.1619 3.45103356 1 P 0 ;0,1,2=300,3=0.000000
L 5.1619 3.45103356 5.16458346 3.44948287 1 P 0 ;0,1,2=300,3=0.000000
L 5.16458346 3.44948287 5.17416683 3.44948287 1 P 0 ;0,1,2=300,3=0.000000
L 5.16458346 3.44948287 5.15883327 3.4345 1 P 0 ;0,1,2=300,3=0.000000
L 5.14278356 3.46033346 5.14048337 3.46343278 1 P 0 ;0,1,2=300,3=0.000000
L 5.14048337 3.46343278 5.1377999 3.46498337 1 P 0 ;0,1,2=300,3=0.000000
L 5.1377999 3.46498337 5.13473317 3.4655 1 P 0 ;0,1,2=300,3=0.000000
L 5.13473317 3.4655 5.1309 3.46446683 1 P 0 ;0,1,2=300,3=0.000000
L 5.1309 3.46446683 5.12821654 3.46188307 1 P 0 ;0,1,2=300,3=0.000000
L 5.12821654 3.46188307 5.12745 3.45878376 1 P 0 ;0,1,2=300,3=0.000000
L 5.12745 3.45878376 5.12783327 3.45568258 1 P 0 ;0,1,2=300,3=0.000000
L 5.12783327 3.45568258 5.12936693 3.4530998 1 P 0 ;0,1,2=300,3=0.000000
L 5.12936693 3.4530998 5.13703337 3.44793327 1 P 0 ;0,1,2=300,3=0.000000
L 5.13703337 3.44793327 5.14048337 3.44431644 1 P 0 ;0,1,2=300,3=0.000000
L 5.14048337 3.44431644 5.14278356 3.43914892 1 P 0 ;0,1,2=300,3=0.000000
L 5.14278356 3.43914892 5.1435501 3.4345 1 P 0 ;0,1,2=300,3=0.000000
L 5.1435501 3.4345 5.12745 3.4345 1 P 0 ;0,1,2=300,3=0.000000
L 5.11178356 3.44741575 5.1091001 3.45103356 1 P 0 ;0,1,2=300,3=0.000000
L 5.1091001 3.45103356 5.1067999 3.4530998 1 P 0 ;0,1,2=300,3=0.000000
L 5.1067999 3.4530998 5.10373317 3.45413287 1 P 0 ;0,1,2=300,3=0.000000
L 5.10373317 3.45413287 5.1010497 3.4530998 1 P 0 ;0,1,2=300,3=0.000000
L 5.1010497 3.4530998 5.09913346 3.45103356 1 P 0 ;0,1,2=300,3=0.000000
L 5.09913346 3.45103356 5.0975998 3.44793327 1 P 0 ;0,1,2=300,3=0.000000
L 5.0975998 3.44793327 5.09721654 3.44431644 1 P 0 ;0,1,2=300,3=0.000000
L 5.09721654 3.44431644 5.0975998 3.44121614 1 P 0 ;0,1,2=300,3=0.000000
L 5.0975998 3.44121614 5.09913346 3.43811585 1 P 0 ;0,1,2=300,3=0.000000
L 5.09913346 3.43811585 5.10143366 3.43553307 1 P 0 ;0,1,2=300,3=0.000000
L 5.10143366 3.43553307 5.10411644 3.4345 1 P 0 ;0,1,2=300,3=0.000000
L 5.10411644 3.4345 5.10718317 3.43553307 1 P 0 ;0,1,2=300,3=0.000000
L 5.10718317 3.43553307 5.10986663 3.43863238 1 P 0 ;0,1,2=300,3=0.000000
L 5.10986663 3.43863238 5.1114003 3.44328327 1 P 0 ;0,1,2=300,3=0.000000
L 5.1114003 3.44328327 5.11178356 3.4484498 1 P 0 ;0,1,2=300,3=0.000000
L 5.11178356 3.4484498 5.11101713 3.45516594 1 P 0 ;0,1,2=300,3=0.000000
L 5.11101713 3.45516594 5.10986663 3.45878376 1 P 0 ;0,1,2=300,3=0.000000
L 5.10986663 3.45878376 5.10795039 3.4623997 1 P 0 ;0,1,2=300,3=0.000000
L 5.10795039 3.4623997 5.10526693 3.46498337 1 P 0 ;0,1,2=300,3=0.000000
L 5.10526693 3.46498337 5.10258346 3.4655 1 P 0 ;0,1,2=300,3=0.000000
L 5.10258346 3.4655 5.0999 3.46446683 1 P 0 ;0,1,2=300,3=0.000000
L 5.0999 3.46446683 5.09798297 3.46188307 1 P 0 ;0,1,2=300,3=0.000000
L 5.08001713 3.43811585 5.07733366 3.43553307 1 P 0 ;0,1,2=300,3=0.000000
L 5.07733366 3.43553307 5.07426693 3.4345 1 P 0 ;0,1,2=300,3=0.000000
L 5.07426693 3.4345 5.0712002 3.43553307 1 P 0 ;0,1,2=300,3=0.000000
L 5.0712002 3.43553307 5.06851673 3.43863238 1 P 0 ;0,1,2=300,3=0.000000
L 5.06851673 3.43863238 5.0665998 3.44328327 1 P 0 ;0,1,2=300,3=0.000000
L 5.0665998 3.44328327 5.06583327 3.44793327 1 P 0 ;0,1,2=300,3=0.000000
L 5.06583327 3.44793327 5.06583327 3.45361634 1 P 0 ;0,1,2=300,3=0.000000
L 5.06583327 3.45361634 5.0665998 3.45826624 1 P 0 ;0,1,2=300,3=0.000000
L 5.0665998 3.45826624 5.06851673 3.4623997 1 P 0 ;0,1,2=300,3=0.000000
L 5.06851673 3.4623997 5.07081693 3.46446683 1 P 0 ;0,1,2=300,3=0.000000
L 5.07081693 3.46446683 5.07350039 3.4655 1 P 0 ;0,1,2=300,3=0.000000
L 5.07350039 3.4655 5.07656713 3.46446683 1 P 0 ;0,1,2=300,3=0.000000
L 5.07656713 3.46446683 5.07886663 3.4623997 1 P 0 ;0,1,2=300,3=0.000000
L 5.07886663 3.4623997 5.0804003 3.4593003 1 P 0 ;0,1,2=300,3=0.000000
L 5.0804003 3.4593003 5.08116683 3.45516594 1 P 0 ;0,1,2=300,3=0.000000
L 5.08116683 3.45516594 5.0804003 3.4515501 1 P 0 ;0,1,2=300,3=0.000000
L 5.0804003 3.4515501 5.07848337 3.44793327 1 P 0 ;0,1,2=300,3=0.000000
L 5.07848337 3.44793327 5.07618317 3.44586604 1 P 0 ;0,1,2=300,3=0.000000
L 5.07618317 3.44586604 5.07350039 3.44534951 1 P 0 ;0,1,2=300,3=0.000000
L 5.07350039 3.44534951 5.07043366 3.44638268 1 P 0 ;0,1,2=300,3=0.000000
L 5.07043366 3.44638268 5.06813346 3.44896634 1 P 0 ;0,1,2=300,3=0.000000
L 5.06813346 3.44896634 5.06583327 3.45361634 1 P 0 ;0,1,2=300,3=0.000000
L 4.963 3.57 5.007 3.57 1 P 0 
L 4.963 3.48 4.963 3.57 1 P 0 
L 5.007 3.57 5.007 3.48 1 P 0 
L 5.007 3.48 4.963 3.48 1 P 0 
L 4.9695 3.58083317 5.0005 3.58083317 1 P 0 ;0,1,2=301,3=90.000000
L 5.0005 3.58083317 5.0005 3.59041654 1 P 0 ;0,1,2=301,3=90.000000
L 5.0005 3.59041654 4.99894931 3.59348327 1 P 0 ;0,1,2=301,3=90.000000
L 4.99894931 3.59348327 4.99688307 3.5954002 1 P 0 ;0,1,2=301,3=90.000000
L 4.99688307 3.5954002 4.9927497 3.59616673 1 P 0 ;0,1,2=301,3=90.000000
L 4.9927497 3.59616673 4.98861634 3.5954002 1 P 0 ;0,1,2=301,3=90.000000
L 4.98861634 3.5954002 4.98603356 3.5931 1 P 0 ;0,1,2=301,3=90.000000
L 4.98603356 3.5931 4.98448287 3.59041654 1 P 0 ;0,1,2=301,3=90.000000
L 4.98448287 3.59041654 4.98448287 3.58083317 1 P 0 ;0,1,2=301,3=90.000000
L 4.98448287 3.59041654 4.9695 3.59616673 1 P 0 ;0,1,2=301,3=90.000000
L 4.9695 3.61949961 5.0005 3.61949961 1 P 0 ;0,1,2=301,3=90.000000
L 5.0005 3.61949961 4.9943003 3.6148999 1 P 0 ;0,1,2=301,3=90.000000
L 4.9695 3.6148999 4.9695 3.62409931 1 P 0 ;0,1,2=301,3=90.000000
L 5.0005 3.65049961 4.99946683 3.64743287 1 P 0 ;0,1,2=301,3=90.000000
L 4.99946683 3.64743287 4.99688307 3.64513337 1 P 0 ;0,1,2=301,3=90.000000
L 4.99688307 3.64513337 4.99378376 3.6435997 1 P 0 ;0,1,2=301,3=90.000000
L 4.99378376 3.6435997 4.98964941 3.6424499 1 P 0 ;0,1,2=301,3=90.000000
L 4.98964941 3.6424499 4.98499951 3.64206663 1 P 0 ;0,1,2=301,3=90.000000
L 4.98499951 3.64206663 4.98034951 3.6424499 1 P 0 ;0,1,2=301,3=90.000000
L 4.98034951 3.6424499 4.97621614 3.6435997 1 P 0 ;0,1,2=301,3=90.000000
L 4.97621614 3.6435997 4.97311585 3.64513337 1 P 0 ;0,1,2=301,3=90.000000
L 4.97311585 3.64513337 4.97053307 3.64743287 1 P 0 ;0,1,2=301,3=90.000000
L 4.97053307 3.64743287 4.9695 3.65049961 1 P 0 ;0,1,2=301,3=90.000000
L 4.9695 3.65049961 4.97053307 3.65356634 1 P 0 ;0,1,2=301,3=90.000000
L 4.97053307 3.65356634 4.97311585 3.65586654 1 P 0 ;0,1,2=301,3=90.000000
L 4.97311585 3.65586654 4.97621614 3.6574002 1 P 0 ;0,1,2=301,3=90.000000
L 4.97621614 3.6574002 4.98034951 3.65855 1 P 0 ;0,1,2=301,3=90.000000
L 4.98034951 3.65855 4.98499951 3.65893327 1 P 0 ;0,1,2=301,3=90.000000
L 4.98499951 3.65893327 4.98964941 3.65855 1 P 0 ;0,1,2=301,3=90.000000
L 4.98964941 3.65855 4.99378376 3.6574002 1 P 0 ;0,1,2=301,3=90.000000
L 4.99378376 3.6574002 4.99688307 3.65586654 1 P 0 ;0,1,2=301,3=90.000000
L 4.99688307 3.65586654 4.99946683 3.65356634 1 P 0 ;0,1,2=301,3=90.000000
L 4.99946683 3.65356634 5.0005 3.65049961 1 P 0 ;0,1,2=301,3=90.000000
L 4.97311585 3.67498287 4.97053307 3.67766634 1 P 0 ;0,1,2=301,3=90.000000
L 4.97053307 3.67766634 4.9695 3.68073307 1 P 0 ;0,1,2=301,3=90.000000
L 4.9695 3.68073307 4.97053307 3.6837998 1 P 0 ;0,1,2=301,3=90.000000
L 4.97053307 3.6837998 4.97363238 3.68648327 1 P 0 ;0,1,2=301,3=90.000000
L 4.97363238 3.68648327 4.97828327 3.6884002 1 P 0 ;0,1,2=301,3=90.000000
L 4.97828327 3.6884002 4.98293327 3.68916673 1 P 0 ;0,1,2=301,3=90.000000
L 4.98293327 3.68916673 4.98861634 3.68916673 1 P 0 ;0,1,2=301,3=90.000000
L 4.98861634 3.68916673 4.99326624 3.6884002 1 P 0 ;0,1,2=301,3=90.000000
L 4.99326624 3.6884002 4.9973997 3.68648327 1 P 0 ;0,1,2=301,3=90.000000
L 4.9973997 3.68648327 4.99946683 3.68418307 1 P 0 ;0,1,2=301,3=90.000000
L 4.99946683 3.68418307 5.0005 3.68149961 1 P 0 ;0,1,2=301,3=90.000000
L 5.0005 3.68149961 4.99946683 3.67843287 1 P 0 ;0,1,2=301,3=90.000000
L 4.99946683 3.67843287 4.9973997 3.67613337 1 P 0 ;0,1,2=301,3=90.000000
L 4.9973997 3.67613337 4.9943003 3.6745997 1 P 0 ;0,1,2=301,3=90.000000
L 4.9943003 3.6745997 4.99016594 3.67383317 1 P 0 ;0,1,2=301,3=90.000000
L 4.99016594 3.67383317 4.9865501 3.6745997 1 P 0 ;0,1,2=301,3=90.000000
L 4.9865501 3.6745997 4.98293327 3.67651663 1 P 0 ;0,1,2=301,3=90.000000
L 4.98293327 3.67651663 4.98086604 3.67881683 1 P 0 ;0,1,2=301,3=90.000000
L 4.98086604 3.67881683 4.98034951 3.68149961 1 P 0 ;0,1,2=301,3=90.000000
L 4.98034951 3.68149961 4.98138268 3.68456634 1 P 0 ;0,1,2=301,3=90.000000
L 4.98138268 3.68456634 4.98396634 3.68686654 1 P 0 ;0,1,2=301,3=90.000000
L 4.98396634 3.68686654 4.98861634 3.68916673 1 P 0 ;0,1,2=301,3=90.000000
L 4.907 3.57 4.907 3.48 1 P 0 
L 4.863 3.57 4.907 3.57 1 P 0 
L 4.863 3.48 4.863 3.57 1 P 0 
L 4.907 3.48 4.863 3.48 1 P 0 
L 4.8745 3.61583317 4.9055 3.61583317 1 P 0 ;0,1,2=302,3=90.000000
L 4.9055 3.61583317 4.9055 3.62541654 1 P 0 ;0,1,2=302,3=90.000000
L 4.9055 3.62541654 4.90394931 3.62848327 1 P 0 ;0,1,2=302,3=90.000000
L 4.90394931 3.62848327 4.90188307 3.6304002 1 P 0 ;0,1,2=302,3=90.000000
L 4.90188307 3.6304002 4.8977497 3.63116673 1 P 0 ;0,1,2=302,3=90.000000
L 4.8977497 3.63116673 4.89361634 3.6304002 1 P 0 ;0,1,2=302,3=90.000000
L 4.89361634 3.6304002 4.89103356 3.6281 1 P 0 ;0,1,2=302,3=90.000000
L 4.89103356 3.6281 4.88948287 3.62541654 1 P 0 ;0,1,2=302,3=90.000000
L 4.88948287 3.62541654 4.88948287 3.61583317 1 P 0 ;0,1,2=302,3=90.000000
L 4.88948287 3.62541654 4.8745 3.63116673 1 P 0 ;0,1,2=302,3=90.000000
L 4.8745 3.65449961 4.9055 3.65449961 1 P 0 ;0,1,2=302,3=90.000000
L 4.9055 3.65449961 4.8993003 3.6498999 1 P 0 ;0,1,2=302,3=90.000000
L 4.8745 3.6498999 4.8745 3.65909931 1 P 0 ;0,1,2=302,3=90.000000
L 4.8745 3.68549961 4.9055 3.68549961 1 P 0 ;0,1,2=302,3=90.000000
L 4.9055 3.68549961 4.8993003 3.6808999 1 P 0 ;0,1,2=302,3=90.000000
L 4.8745 3.6808999 4.8745 3.69009931 1 P 0 ;0,1,2=302,3=90.000000
L 4.8745 3.71649961 4.9055 3.71649961 1 P 0 ;0,1,2=302,3=90.000000
L 4.9055 3.71649961 4.8993003 3.7118999 1 P 0 ;0,1,2=302,3=90.000000
L 4.8745 3.7118999 4.8745 3.72109931 1 P 0 ;0,1,2=302,3=90.000000
L 4.712 3.573 4.802 3.573 1 P 0 
L 4.802 3.529 4.712 3.529 1 P 0 
L 4.712 3.529 4.712 3.573 1 P 0 
L 4.802 3.573 4.802 3.529 1 P 0 
L 4.79416683 3.5845 4.79416683 3.6155 1 P 0 ;0,1,2=303,3=0.000000
L 4.79416683 3.6155 4.78458346 3.6155 1 P 0 ;0,1,2=303,3=0.000000
L 4.78458346 3.6155 4.78151673 3.61394931 1 P 0 ;0,1,2=303,3=0.000000
L 4.78151673 3.61394931 4.7795998 3.61188307 1 P 0 ;0,1,2=303,3=0.000000
L 4.7795998 3.61188307 4.77883327 3.6077497 1 P 0 ;0,1,2=303,3=0.000000
L 4.77883327 3.6077497 4.7795998 3.60361634 1 P 0 ;0,1,2=303,3=0.000000
L 4.7795998 3.60361634 4.7819 3.60103356 1 P 0 ;0,1,2=303,3=0.000000
L 4.7819 3.60103356 4.78458346 3.59948287 1 P 0 ;0,1,2=303,3=0.000000
L 4.78458346 3.59948287 4.79416683 3.59948287 1 P 0 ;0,1,2=303,3=0.000000
L 4.78458346 3.59948287 4.77883327 3.5845 1 P 0 ;0,1,2=303,3=0.000000
L 4.75550039 3.5845 4.75550039 3.6155 1 P 0 ;0,1,2=303,3=0.000000
L 4.75550039 3.6155 4.7601001 3.6093003 1 P 0 ;0,1,2=303,3=0.000000
L 4.7601001 3.5845 4.75090069 3.5845 1 P 0 ;0,1,2=303,3=0.000000
L 4.72450039 3.5845 4.72450039 3.6155 1 P 0 ;0,1,2=303,3=0.000000
L 4.72450039 3.6155 4.7291001 3.6093003 1 P 0 ;0,1,2=303,3=0.000000
L 4.7291001 3.5845 4.71990069 3.5845 1 P 0 ;0,1,2=303,3=0.000000
L 4.70193337 3.58914892 4.69963386 3.58656614 1 P 0 ;0,1,2=303,3=0.000000
L 4.69963386 3.58656614 4.69695039 3.58501654 1 P 0 ;0,1,2=303,3=0.000000
L 4.69695039 3.58501654 4.69350039 3.5845 1 P 0 ;0,1,2=303,3=0.000000
L 4.69350039 3.5845 4.6900497 3.58553307 1 P 0 ;0,1,2=303,3=0.000000
L 4.6900497 3.58553307 4.68736693 3.58759931 1 P 0 ;0,1,2=303,3=0.000000
L 4.68736693 3.58759931 4.68545 3.59121614 1 P 0 ;0,1,2=303,3=0.000000
L 4.68545 3.59121614 4.68506673 3.59534951 1 P 0 ;0,1,2=303,3=0.000000
L 4.68506673 3.59534951 4.68583327 3.59948287 1 P 0 ;0,1,2=303,3=0.000000
L 4.68583327 3.59948287 4.6877502 3.60206663 1 P 0 ;0,1,2=303,3=0.000000
L 4.6877502 3.60206663 4.69043366 3.60413287 1 P 0 ;0,1,2=303,3=0.000000
L 4.69043366 3.60413287 4.69311644 3.60464941 1 P 0 ;0,1,2=303,3=0.000000
L 4.69311644 3.60464941 4.6957999 3.60413287 1 P 0 ;0,1,2=303,3=0.000000
L 4.6957999 3.60413287 4.6992499 3.60206663 1 P 0 ;0,1,2=303,3=0.000000
L 4.6992499 3.60206663 4.6981001 3.6155 1 P 0 ;0,1,2=303,3=0.000000
L 4.6981001 3.6155 4.6877502 3.6155 1 P 0 ;0,1,2=303,3=0.000000
L 4.2 4.137 4.29 4.137 1 P 0 
L 4.29 4.137 4.29 4.093 1 P 0 
L 4.29 4.093 4.2 4.093 1 P 0 
L 4.2 4.093 4.2 4.137 1 P 0 
L 4.30416683 4.2145 4.30416683 4.2455 1 P 0 ;0,1,2=304,3=0.000000
L 4.30416683 4.2455 4.29458346 4.2455 1 P 0 ;0,1,2=304,3=0.000000
L 4.29458346 4.2455 4.29151673 4.24394931 1 P 0 ;0,1,2=304,3=0.000000
L 4.29151673 4.24394931 4.2895998 4.24188307 1 P 0 ;0,1,2=304,3=0.000000
L 4.2895998 4.24188307 4.28883327 4.2377497 1 P 0 ;0,1,2=304,3=0.000000
L 4.28883327 4.2377497 4.2895998 4.23361634 1 P 0 ;0,1,2=304,3=0.000000
L 4.2895998 4.23361634 4.2919 4.23103356 1 P 0 ;0,1,2=304,3=0.000000
L 4.2919 4.23103356 4.29458346 4.22948287 1 P 0 ;0,1,2=304,3=0.000000
L 4.29458346 4.22948287 4.30416683 4.22948287 1 P 0 ;0,1,2=304,3=0.000000
L 4.29458346 4.22948287 4.28883327 4.2145 1 P 0 ;0,1,2=304,3=0.000000
L 4.27393337 4.22069961 4.27163386 4.21708278 1 P 0 ;0,1,2=304,3=0.000000
L 4.27163386 4.21708278 4.26856713 4.21501654 1 P 0 ;0,1,2=304,3=0.000000
L 4.26856713 4.21501654 4.26511644 4.2145 1 P 0 ;0,1,2=304,3=0.000000
L 4.26511644 4.2145 4.2620497 4.21501654 1 P 0 ;0,1,2=304,3=0.000000
L 4.2620497 4.21501654 4.25898297 4.21759931 1 P 0 ;0,1,2=304,3=0.000000
L 4.25898297 4.21759931 4.25706673 4.22069961 1 P 0 ;0,1,2=304,3=0.000000
L 4.25706673 4.22069961 4.25668346 4.2237999 1 P 0 ;0,1,2=304,3=0.000000
L 4.25668346 4.2237999 4.25745 4.22741575 1 P 0 ;0,1,2=304,3=0.000000
L 4.25745 4.22741575 4.26013346 4.22999951 1 P 0 ;0,1,2=304,3=0.000000
L 4.26013346 4.22999951 4.26281693 4.23103356 1 P 0 ;0,1,2=304,3=0.000000
L 4.26281693 4.23103356 4.26626693 4.23103356 1 P 0 ;0,1,2=304,3=0.000000
L 4.26281693 4.23103356 4.26051673 4.23258317 1 P 0 ;0,1,2=304,3=0.000000
L 4.26051673 4.23258317 4.2585998 4.23516594 1 P 0 ;0,1,2=304,3=0.000000
L 4.2585998 4.23516594 4.25783327 4.23826624 1 P 0 ;0,1,2=304,3=0.000000
L 4.25783327 4.23826624 4.2585998 4.24136654 1 P 0 ;0,1,2=304,3=0.000000
L 4.2585998 4.24136654 4.26051673 4.24394931 1 P 0 ;0,1,2=304,3=0.000000
L 4.26051673 4.24394931 4.26396673 4.2455 1 P 0 ;0,1,2=304,3=0.000000
L 4.26396673 4.2455 4.26741663 4.24498337 1 P 0 ;0,1,2=304,3=0.000000
L 4.26741663 4.24498337 4.27086663 4.24291624 1 P 0 ;0,1,2=304,3=0.000000
L 4.23450039 4.2145 4.23450039 4.2455 1 P 0 ;0,1,2=304,3=0.000000
L 4.23450039 4.2455 4.2391001 4.2393003 1 P 0 ;0,1,2=304,3=0.000000
L 4.2391001 4.2145 4.22990069 4.2145 1 P 0 ;0,1,2=304,3=0.000000
L 4.20350039 4.2145 4.20081693 4.21501654 1 P 0 ;0,1,2=304,3=0.000000
L 4.20081693 4.21501654 4.1977502 4.21656614 1 P 0 ;0,1,2=304,3=0.000000
L 4.1977502 4.21656614 4.19583327 4.21914892 1 P 0 ;0,1,2=304,3=0.000000
L 4.19583327 4.21914892 4.19506673 4.22276673 1 P 0 ;0,1,2=304,3=0.000000
L 4.19506673 4.22276673 4.19583327 4.22638268 1 P 0 ;0,1,2=304,3=0.000000
L 4.19583327 4.22638268 4.19813346 4.22948287 1 P 0 ;0,1,2=304,3=0.000000
L 4.19813346 4.22948287 4.20158346 4.23103356 1 P 0 ;0,1,2=304,3=0.000000
L 4.20158346 4.23103356 4.20541663 4.23103356 1 P 0 ;0,1,2=304,3=0.000000
L 4.20541663 4.23103356 4.20771683 4.23206663 1 P 0 ;0,1,2=304,3=0.000000
L 4.20771683 4.23206663 4.20963386 4.23464941 1 P 0 ;0,1,2=304,3=0.000000
L 4.20963386 4.23464941 4.2104003 4.23826624 1 P 0 ;0,1,2=304,3=0.000000
L 4.2104003 4.23826624 4.2092499 4.24188307 1 P 0 ;0,1,2=304,3=0.000000
L 4.2092499 4.24188307 4.20656713 4.24446683 1 P 0 ;0,1,2=304,3=0.000000
L 4.20656713 4.24446683 4.20350039 4.2455 1 P 0 ;0,1,2=304,3=0.000000
L 4.20350039 4.2455 4.20043366 4.24446683 1 P 0 ;0,1,2=304,3=0.000000
L 4.20043366 4.24446683 4.1977502 4.24188307 1 P 0 ;0,1,2=304,3=0.000000
L 4.1977502 4.24188307 4.1965998 4.23826624 1 P 0 ;0,1,2=304,3=0.000000
L 4.1965998 4.23826624 4.19736693 4.23464941 1 P 0 ;0,1,2=304,3=0.000000
L 4.19736693 4.23464941 4.19928327 4.23206663 1 P 0 ;0,1,2=304,3=0.000000
L 4.19928327 4.23206663 4.20158346 4.23103356 1 P 0 ;0,1,2=304,3=0.000000
L 4.20158346 4.23103356 4.20541663 4.23103356 1 P 0 ;0,1,2=304,3=0.000000
L 4.20541663 4.23103356 4.20886663 4.22948287 1 P 0 ;0,1,2=304,3=0.000000
L 4.20886663 4.22948287 4.21116683 4.22638268 1 P 0 ;0,1,2=304,3=0.000000
L 4.21116683 4.22638268 4.21193337 4.22276673 1 P 0 ;0,1,2=304,3=0.000000
L 4.21193337 4.22276673 4.21116683 4.21914892 1 P 0 ;0,1,2=304,3=0.000000
L 4.21116683 4.21914892 4.2092499 4.21656614 1 P 0 ;0,1,2=304,3=0.000000
L 4.2092499 4.21656614 4.20618317 4.21501654 1 P 0 ;0,1,2=304,3=0.000000
L 4.20618317 4.21501654 4.20350039 4.2145 1 P 0 ;0,1,2=304,3=0.000000
L 4.2 4.087 4.29 4.087 1 P 0 
L 4.29 4.087 4.29 4.043 1 P 0 
L 4.29 4.043 4.2 4.043 1 P 0 
L 4.2 4.043 4.2 4.087 1 P 0 
L 4.30416683 4.1745 4.30416683 4.2055 1 P 0 ;0,1,2=305,3=0.000000
L 4.30416683 4.2055 4.29458346 4.2055 1 P 0 ;0,1,2=305,3=0.000000
L 4.29458346 4.2055 4.29151673 4.20394931 1 P 0 ;0,1,2=305,3=0.000000
L 4.29151673 4.20394931 4.2895998 4.20188307 1 P 0 ;0,1,2=305,3=0.000000
L 4.2895998 4.20188307 4.28883327 4.1977497 1 P 0 ;0,1,2=305,3=0.000000
L 4.28883327 4.1977497 4.2895998 4.19361634 1 P 0 ;0,1,2=305,3=0.000000
L 4.2895998 4.19361634 4.2919 4.19103356 1 P 0 ;0,1,2=305,3=0.000000
L 4.2919 4.19103356 4.29458346 4.18948287 1 P 0 ;0,1,2=305,3=0.000000
L 4.29458346 4.18948287 4.30416683 4.18948287 1 P 0 ;0,1,2=305,3=0.000000
L 4.29458346 4.18948287 4.28883327 4.1745 1 P 0 ;0,1,2=305,3=0.000000
L 4.27393337 4.18069961 4.27163386 4.17708278 1 P 0 ;0,1,2=305,3=0.000000
L 4.27163386 4.17708278 4.26856713 4.17501654 1 P 0 ;0,1,2=305,3=0.000000
L 4.26856713 4.17501654 4.26511644 4.1745 1 P 0 ;0,1,2=305,3=0.000000
L 4.26511644 4.1745 4.2620497 4.17501654 1 P 0 ;0,1,2=305,3=0.000000
L 4.2620497 4.17501654 4.25898297 4.17759931 1 P 0 ;0,1,2=305,3=0.000000
L 4.25898297 4.17759931 4.25706673 4.18069961 1 P 0 ;0,1,2=305,3=0.000000
L 4.25706673 4.18069961 4.25668346 4.1837999 1 P 0 ;0,1,2=305,3=0.000000
L 4.25668346 4.1837999 4.25745 4.18741575 1 P 0 ;0,1,2=305,3=0.000000
L 4.25745 4.18741575 4.26013346 4.18999951 1 P 0 ;0,1,2=305,3=0.000000
L 4.26013346 4.18999951 4.26281693 4.19103356 1 P 0 ;0,1,2=305,3=0.000000
L 4.26281693 4.19103356 4.26626693 4.19103356 1 P 0 ;0,1,2=305,3=0.000000
L 4.26281693 4.19103356 4.26051673 4.19258317 1 P 0 ;0,1,2=305,3=0.000000
L 4.26051673 4.19258317 4.2585998 4.19516594 1 P 0 ;0,1,2=305,3=0.000000
L 4.2585998 4.19516594 4.25783327 4.19826624 1 P 0 ;0,1,2=305,3=0.000000
L 4.25783327 4.19826624 4.2585998 4.20136654 1 P 0 ;0,1,2=305,3=0.000000
L 4.2585998 4.20136654 4.26051673 4.20394931 1 P 0 ;0,1,2=305,3=0.000000
L 4.26051673 4.20394931 4.26396673 4.2055 1 P 0 ;0,1,2=305,3=0.000000
L 4.26396673 4.2055 4.26741663 4.20498337 1 P 0 ;0,1,2=305,3=0.000000
L 4.26741663 4.20498337 4.27086663 4.20291624 1 P 0 ;0,1,2=305,3=0.000000
L 4.23450039 4.1745 4.23450039 4.2055 1 P 0 ;0,1,2=305,3=0.000000
L 4.23450039 4.2055 4.2391001 4.1993003 1 P 0 ;0,1,2=305,3=0.000000
L 4.2391001 4.1745 4.22990069 4.1745 1 P 0 ;0,1,2=305,3=0.000000
L 4.20426693 4.1745 4.20350039 4.18121614 1 P 0 ;0,1,2=305,3=0.000000
L 4.20350039 4.18121614 4.2023499 4.18689921 1 P 0 ;0,1,2=305,3=0.000000
L 4.2023499 4.18689921 4.20081693 4.19206663 1 P 0 ;0,1,2=305,3=0.000000
L 4.20081693 4.19206663 4.1989 4.1977497 1 P 0 ;0,1,2=305,3=0.000000
L 4.1989 4.1977497 4.19583327 4.2055 1 P 0 ;0,1,2=305,3=0.000000
L 4.19583327 4.2055 4.21116683 4.2055 1 P 0 ;0,1,2=305,3=0.000000
L 4.42 4.087 4.42 4.043 1 P 0 
L 4.33 4.087 4.42 4.087 1 P 0 
L 4.42 4.043 4.33 4.043 1 P 0 
L 4.33 4.043 4.33 4.087 1 P 0 
L 4.44416683 4.1795 4.44416683 4.2105 1 P 0 ;0,1,2=306,3=0.000000
L 4.44416683 4.2105 4.43458346 4.2105 1 P 0 ;0,1,2=306,3=0.000000
L 4.43458346 4.2105 4.43151673 4.20894931 1 P 0 ;0,1,2=306,3=0.000000
L 4.43151673 4.20894931 4.4295998 4.20688307 1 P 0 ;0,1,2=306,3=0.000000
L 4.4295998 4.20688307 4.42883327 4.2027497 1 P 0 ;0,1,2=306,3=0.000000
L 4.42883327 4.2027497 4.4295998 4.19861634 1 P 0 ;0,1,2=306,3=0.000000
L 4.4295998 4.19861634 4.4319 4.19603356 1 P 0 ;0,1,2=306,3=0.000000
L 4.4319 4.19603356 4.43458346 4.19448287 1 P 0 ;0,1,2=306,3=0.000000
L 4.43458346 4.19448287 4.44416683 4.19448287 1 P 0 ;0,1,2=306,3=0.000000
L 4.43458346 4.19448287 4.42883327 4.1795 1 P 0 ;0,1,2=306,3=0.000000
L 4.41393337 4.18569961 4.41163386 4.18208278 1 P 0 ;0,1,2=306,3=0.000000
L 4.41163386 4.18208278 4.40856713 4.18001654 1 P 0 ;0,1,2=306,3=0.000000
L 4.40856713 4.18001654 4.40511644 4.1795 1 P 0 ;0,1,2=306,3=0.000000
L 4.40511644 4.1795 4.4020497 4.18001654 1 P 0 ;0,1,2=306,3=0.000000
L 4.4020497 4.18001654 4.39898297 4.18259931 1 P 0 ;0,1,2=306,3=0.000000
L 4.39898297 4.18259931 4.39706673 4.18569961 1 P 0 ;0,1,2=306,3=0.000000
L 4.39706673 4.18569961 4.39668346 4.1887999 1 P 0 ;0,1,2=306,3=0.000000
L 4.39668346 4.1887999 4.39745 4.19241575 1 P 0 ;0,1,2=306,3=0.000000
L 4.39745 4.19241575 4.40013346 4.19499951 1 P 0 ;0,1,2=306,3=0.000000
L 4.40013346 4.19499951 4.40281693 4.19603356 1 P 0 ;0,1,2=306,3=0.000000
L 4.40281693 4.19603356 4.40626693 4.19603356 1 P 0 ;0,1,2=306,3=0.000000
L 4.40281693 4.19603356 4.40051673 4.19758317 1 P 0 ;0,1,2=306,3=0.000000
L 4.40051673 4.19758317 4.3985998 4.20016594 1 P 0 ;0,1,2=306,3=0.000000
L 4.3985998 4.20016594 4.39783327 4.20326624 1 P 0 ;0,1,2=306,3=0.000000
L 4.39783327 4.20326624 4.3985998 4.20636654 1 P 0 ;0,1,2=306,3=0.000000
L 4.3985998 4.20636654 4.40051673 4.20894931 1 P 0 ;0,1,2=306,3=0.000000
L 4.40051673 4.20894931 4.40396673 4.2105 1 P 0 ;0,1,2=306,3=0.000000
L 4.40396673 4.2105 4.40741663 4.20998337 1 P 0 ;0,1,2=306,3=0.000000
L 4.40741663 4.20998337 4.41086663 4.20791624 1 P 0 ;0,1,2=306,3=0.000000
L 4.38178356 4.20533346 4.37948337 4.20843278 1 P 0 ;0,1,2=306,3=0.000000
L 4.37948337 4.20843278 4.3767999 4.20998337 1 P 0 ;0,1,2=306,3=0.000000
L 4.3767999 4.20998337 4.37373317 4.2105 1 P 0 ;0,1,2=306,3=0.000000
L 4.37373317 4.2105 4.3699 4.20946683 1 P 0 ;0,1,2=306,3=0.000000
L 4.3699 4.20946683 4.36721654 4.20688307 1 P 0 ;0,1,2=306,3=0.000000
L 4.36721654 4.20688307 4.36645 4.20378376 1 P 0 ;0,1,2=306,3=0.000000
L 4.36645 4.20378376 4.36683327 4.20068258 1 P 0 ;0,1,2=306,3=0.000000
L 4.36683327 4.20068258 4.36836693 4.1980998 1 P 0 ;0,1,2=306,3=0.000000
L 4.36836693 4.1980998 4.37603337 4.19293327 1 P 0 ;0,1,2=306,3=0.000000
L 4.37603337 4.19293327 4.37948337 4.18931644 1 P 0 ;0,1,2=306,3=0.000000
L 4.37948337 4.18931644 4.38178356 4.18414892 1 P 0 ;0,1,2=306,3=0.000000
L 4.38178356 4.18414892 4.3825501 4.1795 1 P 0 ;0,1,2=306,3=0.000000
L 4.3825501 4.1795 4.36645 4.1795 1 P 0 ;0,1,2=306,3=0.000000
L 4.34350039 4.1795 4.34350039 4.2105 1 P 0 ;0,1,2=306,3=0.000000
L 4.34350039 4.2105 4.3481001 4.2043003 1 P 0 ;0,1,2=306,3=0.000000
L 4.3481001 4.1795 4.33890069 4.1795 1 P 0 ;0,1,2=306,3=0.000000
L 4.42 4.137 4.42 4.093 1 P 0 
L 4.42 4.093 4.33 4.093 1 P 0 
L 4.33 4.093 4.33 4.137 1 P 0 
L 4.33 4.137 4.42 4.137 1 P 0 
L 4.44416683 4.2195 4.44416683 4.2505 1 P 0 ;0,1,2=307,3=0.000000
L 4.44416683 4.2505 4.43458346 4.2505 1 P 0 ;0,1,2=307,3=0.000000
L 4.43458346 4.2505 4.43151673 4.24894931 1 P 0 ;0,1,2=307,3=0.000000
L 4.43151673 4.24894931 4.4295998 4.24688307 1 P 0 ;0,1,2=307,3=0.000000
L 4.4295998 4.24688307 4.42883327 4.2427497 1 P 0 ;0,1,2=307,3=0.000000
L 4.42883327 4.2427497 4.4295998 4.23861634 1 P 0 ;0,1,2=307,3=0.000000
L 4.4295998 4.23861634 4.4319 4.23603356 1 P 0 ;0,1,2=307,3=0.000000
L 4.4319 4.23603356 4.43458346 4.23448287 1 P 0 ;0,1,2=307,3=0.000000
L 4.43458346 4.23448287 4.44416683 4.23448287 1 P 0 ;0,1,2=307,3=0.000000
L 4.43458346 4.23448287 4.42883327 4.2195 1 P 0 ;0,1,2=307,3=0.000000
L 4.41393337 4.22569961 4.41163386 4.22208278 1 P 0 ;0,1,2=307,3=0.000000
L 4.41163386 4.22208278 4.40856713 4.22001654 1 P 0 ;0,1,2=307,3=0.000000
L 4.40856713 4.22001654 4.40511644 4.2195 1 P 0 ;0,1,2=307,3=0.000000
L 4.40511644 4.2195 4.4020497 4.22001654 1 P 0 ;0,1,2=307,3=0.000000
L 4.4020497 4.22001654 4.39898297 4.22259931 1 P 0 ;0,1,2=307,3=0.000000
L 4.39898297 4.22259931 4.39706673 4.22569961 1 P 0 ;0,1,2=307,3=0.000000
L 4.39706673 4.22569961 4.39668346 4.2287999 1 P 0 ;0,1,2=307,3=0.000000
L 4.39668346 4.2287999 4.39745 4.23241575 1 P 0 ;0,1,2=307,3=0.000000
L 4.39745 4.23241575 4.40013346 4.23499951 1 P 0 ;0,1,2=307,3=0.000000
L 4.40013346 4.23499951 4.40281693 4.23603356 1 P 0 ;0,1,2=307,3=0.000000
L 4.40281693 4.23603356 4.40626693 4.23603356 1 P 0 ;0,1,2=307,3=0.000000
L 4.40281693 4.23603356 4.40051673 4.23758317 1 P 0 ;0,1,2=307,3=0.000000
L 4.40051673 4.23758317 4.3985998 4.24016594 1 P 0 ;0,1,2=307,3=0.000000
L 4.3985998 4.24016594 4.39783327 4.24326624 1 P 0 ;0,1,2=307,3=0.000000
L 4.39783327 4.24326624 4.3985998 4.24636654 1 P 0 ;0,1,2=307,3=0.000000
L 4.3985998 4.24636654 4.40051673 4.24894931 1 P 0 ;0,1,2=307,3=0.000000
L 4.40051673 4.24894931 4.40396673 4.2505 1 P 0 ;0,1,2=307,3=0.000000
L 4.40396673 4.2505 4.40741663 4.24998337 1 P 0 ;0,1,2=307,3=0.000000
L 4.40741663 4.24998337 4.41086663 4.24791624 1 P 0 ;0,1,2=307,3=0.000000
L 4.38178356 4.24533346 4.37948337 4.24843278 1 P 0 ;0,1,2=307,3=0.000000
L 4.37948337 4.24843278 4.3767999 4.24998337 1 P 0 ;0,1,2=307,3=0.000000
L 4.3767999 4.24998337 4.37373317 4.2505 1 P 0 ;0,1,2=307,3=0.000000
L 4.37373317 4.2505 4.3699 4.24946683 1 P 0 ;0,1,2=307,3=0.000000
L 4.3699 4.24946683 4.36721654 4.24688307 1 P 0 ;0,1,2=307,3=0.000000
L 4.36721654 4.24688307 4.36645 4.24378376 1 P 0 ;0,1,2=307,3=0.000000
L 4.36645 4.24378376 4.36683327 4.24068258 1 P 0 ;0,1,2=307,3=0.000000
L 4.36683327 4.24068258 4.36836693 4.2380998 1 P 0 ;0,1,2=307,3=0.000000
L 4.36836693 4.2380998 4.37603337 4.23293327 1 P 0 ;0,1,2=307,3=0.000000
L 4.37603337 4.23293327 4.37948337 4.22931644 1 P 0 ;0,1,2=307,3=0.000000
L 4.37948337 4.22931644 4.38178356 4.22414892 1 P 0 ;0,1,2=307,3=0.000000
L 4.38178356 4.22414892 4.3825501 4.2195 1 P 0 ;0,1,2=307,3=0.000000
L 4.3825501 4.2195 4.36645 4.2195 1 P 0 ;0,1,2=307,3=0.000000
L 4.35078356 4.24533346 4.34848337 4.24843278 1 P 0 ;0,1,2=307,3=0.000000
L 4.34848337 4.24843278 4.3457999 4.24998337 1 P 0 ;0,1,2=307,3=0.000000
L 4.3457999 4.24998337 4.34273317 4.2505 1 P 0 ;0,1,2=307,3=0.000000
L 4.34273317 4.2505 4.3389 4.24946683 1 P 0 ;0,1,2=307,3=0.000000
L 4.3389 4.24946683 4.33621654 4.24688307 1 P 0 ;0,1,2=307,3=0.000000
L 4.33621654 4.24688307 4.33545 4.24378376 1 P 0 ;0,1,2=307,3=0.000000
L 4.33545 4.24378376 4.33583327 4.24068258 1 P 0 ;0,1,2=307,3=0.000000
L 4.33583327 4.24068258 4.33736693 4.2380998 1 P 0 ;0,1,2=307,3=0.000000
L 4.33736693 4.2380998 4.34503337 4.23293327 1 P 0 ;0,1,2=307,3=0.000000
L 4.34503337 4.23293327 4.34848337 4.22931644 1 P 0 ;0,1,2=307,3=0.000000
L 4.34848337 4.22931644 4.35078356 4.22414892 1 P 0 ;0,1,2=307,3=0.000000
L 4.35078356 4.22414892 4.3515501 4.2195 1 P 0 ;0,1,2=307,3=0.000000
L 4.3515501 4.2195 4.33545 4.2195 1 P 0 ;0,1,2=307,3=0.000000
L 6.06 2.768 5.97 2.768 1 P 0 
L 5.97 2.768 5.97 2.812 1 P 0 
L 5.97 2.812 6.06 2.812 1 P 0 
L 6.06 2.812 6.06 2.768 1 P 0 
L 6.05366683 2.8145 6.05366683 2.8455 1 P 0 ;0,1,2=308,3=0.000000
L 6.05366683 2.8455 6.04408346 2.8455 1 P 0 ;0,1,2=308,3=0.000000
L 6.04408346 2.8455 6.04101673 2.84394931 1 P 0 ;0,1,2=308,3=0.000000
L 6.04101673 2.84394931 6.0390998 2.84188307 1 P 0 ;0,1,2=308,3=0.000000
L 6.0390998 2.84188307 6.03833327 2.8377497 1 P 0 ;0,1,2=308,3=0.000000
L 6.03833327 2.8377497 6.0390998 2.83361634 1 P 0 ;0,1,2=308,3=0.000000
L 6.0390998 2.83361634 6.0414 2.83103356 1 P 0 ;0,1,2=308,3=0.000000
L 6.0414 2.83103356 6.04408346 2.82948287 1 P 0 ;0,1,2=308,3=0.000000
L 6.04408346 2.82948287 6.05366683 2.82948287 1 P 0 ;0,1,2=308,3=0.000000
L 6.04408346 2.82948287 6.03833327 2.8145 1 P 0 ;0,1,2=308,3=0.000000
L 6.01500039 2.8145 6.01231693 2.81501654 1 P 0 ;0,1,2=308,3=0.000000
L 6.01231693 2.81501654 6.0092502 2.81656614 1 P 0 ;0,1,2=308,3=0.000000
L 6.0092502 2.81656614 6.00733327 2.81914892 1 P 0 ;0,1,2=308,3=0.000000
L 6.00733327 2.81914892 6.00656673 2.82276673 1 P 0 ;0,1,2=308,3=0.000000
L 6.00656673 2.82276673 6.00733327 2.82638268 1 P 0 ;0,1,2=308,3=0.000000
L 6.00733327 2.82638268 6.00963346 2.82948287 1 P 0 ;0,1,2=308,3=0.000000
L 6.00963346 2.82948287 6.01308346 2.83103356 1 P 0 ;0,1,2=308,3=0.000000
L 6.01308346 2.83103356 6.01691663 2.83103356 1 P 0 ;0,1,2=308,3=0.000000
L 6.01691663 2.83103356 6.01921683 2.83206663 1 P 0 ;0,1,2=308,3=0.000000
L 6.01921683 2.83206663 6.02113386 2.83464941 1 P 0 ;0,1,2=308,3=0.000000
L 6.02113386 2.83464941 6.0219003 2.83826624 1 P 0 ;0,1,2=308,3=0.000000
L 6.0219003 2.83826624 6.0207499 2.84188307 1 P 0 ;0,1,2=308,3=0.000000
L 6.0207499 2.84188307 6.01806713 2.84446683 1 P 0 ;0,1,2=308,3=0.000000
L 6.01806713 2.84446683 6.01500039 2.8455 1 P 0 ;0,1,2=308,3=0.000000
L 6.01500039 2.8455 6.01193366 2.84446683 1 P 0 ;0,1,2=308,3=0.000000
L 6.01193366 2.84446683 6.0092502 2.84188307 1 P 0 ;0,1,2=308,3=0.000000
L 6.0092502 2.84188307 6.0080998 2.83826624 1 P 0 ;0,1,2=308,3=0.000000
L 6.0080998 2.83826624 6.00886693 2.83464941 1 P 0 ;0,1,2=308,3=0.000000
L 6.00886693 2.83464941 6.01078327 2.83206663 1 P 0 ;0,1,2=308,3=0.000000
L 6.01078327 2.83206663 6.01308346 2.83103356 1 P 0 ;0,1,2=308,3=0.000000
L 6.01308346 2.83103356 6.01691663 2.83103356 1 P 0 ;0,1,2=308,3=0.000000
L 6.01691663 2.83103356 6.02036663 2.82948287 1 P 0 ;0,1,2=308,3=0.000000
L 6.02036663 2.82948287 6.02266683 2.82638268 1 P 0 ;0,1,2=308,3=0.000000
L 6.02266683 2.82638268 6.02343337 2.82276673 1 P 0 ;0,1,2=308,3=0.000000
L 6.02343337 2.82276673 6.02266683 2.81914892 1 P 0 ;0,1,2=308,3=0.000000
L 6.02266683 2.81914892 6.0207499 2.81656614 1 P 0 ;0,1,2=308,3=0.000000
L 6.0207499 2.81656614 6.01768317 2.81501654 1 P 0 ;0,1,2=308,3=0.000000
L 6.01768317 2.81501654 6.01500039 2.8145 1 P 0 ;0,1,2=308,3=0.000000
L 5.99128356 2.84033346 5.98898337 2.84343278 1 P 0 ;0,1,2=308,3=0.000000
L 5.98898337 2.84343278 5.9862999 2.84498337 1 P 0 ;0,1,2=308,3=0.000000
L 5.9862999 2.84498337 5.98323317 2.8455 1 P 0 ;0,1,2=308,3=0.000000
L 5.98323317 2.8455 5.9794 2.84446683 1 P 0 ;0,1,2=308,3=0.000000
L 5.9794 2.84446683 5.97671654 2.84188307 1 P 0 ;0,1,2=308,3=0.000000
L 5.97671654 2.84188307 5.97595 2.83878376 1 P 0 ;0,1,2=308,3=0.000000
L 5.97595 2.83878376 5.97633327 2.83568258 1 P 0 ;0,1,2=308,3=0.000000
L 5.97633327 2.83568258 5.97786693 2.8330998 1 P 0 ;0,1,2=308,3=0.000000
L 5.97786693 2.8330998 5.98553337 2.82793327 1 P 0 ;0,1,2=308,3=0.000000
L 5.98553337 2.82793327 5.98898337 2.82431644 1 P 0 ;0,1,2=308,3=0.000000
L 5.98898337 2.82431644 5.99128356 2.81914892 1 P 0 ;0,1,2=308,3=0.000000
L 5.99128356 2.81914892 5.9920501 2.8145 1 P 0 ;0,1,2=308,3=0.000000
L 5.9920501 2.8145 5.97595 2.8145 1 P 0 ;0,1,2=308,3=0.000000
L 6.06 2.637 6.06 2.593 1 P 0 
L 5.97 2.637 6.06 2.637 1 P 0 
L 5.97 2.593 5.97 2.637 1 P 0 
L 6.06 2.593 5.97 2.593 1 P 0 
L 6.05366683 2.6445 6.05366683 2.6755 1 P 0 ;0,1,2=309,3=0.000000
L 6.05366683 2.6755 6.04408346 2.6755 1 P 0 ;0,1,2=309,3=0.000000
L 6.04408346 2.6755 6.04101673 2.67394931 1 P 0 ;0,1,2=309,3=0.000000
L 6.04101673 2.67394931 6.0390998 2.67188307 1 P 0 ;0,1,2=309,3=0.000000
L 6.0390998 2.67188307 6.03833327 2.6677497 1 P 0 ;0,1,2=309,3=0.000000
L 6.03833327 2.6677497 6.0390998 2.66361634 1 P 0 ;0,1,2=309,3=0.000000
L 6.0390998 2.66361634 6.0414 2.66103356 1 P 0 ;0,1,2=309,3=0.000000
L 6.0414 2.66103356 6.04408346 2.65948287 1 P 0 ;0,1,2=309,3=0.000000
L 6.04408346 2.65948287 6.05366683 2.65948287 1 P 0 ;0,1,2=309,3=0.000000
L 6.04408346 2.65948287 6.03833327 2.6445 1 P 0 ;0,1,2=309,3=0.000000
L 6.01500039 2.6445 6.01231693 2.64501654 1 P 0 ;0,1,2=309,3=0.000000
L 6.01231693 2.64501654 6.0092502 2.64656614 1 P 0 ;0,1,2=309,3=0.000000
L 6.0092502 2.64656614 6.00733327 2.64914892 1 P 0 ;0,1,2=309,3=0.000000
L 6.00733327 2.64914892 6.00656673 2.65276673 1 P 0 ;0,1,2=309,3=0.000000
L 6.00656673 2.65276673 6.00733327 2.65638268 1 P 0 ;0,1,2=309,3=0.000000
L 6.00733327 2.65638268 6.00963346 2.65948287 1 P 0 ;0,1,2=309,3=0.000000
L 6.00963346 2.65948287 6.01308346 2.66103356 1 P 0 ;0,1,2=309,3=0.000000
L 6.01308346 2.66103356 6.01691663 2.66103356 1 P 0 ;0,1,2=309,3=0.000000
L 6.01691663 2.66103356 6.01921683 2.66206663 1 P 0 ;0,1,2=309,3=0.000000
L 6.01921683 2.66206663 6.02113386 2.66464941 1 P 0 ;0,1,2=309,3=0.000000
L 6.02113386 2.66464941 6.0219003 2.66826624 1 P 0 ;0,1,2=309,3=0.000000
L 6.0219003 2.66826624 6.0207499 2.67188307 1 P 0 ;0,1,2=309,3=0.000000
L 6.0207499 2.67188307 6.01806713 2.67446683 1 P 0 ;0,1,2=309,3=0.000000
L 6.01806713 2.67446683 6.01500039 2.6755 1 P 0 ;0,1,2=309,3=0.000000
L 6.01500039 2.6755 6.01193366 2.67446683 1 P 0 ;0,1,2=309,3=0.000000
L 6.01193366 2.67446683 6.0092502 2.67188307 1 P 0 ;0,1,2=309,3=0.000000
L 6.0092502 2.67188307 6.0080998 2.66826624 1 P 0 ;0,1,2=309,3=0.000000
L 6.0080998 2.66826624 6.00886693 2.66464941 1 P 0 ;0,1,2=309,3=0.000000
L 6.00886693 2.66464941 6.01078327 2.66206663 1 P 0 ;0,1,2=309,3=0.000000
L 6.01078327 2.66206663 6.01308346 2.66103356 1 P 0 ;0,1,2=309,3=0.000000
L 6.01308346 2.66103356 6.01691663 2.66103356 1 P 0 ;0,1,2=309,3=0.000000
L 6.01691663 2.66103356 6.02036663 2.65948287 1 P 0 ;0,1,2=309,3=0.000000
L 6.02036663 2.65948287 6.02266683 2.65638268 1 P 0 ;0,1,2=309,3=0.000000
L 6.02266683 2.65638268 6.02343337 2.65276673 1 P 0 ;0,1,2=309,3=0.000000
L 6.02343337 2.65276673 6.02266683 2.64914892 1 P 0 ;0,1,2=309,3=0.000000
L 6.02266683 2.64914892 6.0207499 2.64656614 1 P 0 ;0,1,2=309,3=0.000000
L 6.0207499 2.64656614 6.01768317 2.64501654 1 P 0 ;0,1,2=309,3=0.000000
L 6.01768317 2.64501654 6.01500039 2.6445 1 P 0 ;0,1,2=309,3=0.000000
L 5.98400039 2.6445 5.98400039 2.6755 1 P 0 ;0,1,2=309,3=0.000000
L 5.98400039 2.6755 5.9886001 2.6693003 1 P 0 ;0,1,2=309,3=0.000000
L 5.9886001 2.6445 5.97940069 2.6445 1 P 0 ;0,1,2=309,3=0.000000
L 5.57 2.748 5.48 2.748 1 P 0 
L 5.48 2.748 5.48 2.792 1 P 0 
L 5.48 2.792 5.57 2.792 1 P 0 
L 5.57 2.792 5.57 2.748 1 P 0 
L 5.39916683 2.7695 5.39916683 2.8005 1 P 0 ;0,1,2=310,3=0.000000
L 5.39916683 2.8005 5.38958346 2.8005 1 P 0 ;0,1,2=310,3=0.000000
L 5.38958346 2.8005 5.38651673 2.79894931 1 P 0 ;0,1,2=310,3=0.000000
L 5.38651673 2.79894931 5.3845998 2.79688307 1 P 0 ;0,1,2=310,3=0.000000
L 5.3845998 2.79688307 5.38383327 2.7927497 1 P 0 ;0,1,2=310,3=0.000000
L 5.38383327 2.7927497 5.3845998 2.78861634 1 P 0 ;0,1,2=310,3=0.000000
L 5.3845998 2.78861634 5.3869 2.78603356 1 P 0 ;0,1,2=310,3=0.000000
L 5.3869 2.78603356 5.38958346 2.78448287 1 P 0 ;0,1,2=310,3=0.000000
L 5.38958346 2.78448287 5.39916683 2.78448287 1 P 0 ;0,1,2=310,3=0.000000
L 5.38958346 2.78448287 5.38383327 2.7695 1 P 0 ;0,1,2=310,3=0.000000
L 5.36050039 2.7695 5.36050039 2.8005 1 P 0 ;0,1,2=310,3=0.000000
L 5.36050039 2.8005 5.3651001 2.7943003 1 P 0 ;0,1,2=310,3=0.000000
L 5.3651001 2.7695 5.35590069 2.7695 1 P 0 ;0,1,2=310,3=0.000000
L 5.33793337 2.77569961 5.33563386 2.77208278 1 P 0 ;0,1,2=310,3=0.000000
L 5.33563386 2.77208278 5.33256713 2.77001654 1 P 0 ;0,1,2=310,3=0.000000
L 5.33256713 2.77001654 5.32911644 2.7695 1 P 0 ;0,1,2=310,3=0.000000
L 5.32911644 2.7695 5.3260497 2.77001654 1 P 0 ;0,1,2=310,3=0.000000
L 5.3260497 2.77001654 5.32298297 2.77259931 1 P 0 ;0,1,2=310,3=0.000000
L 5.32298297 2.77259931 5.32106673 2.77569961 1 P 0 ;0,1,2=310,3=0.000000
L 5.32106673 2.77569961 5.32068346 2.7787999 1 P 0 ;0,1,2=310,3=0.000000
L 5.32068346 2.7787999 5.32145 2.78241575 1 P 0 ;0,1,2=310,3=0.000000
L 5.32145 2.78241575 5.32413346 2.78499951 1 P 0 ;0,1,2=310,3=0.000000
L 5.32413346 2.78499951 5.32681693 2.78603356 1 P 0 ;0,1,2=310,3=0.000000
L 5.32681693 2.78603356 5.33026693 2.78603356 1 P 0 ;0,1,2=310,3=0.000000
L 5.32681693 2.78603356 5.32451673 2.78758317 1 P 0 ;0,1,2=310,3=0.000000
L 5.32451673 2.78758317 5.3225998 2.79016594 1 P 0 ;0,1,2=310,3=0.000000
L 5.3225998 2.79016594 5.32183327 2.79326624 1 P 0 ;0,1,2=310,3=0.000000
L 5.32183327 2.79326624 5.3225998 2.79636654 1 P 0 ;0,1,2=310,3=0.000000
L 5.3225998 2.79636654 5.32451673 2.79894931 1 P 0 ;0,1,2=310,3=0.000000
L 5.32451673 2.79894931 5.32796673 2.8005 1 P 0 ;0,1,2=310,3=0.000000
L 5.32796673 2.8005 5.33141663 2.79998337 1 P 0 ;0,1,2=310,3=0.000000
L 5.33141663 2.79998337 5.33486663 2.79791624 1 P 0 ;0,1,2=310,3=0.000000
L 5.30693337 2.77414892 5.30463386 2.77156614 1 P 0 ;0,1,2=310,3=0.000000
L 5.30463386 2.77156614 5.30195039 2.77001654 1 P 0 ;0,1,2=310,3=0.000000
L 5.30195039 2.77001654 5.29850039 2.7695 1 P 0 ;0,1,2=310,3=0.000000
L 5.29850039 2.7695 5.2950497 2.77053307 1 P 0 ;0,1,2=310,3=0.000000
L 5.2950497 2.77053307 5.29236693 2.77259931 1 P 0 ;0,1,2=310,3=0.000000
L 5.29236693 2.77259931 5.29045 2.77621614 1 P 0 ;0,1,2=310,3=0.000000
L 5.29045 2.77621614 5.29006673 2.78034951 1 P 0 ;0,1,2=310,3=0.000000
L 5.29006673 2.78034951 5.29083327 2.78448287 1 P 0 ;0,1,2=310,3=0.000000
L 5.29083327 2.78448287 5.2927502 2.78706663 1 P 0 ;0,1,2=310,3=0.000000
L 5.2927502 2.78706663 5.29543366 2.78913287 1 P 0 ;0,1,2=310,3=0.000000
L 5.29543366 2.78913287 5.29811644 2.78964941 1 P 0 ;0,1,2=310,3=0.000000
L 5.29811644 2.78964941 5.3007999 2.78913287 1 P 0 ;0,1,2=310,3=0.000000
L 5.3007999 2.78913287 5.3042499 2.78706663 1 P 0 ;0,1,2=310,3=0.000000
L 5.3042499 2.78706663 5.3031001 2.8005 1 P 0 ;0,1,2=310,3=0.000000
L 5.3031001 2.8005 5.2927502 2.8005 1 P 0 ;0,1,2=310,3=0.000000
L 5.568 2.699 5.478 2.699 1 P 0 
L 5.478 2.699 5.478 2.743 1 P 0 
L 5.478 2.743 5.568 2.743 1 P 0 
L 5.568 2.743 5.568 2.699 1 P 0 
L 5.37916683 2.7295 5.37916683 2.7605 1 P 0 ;0,1,2=311,3=0.000000
L 5.37916683 2.7605 5.36958346 2.7605 1 P 0 ;0,1,2=311,3=0.000000
L 5.36958346 2.7605 5.36651673 2.75894931 1 P 0 ;0,1,2=311,3=0.000000
L 5.36651673 2.75894931 5.3645998 2.75688307 1 P 0 ;0,1,2=311,3=0.000000
L 5.3645998 2.75688307 5.36383327 2.7527497 1 P 0 ;0,1,2=311,3=0.000000
L 5.36383327 2.7527497 5.3645998 2.74861634 1 P 0 ;0,1,2=311,3=0.000000
L 5.3645998 2.74861634 5.3669 2.74603356 1 P 0 ;0,1,2=311,3=0.000000
L 5.3669 2.74603356 5.36958346 2.74448287 1 P 0 ;0,1,2=311,3=0.000000
L 5.36958346 2.74448287 5.37916683 2.74448287 1 P 0 ;0,1,2=311,3=0.000000
L 5.36958346 2.74448287 5.36383327 2.7295 1 P 0 ;0,1,2=311,3=0.000000
L 5.34050039 2.7295 5.34050039 2.7605 1 P 0 ;0,1,2=311,3=0.000000
L 5.34050039 2.7605 5.3451001 2.7543003 1 P 0 ;0,1,2=311,3=0.000000
L 5.3451001 2.7295 5.33590069 2.7295 1 P 0 ;0,1,2=311,3=0.000000
L 5.31793337 2.73569961 5.31563386 2.73208278 1 P 0 ;0,1,2=311,3=0.000000
L 5.31563386 2.73208278 5.31256713 2.73001654 1 P 0 ;0,1,2=311,3=0.000000
L 5.31256713 2.73001654 5.30911644 2.7295 1 P 0 ;0,1,2=311,3=0.000000
L 5.30911644 2.7295 5.3060497 2.73001654 1 P 0 ;0,1,2=311,3=0.000000
L 5.3060497 2.73001654 5.30298297 2.73259931 1 P 0 ;0,1,2=311,3=0.000000
L 5.30298297 2.73259931 5.30106673 2.73569961 1 P 0 ;0,1,2=311,3=0.000000
L 5.30106673 2.73569961 5.30068346 2.7387999 1 P 0 ;0,1,2=311,3=0.000000
L 5.30068346 2.7387999 5.30145 2.74241575 1 P 0 ;0,1,2=311,3=0.000000
L 5.30145 2.74241575 5.30413346 2.74499951 1 P 0 ;0,1,2=311,3=0.000000
L 5.30413346 2.74499951 5.30681693 2.74603356 1 P 0 ;0,1,2=311,3=0.000000
L 5.30681693 2.74603356 5.31026693 2.74603356 1 P 0 ;0,1,2=311,3=0.000000
L 5.30681693 2.74603356 5.30451673 2.74758317 1 P 0 ;0,1,2=311,3=0.000000
L 5.30451673 2.74758317 5.3025998 2.75016594 1 P 0 ;0,1,2=311,3=0.000000
L 5.3025998 2.75016594 5.30183327 2.75326624 1 P 0 ;0,1,2=311,3=0.000000
L 5.30183327 2.75326624 5.3025998 2.75636654 1 P 0 ;0,1,2=311,3=0.000000
L 5.3025998 2.75636654 5.30451673 2.75894931 1 P 0 ;0,1,2=311,3=0.000000
L 5.30451673 2.75894931 5.30796673 2.7605 1 P 0 ;0,1,2=311,3=0.000000
L 5.30796673 2.7605 5.31141663 2.75998337 1 P 0 ;0,1,2=311,3=0.000000
L 5.31141663 2.75998337 5.31486663 2.75791624 1 P 0 ;0,1,2=311,3=0.000000
L 5.28693337 2.73569961 5.28463386 2.73208278 1 P 0 ;0,1,2=311,3=0.000000
L 5.28463386 2.73208278 5.28156713 2.73001654 1 P 0 ;0,1,2=311,3=0.000000
L 5.28156713 2.73001654 5.27811644 2.7295 1 P 0 ;0,1,2=311,3=0.000000
L 5.27811644 2.7295 5.2750497 2.73001654 1 P 0 ;0,1,2=311,3=0.000000
L 5.2750497 2.73001654 5.27198297 2.73259931 1 P 0 ;0,1,2=311,3=0.000000
L 5.27198297 2.73259931 5.27006673 2.73569961 1 P 0 ;0,1,2=311,3=0.000000
L 5.27006673 2.73569961 5.26968346 2.7387999 1 P 0 ;0,1,2=311,3=0.000000
L 5.26968346 2.7387999 5.27045 2.74241575 1 P 0 ;0,1,2=311,3=0.000000
L 5.27045 2.74241575 5.27313346 2.74499951 1 P 0 ;0,1,2=311,3=0.000000
L 5.27313346 2.74499951 5.27581693 2.74603356 1 P 0 ;0,1,2=311,3=0.000000
L 5.27581693 2.74603356 5.27926693 2.74603356 1 P 0 ;0,1,2=311,3=0.000000
L 5.27581693 2.74603356 5.27351673 2.74758317 1 P 0 ;0,1,2=311,3=0.000000
L 5.27351673 2.74758317 5.2715998 2.75016594 1 P 0 ;0,1,2=311,3=0.000000
L 5.2715998 2.75016594 5.27083327 2.75326624 1 P 0 ;0,1,2=311,3=0.000000
L 5.27083327 2.75326624 5.2715998 2.75636654 1 P 0 ;0,1,2=311,3=0.000000
L 5.2715998 2.75636654 5.27351673 2.75894931 1 P 0 ;0,1,2=311,3=0.000000
L 5.27351673 2.75894931 5.27696673 2.7605 1 P 0 ;0,1,2=311,3=0.000000
L 5.27696673 2.7605 5.28041663 2.75998337 1 P 0 ;0,1,2=311,3=0.000000
L 5.28041663 2.75998337 5.28386663 2.75791624 1 P 0 ;0,1,2=311,3=0.000000
L 5.57 2.618 5.48 2.618 1 P 0 
L 5.48 2.618 5.48 2.662 1 P 0 
L 5.48 2.662 5.57 2.662 1 P 0 
L 5.57 2.662 5.57 2.618 1 P 0 
L 5.5795 2.63083317 5.6105 2.63083317 1 P 0 ;0,1,2=312,3=90.000000
L 5.6105 2.63083317 5.6105 2.64041654 1 P 0 ;0,1,2=312,3=90.000000
L 5.6105 2.64041654 5.60894931 2.64348327 1 P 0 ;0,1,2=312,3=90.000000
L 5.60894931 2.64348327 5.60688307 2.6454002 1 P 0 ;0,1,2=312,3=90.000000
L 5.60688307 2.6454002 5.6027497 2.64616673 1 P 0 ;0,1,2=312,3=90.000000
L 5.6027497 2.64616673 5.59861634 2.6454002 1 P 0 ;0,1,2=312,3=90.000000
L 5.59861634 2.6454002 5.59603356 2.6431 1 P 0 ;0,1,2=312,3=90.000000
L 5.59603356 2.6431 5.59448287 2.64041654 1 P 0 ;0,1,2=312,3=90.000000
L 5.59448287 2.64041654 5.59448287 2.63083317 1 P 0 ;0,1,2=312,3=90.000000
L 5.59448287 2.64041654 5.5795 2.64616673 1 P 0 ;0,1,2=312,3=90.000000
L 5.5795 2.66949961 5.6105 2.66949961 1 P 0 ;0,1,2=312,3=90.000000
L 5.6105 2.66949961 5.6043003 2.6648999 1 P 0 ;0,1,2=312,3=90.000000
L 5.5795 2.6648999 5.5795 2.67409931 1 P 0 ;0,1,2=312,3=90.000000
L 5.58569961 2.69206663 5.58208278 2.69436614 1 P 0 ;0,1,2=312,3=90.000000
L 5.58208278 2.69436614 5.58001654 2.69743287 1 P 0 ;0,1,2=312,3=90.000000
L 5.58001654 2.69743287 5.5795 2.70088356 1 P 0 ;0,1,2=312,3=90.000000
L 5.5795 2.70088356 5.58001654 2.7039503 1 P 0 ;0,1,2=312,3=90.000000
L 5.58001654 2.7039503 5.58259931 2.70701703 1 P 0 ;0,1,2=312,3=90.000000
L 5.58259931 2.70701703 5.58569961 2.70893327 1 P 0 ;0,1,2=312,3=90.000000
L 5.58569961 2.70893327 5.5887999 2.70931654 1 P 0 ;0,1,2=312,3=90.000000
L 5.5887999 2.70931654 5.59241575 2.70855 1 P 0 ;0,1,2=312,3=90.000000
L 5.59241575 2.70855 5.59499951 2.70586654 1 P 0 ;0,1,2=312,3=90.000000
L 5.59499951 2.70586654 5.59603356 2.70318307 1 P 0 ;0,1,2=312,3=90.000000
L 5.59603356 2.70318307 5.59603356 2.69973307 1 P 0 ;0,1,2=312,3=90.000000
L 5.59603356 2.70318307 5.59758317 2.70548327 1 P 0 ;0,1,2=312,3=90.000000
L 5.59758317 2.70548327 5.60016594 2.7074002 1 P 0 ;0,1,2=312,3=90.000000
L 5.60016594 2.7074002 5.60326624 2.70816673 1 P 0 ;0,1,2=312,3=90.000000
L 5.60326624 2.70816673 5.60636654 2.7074002 1 P 0 ;0,1,2=312,3=90.000000
L 5.60636654 2.7074002 5.60894931 2.70548327 1 P 0 ;0,1,2=312,3=90.000000
L 5.60894931 2.70548327 5.6105 2.70203327 1 P 0 ;0,1,2=312,3=90.000000
L 5.6105 2.70203327 5.60998337 2.69858337 1 P 0 ;0,1,2=312,3=90.000000
L 5.60998337 2.69858337 5.60791624 2.69513337 1 P 0 ;0,1,2=312,3=90.000000
L 5.5795 2.7361 5.6105 2.7361 1 P 0 ;0,1,2=312,3=90.000000
L 5.6105 2.7361 5.58828327 2.72191624 1 P 0 ;0,1,2=312,3=90.000000
L 5.58828327 2.72191624 5.58828327 2.74108366 1 P 0 ;0,1,2=312,3=90.000000
L 5.474 2.837 5.474 2.747 1 P 0 
L 5.474 2.747 5.43 2.747 1 P 0 
L 5.43 2.747 5.43 2.837 1 P 0 
L 5.43 2.837 5.474 2.837 1 P 0 
L 5.2495 2.77583317 5.2805 2.77583317 1 P 0 ;0,1,2=313,3=90.000000
L 5.2805 2.77583317 5.2805 2.78541654 1 P 0 ;0,1,2=313,3=90.000000
L 5.2805 2.78541654 5.27894931 2.78848327 1 P 0 ;0,1,2=313,3=90.000000
L 5.27894931 2.78848327 5.27688307 2.7904002 1 P 0 ;0,1,2=313,3=90.000000
L 5.27688307 2.7904002 5.2727497 2.79116673 1 P 0 ;0,1,2=313,3=90.000000
L 5.2727497 2.79116673 5.26861634 2.7904002 1 P 0 ;0,1,2=313,3=90.000000
L 5.26861634 2.7904002 5.26603356 2.7881 1 P 0 ;0,1,2=313,3=90.000000
L 5.26603356 2.7881 5.26448287 2.78541654 1 P 0 ;0,1,2=313,3=90.000000
L 5.26448287 2.78541654 5.26448287 2.77583317 1 P 0 ;0,1,2=313,3=90.000000
L 5.26448287 2.78541654 5.2495 2.79116673 1 P 0 ;0,1,2=313,3=90.000000
L 5.2495 2.8191 5.2805 2.8191 1 P 0 ;0,1,2=313,3=90.000000
L 5.2805 2.8191 5.25828327 2.80491624 1 P 0 ;0,1,2=313,3=90.000000
L 5.25828327 2.80491624 5.25828327 2.82408366 1 P 0 ;0,1,2=313,3=90.000000
L 5.2805 2.84549961 5.27946683 2.84243287 1 P 0 ;0,1,2=313,3=90.000000
L 5.27946683 2.84243287 5.27688307 2.84013337 1 P 0 ;0,1,2=313,3=90.000000
L 5.27688307 2.84013337 5.27378376 2.8385997 1 P 0 ;0,1,2=313,3=90.000000
L 5.27378376 2.8385997 5.26964941 2.8374499 1 P 0 ;0,1,2=313,3=90.000000
L 5.26964941 2.8374499 5.26499951 2.83706663 1 P 0 ;0,1,2=313,3=90.000000
L 5.26499951 2.83706663 5.26034951 2.8374499 1 P 0 ;0,1,2=313,3=90.000000
L 5.26034951 2.8374499 5.25621614 2.8385997 1 P 0 ;0,1,2=313,3=90.000000
L 5.25621614 2.8385997 5.25311585 2.84013337 1 P 0 ;0,1,2=313,3=90.000000
L 5.25311585 2.84013337 5.25053307 2.84243287 1 P 0 ;0,1,2=313,3=90.000000
L 5.25053307 2.84243287 5.2495 2.84549961 1 P 0 ;0,1,2=313,3=90.000000
L 5.2495 2.84549961 5.25053307 2.84856634 1 P 0 ;0,1,2=313,3=90.000000
L 5.25053307 2.84856634 5.25311585 2.85086654 1 P 0 ;0,1,2=313,3=90.000000
L 5.25311585 2.85086654 5.25621614 2.8524002 1 P 0 ;0,1,2=313,3=90.000000
L 5.25621614 2.8524002 5.26034951 2.85355 1 P 0 ;0,1,2=313,3=90.000000
L 5.26034951 2.85355 5.26499951 2.85393327 1 P 0 ;0,1,2=313,3=90.000000
L 5.26499951 2.85393327 5.26964941 2.85355 1 P 0 ;0,1,2=313,3=90.000000
L 5.26964941 2.85355 5.27378376 2.8524002 1 P 0 ;0,1,2=313,3=90.000000
L 5.27378376 2.8524002 5.27688307 2.85086654 1 P 0 ;0,1,2=313,3=90.000000
L 5.27688307 2.85086654 5.27946683 2.84856634 1 P 0 ;0,1,2=313,3=90.000000
L 5.27946683 2.84856634 5.2805 2.84549961 1 P 0 ;0,1,2=313,3=90.000000
L 5.25569961 2.86806663 5.25208278 2.87036614 1 P 0 ;0,1,2=313,3=90.000000
L 5.25208278 2.87036614 5.25001654 2.87343287 1 P 0 ;0,1,2=313,3=90.000000
L 5.25001654 2.87343287 5.2495 2.87688356 1 P 0 ;0,1,2=313,3=90.000000
L 5.2495 2.87688356 5.25001654 2.8799503 1 P 0 ;0,1,2=313,3=90.000000
L 5.25001654 2.8799503 5.25259931 2.88301703 1 P 0 ;0,1,2=313,3=90.000000
L 5.25259931 2.88301703 5.25569961 2.88493327 1 P 0 ;0,1,2=313,3=90.000000
L 5.25569961 2.88493327 5.2587999 2.88531654 1 P 0 ;0,1,2=313,3=90.000000
L 5.2587999 2.88531654 5.26241575 2.88455 1 P 0 ;0,1,2=313,3=90.000000
L 5.26241575 2.88455 5.26499951 2.88186654 1 P 0 ;0,1,2=313,3=90.000000
L 5.26499951 2.88186654 5.26603356 2.87918307 1 P 0 ;0,1,2=313,3=90.000000
L 5.26603356 2.87918307 5.26603356 2.87573307 1 P 0 ;0,1,2=313,3=90.000000
L 5.26603356 2.87918307 5.26758317 2.88148327 1 P 0 ;0,1,2=313,3=90.000000
L 5.26758317 2.88148327 5.27016594 2.8834002 1 P 0 ;0,1,2=313,3=90.000000
L 5.27016594 2.8834002 5.27326624 2.88416673 1 P 0 ;0,1,2=313,3=90.000000
L 5.27326624 2.88416673 5.27636654 2.8834002 1 P 0 ;0,1,2=313,3=90.000000
L 5.27636654 2.8834002 5.27894931 2.88148327 1 P 0 ;0,1,2=313,3=90.000000
L 5.27894931 2.88148327 5.2805 2.87803327 1 P 0 ;0,1,2=313,3=90.000000
L 5.2805 2.87803327 5.27998337 2.87458337 1 P 0 ;0,1,2=313,3=90.000000
L 5.27998337 2.87458337 5.27791624 2.87113337 1 P 0 ;0,1,2=313,3=90.000000
L 5.4305 2.7035 5.4745 2.7035 1 P 0 
L 5.4305 2.6135 5.4305 2.7035 1 P 0 
L 5.4745 2.7035 5.4745 2.6135 1 P 0 
L 5.4745 2.6135 5.4305 2.6135 1 P 0 
L 5.3895 2.57083317 5.4205 2.57083317 1 P 0 ;0,1,2=314,3=90.000000
L 5.4205 2.57083317 5.4205 2.58041654 1 P 0 ;0,1,2=314,3=90.000000
L 5.4205 2.58041654 5.41894931 2.58348327 1 P 0 ;0,1,2=314,3=90.000000
L 5.41894931 2.58348327 5.41688307 2.5854002 1 P 0 ;0,1,2=314,3=90.000000
L 5.41688307 2.5854002 5.4127497 2.58616673 1 P 0 ;0,1,2=314,3=90.000000
L 5.4127497 2.58616673 5.40861634 2.5854002 1 P 0 ;0,1,2=314,3=90.000000
L 5.40861634 2.5854002 5.40603356 2.5831 1 P 0 ;0,1,2=314,3=90.000000
L 5.40603356 2.5831 5.40448287 2.58041654 1 P 0 ;0,1,2=314,3=90.000000
L 5.40448287 2.58041654 5.40448287 2.57083317 1 P 0 ;0,1,2=314,3=90.000000
L 5.40448287 2.58041654 5.3895 2.58616673 1 P 0 ;0,1,2=314,3=90.000000
L 5.3895 2.6141 5.4205 2.6141 1 P 0 ;0,1,2=314,3=90.000000
L 5.4205 2.6141 5.39828327 2.59991624 1 P 0 ;0,1,2=314,3=90.000000
L 5.39828327 2.59991624 5.39828327 2.61908366 1 P 0 ;0,1,2=314,3=90.000000
L 5.4205 2.64049961 5.41946683 2.63743287 1 P 0 ;0,1,2=314,3=90.000000
L 5.41946683 2.63743287 5.41688307 2.63513337 1 P 0 ;0,1,2=314,3=90.000000
L 5.41688307 2.63513337 5.41378376 2.6335997 1 P 0 ;0,1,2=314,3=90.000000
L 5.41378376 2.6335997 5.40964941 2.6324499 1 P 0 ;0,1,2=314,3=90.000000
L 5.40964941 2.6324499 5.40499951 2.63206663 1 P 0 ;0,1,2=314,3=90.000000
L 5.40499951 2.63206663 5.40034951 2.6324499 1 P 0 ;0,1,2=314,3=90.000000
L 5.40034951 2.6324499 5.39621614 2.6335997 1 P 0 ;0,1,2=314,3=90.000000
L 5.39621614 2.6335997 5.39311585 2.63513337 1 P 0 ;0,1,2=314,3=90.000000
L 5.39311585 2.63513337 5.39053307 2.63743287 1 P 0 ;0,1,2=314,3=90.000000
L 5.39053307 2.63743287 5.3895 2.64049961 1 P 0 ;0,1,2=314,3=90.000000
L 5.3895 2.64049961 5.39053307 2.64356634 1 P 0 ;0,1,2=314,3=90.000000
L 5.39053307 2.64356634 5.39311585 2.64586654 1 P 0 ;0,1,2=314,3=90.000000
L 5.39311585 2.64586654 5.39621614 2.6474002 1 P 0 ;0,1,2=314,3=90.000000
L 5.39621614 2.6474002 5.40034951 2.64855 1 P 0 ;0,1,2=314,3=90.000000
L 5.40034951 2.64855 5.40499951 2.64893327 1 P 0 ;0,1,2=314,3=90.000000
L 5.40499951 2.64893327 5.40964941 2.64855 1 P 0 ;0,1,2=314,3=90.000000
L 5.40964941 2.64855 5.41378376 2.6474002 1 P 0 ;0,1,2=314,3=90.000000
L 5.41378376 2.6474002 5.41688307 2.64586654 1 P 0 ;0,1,2=314,3=90.000000
L 5.41688307 2.64586654 5.41946683 2.64356634 1 P 0 ;0,1,2=314,3=90.000000
L 5.41946683 2.64356634 5.4205 2.64049961 1 P 0 ;0,1,2=314,3=90.000000
L 5.41533346 2.66421644 5.41843278 2.66651663 1 P 0 ;0,1,2=314,3=90.000000
L 5.41843278 2.66651663 5.41998337 2.6692001 1 P 0 ;0,1,2=314,3=90.000000
L 5.41998337 2.6692001 5.4205 2.67226683 1 P 0 ;0,1,2=314,3=90.000000
L 5.4205 2.67226683 5.41946683 2.6761 1 P 0 ;0,1,2=314,3=90.000000
L 5.41946683 2.6761 5.41688307 2.67878346 1 P 0 ;0,1,2=314,3=90.000000
L 5.41688307 2.67878346 5.41378376 2.67955 1 P 0 ;0,1,2=314,3=90.000000
L 5.41378376 2.67955 5.41068258 2.67916673 1 P 0 ;0,1,2=314,3=90.000000
L 5.41068258 2.67916673 5.4080998 2.67763307 1 P 0 ;0,1,2=314,3=90.000000
L 5.4080998 2.67763307 5.40293327 2.66996663 1 P 0 ;0,1,2=314,3=90.000000
L 5.40293327 2.66996663 5.39931644 2.66651663 1 P 0 ;0,1,2=314,3=90.000000
L 5.39931644 2.66651663 5.39414892 2.66421644 1 P 0 ;0,1,2=314,3=90.000000
L 5.39414892 2.66421644 5.3895 2.6634499 1 P 0 ;0,1,2=314,3=90.000000
L 5.3895 2.6634499 5.3895 2.67955 1 P 0 ;0,1,2=314,3=90.000000
L 6.123 4.16 6.167 4.16 1 P 0 
L 6.167 4.16 6.167 4.07 1 P 0 
L 6.167 4.07 6.123 4.07 1 P 0 
L 6.123 4.07 6.123 4.16 1 P 0 
L 6.1795 4.01083317 6.2105 4.01083317 1 P 0 ;0,1,2=315,3=90.000000
L 6.2105 4.01083317 6.2105 4.02041654 1 P 0 ;0,1,2=315,3=90.000000
L 6.2105 4.02041654 6.20894931 4.02348327 1 P 0 ;0,1,2=315,3=90.000000
L 6.20894931 4.02348327 6.20688307 4.0254002 1 P 0 ;0,1,2=315,3=90.000000
L 6.20688307 4.0254002 6.2027497 4.02616673 1 P 0 ;0,1,2=315,3=90.000000
L 6.2027497 4.02616673 6.19861634 4.0254002 1 P 0 ;0,1,2=315,3=90.000000
L 6.19861634 4.0254002 6.19603356 4.0231 1 P 0 ;0,1,2=315,3=90.000000
L 6.19603356 4.0231 6.19448287 4.02041654 1 P 0 ;0,1,2=315,3=90.000000
L 6.19448287 4.02041654 6.19448287 4.01083317 1 P 0 ;0,1,2=315,3=90.000000
L 6.19448287 4.02041654 6.1795 4.02616673 1 P 0 ;0,1,2=315,3=90.000000
L 6.1795 4.04949961 6.2105 4.04949961 1 P 0 ;0,1,2=315,3=90.000000
L 6.2105 4.04949961 6.2043003 4.0448999 1 P 0 ;0,1,2=315,3=90.000000
L 6.1795 4.0448999 6.1795 4.05409931 1 P 0 ;0,1,2=315,3=90.000000
L 6.19241575 4.07321644 6.19603356 4.0758999 1 P 0 ;0,1,2=315,3=90.000000
L 6.19603356 4.0758999 6.1980998 4.0782001 1 P 0 ;0,1,2=315,3=90.000000
L 6.1980998 4.0782001 6.19913287 4.08126683 1 P 0 ;0,1,2=315,3=90.000000
L 6.19913287 4.08126683 6.1980998 4.0839503 1 P 0 ;0,1,2=315,3=90.000000
L 6.1980998 4.0839503 6.19603356 4.08586654 1 P 0 ;0,1,2=315,3=90.000000
L 6.19603356 4.08586654 6.19293327 4.0874002 1 P 0 ;0,1,2=315,3=90.000000
L 6.19293327 4.0874002 6.18931644 4.08778346 1 P 0 ;0,1,2=315,3=90.000000
L 6.18931644 4.08778346 6.18621614 4.0874002 1 P 0 ;0,1,2=315,3=90.000000
L 6.18621614 4.0874002 6.18311585 4.08586654 1 P 0 ;0,1,2=315,3=90.000000
L 6.18311585 4.08586654 6.18053307 4.08356634 1 P 0 ;0,1,2=315,3=90.000000
L 6.18053307 4.08356634 6.1795 4.08088356 1 P 0 ;0,1,2=315,3=90.000000
L 6.1795 4.08088356 6.18053307 4.07781683 1 P 0 ;0,1,2=315,3=90.000000
L 6.18053307 4.07781683 6.18363238 4.07513337 1 P 0 ;0,1,2=315,3=90.000000
L 6.18363238 4.07513337 6.18828327 4.0735997 1 P 0 ;0,1,2=315,3=90.000000
L 6.18828327 4.0735997 6.1934498 4.07321644 1 P 0 ;0,1,2=315,3=90.000000
L 6.1934498 4.07321644 6.20016594 4.07398287 1 P 0 ;0,1,2=315,3=90.000000
L 6.20016594 4.07398287 6.20378376 4.07513337 1 P 0 ;0,1,2=315,3=90.000000
L 6.20378376 4.07513337 6.2073997 4.07704961 1 P 0 ;0,1,2=315,3=90.000000
L 6.2073997 4.07704961 6.20998337 4.07973307 1 P 0 ;0,1,2=315,3=90.000000
L 6.20998337 4.07973307 6.2105 4.08241654 1 P 0 ;0,1,2=315,3=90.000000
L 6.2105 4.08241654 6.20946683 4.0851 1 P 0 ;0,1,2=315,3=90.000000
L 6.20946683 4.0851 6.20688307 4.08701703 1 P 0 ;0,1,2=315,3=90.000000
L 6.18311585 4.10498287 6.18053307 4.10766634 1 P 0 ;0,1,2=315,3=90.000000
L 6.18053307 4.10766634 6.1795 4.11073307 1 P 0 ;0,1,2=315,3=90.000000
L 6.1795 4.11073307 6.18053307 4.1137998 1 P 0 ;0,1,2=315,3=90.000000
L 6.18053307 4.1137998 6.18363238 4.11648327 1 P 0 ;0,1,2=315,3=90.000000
L 6.18363238 4.11648327 6.18828327 4.1184002 1 P 0 ;0,1,2=315,3=90.000000
L 6.18828327 4.1184002 6.19293327 4.11916673 1 P 0 ;0,1,2=315,3=90.000000
L 6.19293327 4.11916673 6.19861634 4.11916673 1 P 0 ;0,1,2=315,3=90.000000
L 6.19861634 4.11916673 6.20326624 4.1184002 1 P 0 ;0,1,2=315,3=90.000000
L 6.20326624 4.1184002 6.2073997 4.11648327 1 P 0 ;0,1,2=315,3=90.000000
L 6.2073997 4.11648327 6.20946683 4.11418307 1 P 0 ;0,1,2=315,3=90.000000
L 6.20946683 4.11418307 6.2105 4.11149961 1 P 0 ;0,1,2=315,3=90.000000
L 6.2105 4.11149961 6.20946683 4.10843287 1 P 0 ;0,1,2=315,3=90.000000
L 6.20946683 4.10843287 6.2073997 4.10613337 1 P 0 ;0,1,2=315,3=90.000000
L 6.2073997 4.10613337 6.2043003 4.1045997 1 P 0 ;0,1,2=315,3=90.000000
L 6.2043003 4.1045997 6.20016594 4.10383317 1 P 0 ;0,1,2=315,3=90.000000
L 6.20016594 4.10383317 6.1965501 4.1045997 1 P 0 ;0,1,2=315,3=90.000000
L 6.1965501 4.1045997 6.19293327 4.10651663 1 P 0 ;0,1,2=315,3=90.000000
L 6.19293327 4.10651663 6.19086604 4.10881683 1 P 0 ;0,1,2=315,3=90.000000
L 6.19086604 4.10881683 6.19034951 4.11149961 1 P 0 ;0,1,2=315,3=90.000000
L 6.19034951 4.11149961 6.19138268 4.11456634 1 P 0 ;0,1,2=315,3=90.000000
L 6.19138268 4.11456634 6.19396634 4.11686654 1 P 0 ;0,1,2=315,3=90.000000
L 6.19396634 4.11686654 6.19861634 4.11916673 1 P 0 ;0,1,2=315,3=90.000000
L 3.956 2.576 4 2.576 1 P 0 
L 4 2.576 4 2.486 1 P 0 
L 4 2.486 3.956 2.486 1 P 0 
L 3.956 2.486 3.956 2.576 1 P 0 
L 3.9545 2.61083317 3.9855 2.61083317 1 P 0 ;0,1,2=316,3=90.000000
L 3.9855 2.61083317 3.9855 2.62041654 1 P 0 ;0,1,2=316,3=90.000000
L 3.9855 2.62041654 3.98394931 2.62348327 1 P 0 ;0,1,2=316,3=90.000000
L 3.98394931 2.62348327 3.98188307 2.6254002 1 P 0 ;0,1,2=316,3=90.000000
L 3.98188307 2.6254002 3.9777497 2.62616673 1 P 0 ;0,1,2=316,3=90.000000
L 3.9777497 2.62616673 3.97361634 2.6254002 1 P 0 ;0,1,2=316,3=90.000000
L 3.97361634 2.6254002 3.97103356 2.6231 1 P 0 ;0,1,2=316,3=90.000000
L 3.97103356 2.6231 3.96948287 2.62041654 1 P 0 ;0,1,2=316,3=90.000000
L 3.96948287 2.62041654 3.96948287 2.61083317 1 P 0 ;0,1,2=316,3=90.000000
L 3.96948287 2.62041654 3.9545 2.62616673 1 P 0 ;0,1,2=316,3=90.000000
L 3.9545 2.64949961 3.9855 2.64949961 1 P 0 ;0,1,2=316,3=90.000000
L 3.9855 2.64949961 3.9793003 2.6448999 1 P 0 ;0,1,2=316,3=90.000000
L 3.9545 2.6448999 3.9545 2.65409931 1 P 0 ;0,1,2=316,3=90.000000
L 3.9545 2.67973307 3.96121614 2.68049961 1 P 0 ;0,1,2=316,3=90.000000
L 3.96121614 2.68049961 3.96689921 2.6816501 1 P 0 ;0,1,2=316,3=90.000000
L 3.96689921 2.6816501 3.97206663 2.68318307 1 P 0 ;0,1,2=316,3=90.000000
L 3.97206663 2.68318307 3.9777497 2.6851 1 P 0 ;0,1,2=316,3=90.000000
L 3.9777497 2.6851 3.9855 2.68816673 1 P 0 ;0,1,2=316,3=90.000000
L 3.9855 2.68816673 3.9855 2.67283317 1 P 0 ;0,1,2=316,3=90.000000
L 3.9545 2.71149961 3.9855 2.71149961 1 P 0 ;0,1,2=316,3=90.000000
L 3.9855 2.71149961 3.9793003 2.7068999 1 P 0 ;0,1,2=316,3=90.000000
L 3.9545 2.7068999 3.9545 2.71609931 1 P 0 ;0,1,2=316,3=90.000000
L 3.492 2.4 3.492 2.31 1 P 0 
L 3.448 2.4 3.492 2.4 1 P 0 
L 3.492 2.31 3.448 2.31 1 P 0 
L 3.448 2.31 3.448 2.4 1 P 0 
L 3.4645 2.41083317 3.4955 2.41083317 1 P 0 ;0,1,2=317,3=90.000000
L 3.4955 2.41083317 3.4955 2.42041654 1 P 0 ;0,1,2=317,3=90.000000
L 3.4955 2.42041654 3.49394931 2.42348327 1 P 0 ;0,1,2=317,3=90.000000
L 3.49394931 2.42348327 3.49188307 2.4254002 1 P 0 ;0,1,2=317,3=90.000000
L 3.49188307 2.4254002 3.4877497 2.42616673 1 P 0 ;0,1,2=317,3=90.000000
L 3.4877497 2.42616673 3.48361634 2.4254002 1 P 0 ;0,1,2=317,3=90.000000
L 3.48361634 2.4254002 3.48103356 2.4231 1 P 0 ;0,1,2=317,3=90.000000
L 3.48103356 2.4231 3.47948287 2.42041654 1 P 0 ;0,1,2=317,3=90.000000
L 3.47948287 2.42041654 3.47948287 2.41083317 1 P 0 ;0,1,2=317,3=90.000000
L 3.47948287 2.42041654 3.4645 2.42616673 1 P 0 ;0,1,2=317,3=90.000000
L 3.4645 2.44949961 3.4955 2.44949961 1 P 0 ;0,1,2=317,3=90.000000
L 3.4955 2.44949961 3.4893003 2.4448999 1 P 0 ;0,1,2=317,3=90.000000
L 3.4645 2.4448999 3.4645 2.45409931 1 P 0 ;0,1,2=317,3=90.000000
L 3.47741575 2.47321644 3.48103356 2.4758999 1 P 0 ;0,1,2=317,3=90.000000
L 3.48103356 2.4758999 3.4830998 2.4782001 1 P 0 ;0,1,2=317,3=90.000000
L 3.4830998 2.4782001 3.48413287 2.48126683 1 P 0 ;0,1,2=317,3=90.000000
L 3.48413287 2.48126683 3.4830998 2.4839503 1 P 0 ;0,1,2=317,3=90.000000
L 3.4830998 2.4839503 3.48103356 2.48586654 1 P 0 ;0,1,2=317,3=90.000000
L 3.48103356 2.48586654 3.47793327 2.4874002 1 P 0 ;0,1,2=317,3=90.000000
L 3.47793327 2.4874002 3.47431644 2.48778346 1 P 0 ;0,1,2=317,3=90.000000
L 3.47431644 2.48778346 3.47121614 2.4874002 1 P 0 ;0,1,2=317,3=90.000000
L 3.47121614 2.4874002 3.46811585 2.48586654 1 P 0 ;0,1,2=317,3=90.000000
L 3.46811585 2.48586654 3.46553307 2.48356634 1 P 0 ;0,1,2=317,3=90.000000
L 3.46553307 2.48356634 3.4645 2.48088356 1 P 0 ;0,1,2=317,3=90.000000
L 3.4645 2.48088356 3.46553307 2.47781683 1 P 0 ;0,1,2=317,3=90.000000
L 3.46553307 2.47781683 3.46863238 2.47513337 1 P 0 ;0,1,2=317,3=90.000000
L 3.46863238 2.47513337 3.47328327 2.4735997 1 P 0 ;0,1,2=317,3=90.000000
L 3.47328327 2.4735997 3.4784498 2.47321644 1 P 0 ;0,1,2=317,3=90.000000
L 3.4784498 2.47321644 3.48516594 2.47398287 1 P 0 ;0,1,2=317,3=90.000000
L 3.48516594 2.47398287 3.48878376 2.47513337 1 P 0 ;0,1,2=317,3=90.000000
L 3.48878376 2.47513337 3.4923997 2.47704961 1 P 0 ;0,1,2=317,3=90.000000
L 3.4923997 2.47704961 3.49498337 2.47973307 1 P 0 ;0,1,2=317,3=90.000000
L 3.49498337 2.47973307 3.4955 2.48241654 1 P 0 ;0,1,2=317,3=90.000000
L 3.4955 2.48241654 3.49446683 2.4851 1 P 0 ;0,1,2=317,3=90.000000
L 3.49446683 2.4851 3.49188307 2.48701703 1 P 0 ;0,1,2=317,3=90.000000
L 3.4645 2.51149961 3.46501654 2.51418307 1 P 0 ;0,1,2=317,3=90.000000
L 3.46501654 2.51418307 3.46656614 2.5172498 1 P 0 ;0,1,2=317,3=90.000000
L 3.46656614 2.5172498 3.46914892 2.51916673 1 P 0 ;0,1,2=317,3=90.000000
L 3.46914892 2.51916673 3.47276673 2.51993327 1 P 0 ;0,1,2=317,3=90.000000
L 3.47276673 2.51993327 3.47638268 2.51916673 1 P 0 ;0,1,2=317,3=90.000000
L 3.47638268 2.51916673 3.47948287 2.51686654 1 P 0 ;0,1,2=317,3=90.000000
L 3.47948287 2.51686654 3.48103356 2.51341654 1 P 0 ;0,1,2=317,3=90.000000
L 3.48103356 2.51341654 3.48103356 2.50958337 1 P 0 ;0,1,2=317,3=90.000000
L 3.48103356 2.50958337 3.48206663 2.50728317 1 P 0 ;0,1,2=317,3=90.000000
L 3.48206663 2.50728317 3.48464941 2.50536614 1 P 0 ;0,1,2=317,3=90.000000
L 3.48464941 2.50536614 3.48826624 2.5045997 1 P 0 ;0,1,2=317,3=90.000000
L 3.48826624 2.5045997 3.49188307 2.5057501 1 P 0 ;0,1,2=317,3=90.000000
L 3.49188307 2.5057501 3.49446683 2.50843287 1 P 0 ;0,1,2=317,3=90.000000
L 3.49446683 2.50843287 3.4955 2.51149961 1 P 0 ;0,1,2=317,3=90.000000
L 3.4955 2.51149961 3.49446683 2.51456634 1 P 0 ;0,1,2=317,3=90.000000
L 3.49446683 2.51456634 3.49188307 2.5172498 1 P 0 ;0,1,2=317,3=90.000000
L 3.49188307 2.5172498 3.48826624 2.5184002 1 P 0 ;0,1,2=317,3=90.000000
L 3.48826624 2.5184002 3.48464941 2.51763307 1 P 0 ;0,1,2=317,3=90.000000
L 3.48464941 2.51763307 3.48206663 2.51571673 1 P 0 ;0,1,2=317,3=90.000000
L 3.48206663 2.51571673 3.48103356 2.51341654 1 P 0 ;0,1,2=317,3=90.000000
L 3.48103356 2.51341654 3.48103356 2.50958337 1 P 0 ;0,1,2=317,3=90.000000
L 3.48103356 2.50958337 3.47948287 2.50613337 1 P 0 ;0,1,2=317,3=90.000000
L 3.47948287 2.50613337 3.47638268 2.50383317 1 P 0 ;0,1,2=317,3=90.000000
L 3.47638268 2.50383317 3.47276673 2.50306663 1 P 0 ;0,1,2=317,3=90.000000
L 3.47276673 2.50306663 3.46914892 2.50383317 1 P 0 ;0,1,2=317,3=90.000000
L 3.46914892 2.50383317 3.46656614 2.5057501 1 P 0 ;0,1,2=317,3=90.000000
L 3.46656614 2.5057501 3.46501654 2.50881683 1 P 0 ;0,1,2=317,3=90.000000
L 3.46501654 2.50881683 3.4645 2.51149961 1 P 0 ;0,1,2=317,3=90.000000
L 5.48 3.042 5.57 3.042 1 P 0 
L 5.57 2.998 5.48 2.998 1 P 0 
L 5.48 2.998 5.48 3.042 1 P 0 
L 5.57 3.042 5.57 2.998 1 P 0 
L 5.57916683 3.0945 5.57916683 3.1255 1 P 0 ;0,1,2=318,3=0.000000
L 5.57916683 3.1255 5.56958346 3.1255 1 P 0 ;0,1,2=318,3=0.000000
L 5.56958346 3.1255 5.56651673 3.12394931 1 P 0 ;0,1,2=318,3=0.000000
L 5.56651673 3.12394931 5.5645998 3.12188307 1 P 0 ;0,1,2=318,3=0.000000
L 5.5645998 3.12188307 5.56383327 3.1177497 1 P 0 ;0,1,2=318,3=0.000000
L 5.56383327 3.1177497 5.5645998 3.11361634 1 P 0 ;0,1,2=318,3=0.000000
L 5.5645998 3.11361634 5.5669 3.11103356 1 P 0 ;0,1,2=318,3=0.000000
L 5.5669 3.11103356 5.56958346 3.10948287 1 P 0 ;0,1,2=318,3=0.000000
L 5.56958346 3.10948287 5.57916683 3.10948287 1 P 0 ;0,1,2=318,3=0.000000
L 5.56958346 3.10948287 5.56383327 3.0945 1 P 0 ;0,1,2=318,3=0.000000
L 5.54050039 3.0945 5.54050039 3.1255 1 P 0 ;0,1,2=318,3=0.000000
L 5.54050039 3.1255 5.5451001 3.1193003 1 P 0 ;0,1,2=318,3=0.000000
L 5.5451001 3.0945 5.53590069 3.0945 1 P 0 ;0,1,2=318,3=0.000000
L 5.51793337 3.10069961 5.51563386 3.09708278 1 P 0 ;0,1,2=318,3=0.000000
L 5.51563386 3.09708278 5.51256713 3.09501654 1 P 0 ;0,1,2=318,3=0.000000
L 5.51256713 3.09501654 5.50911644 3.0945 1 P 0 ;0,1,2=318,3=0.000000
L 5.50911644 3.0945 5.5060497 3.09501654 1 P 0 ;0,1,2=318,3=0.000000
L 5.5060497 3.09501654 5.50298297 3.09759931 1 P 0 ;0,1,2=318,3=0.000000
L 5.50298297 3.09759931 5.50106673 3.10069961 1 P 0 ;0,1,2=318,3=0.000000
L 5.50106673 3.10069961 5.50068346 3.1037999 1 P 0 ;0,1,2=318,3=0.000000
L 5.50068346 3.1037999 5.50145 3.10741575 1 P 0 ;0,1,2=318,3=0.000000
L 5.50145 3.10741575 5.50413346 3.10999951 1 P 0 ;0,1,2=318,3=0.000000
L 5.50413346 3.10999951 5.50681693 3.11103356 1 P 0 ;0,1,2=318,3=0.000000
L 5.50681693 3.11103356 5.51026693 3.11103356 1 P 0 ;0,1,2=318,3=0.000000
L 5.50681693 3.11103356 5.50451673 3.11258317 1 P 0 ;0,1,2=318,3=0.000000
L 5.50451673 3.11258317 5.5025998 3.11516594 1 P 0 ;0,1,2=318,3=0.000000
L 5.5025998 3.11516594 5.50183327 3.11826624 1 P 0 ;0,1,2=318,3=0.000000
L 5.50183327 3.11826624 5.5025998 3.12136654 1 P 0 ;0,1,2=318,3=0.000000
L 5.5025998 3.12136654 5.50451673 3.12394931 1 P 0 ;0,1,2=318,3=0.000000
L 5.50451673 3.12394931 5.50796673 3.1255 1 P 0 ;0,1,2=318,3=0.000000
L 5.50796673 3.1255 5.51141663 3.12498337 1 P 0 ;0,1,2=318,3=0.000000
L 5.51141663 3.12498337 5.51486663 3.12291624 1 P 0 ;0,1,2=318,3=0.000000
L 5.47926693 3.0945 5.47850039 3.10121614 1 P 0 ;0,1,2=318,3=0.000000
L 5.47850039 3.10121614 5.4773499 3.10689921 1 P 0 ;0,1,2=318,3=0.000000
L 5.4773499 3.10689921 5.47581693 3.11206663 1 P 0 ;0,1,2=318,3=0.000000
L 5.47581693 3.11206663 5.4739 3.1177497 1 P 0 ;0,1,2=318,3=0.000000
L 5.4739 3.1177497 5.47083327 3.1255 1 P 0 ;0,1,2=318,3=0.000000
L 5.47083327 3.1255 5.48616683 3.1255 1 P 0 ;0,1,2=318,3=0.000000
L 5.568 2.9005 5.478 2.9005 1 P 0 
L 5.478 2.9005 5.478 2.9445 1 P 0 
L 5.478 2.9445 5.568 2.9445 1 P 0 
L 5.568 2.9445 5.568 2.9005 1 P 0 
L 5.59416683 2.9495 5.59416683 2.9805 1 P 0 ;0,1,2=319,3=0.000000
L 5.59416683 2.9805 5.58458346 2.9805 1 P 0 ;0,1,2=319,3=0.000000
L 5.58458346 2.9805 5.58151673 2.97894931 1 P 0 ;0,1,2=319,3=0.000000
L 5.58151673 2.97894931 5.5795998 2.97688307 1 P 0 ;0,1,2=319,3=0.000000
L 5.5795998 2.97688307 5.57883327 2.9727497 1 P 0 ;0,1,2=319,3=0.000000
L 5.57883327 2.9727497 5.5795998 2.96861634 1 P 0 ;0,1,2=319,3=0.000000
L 5.5795998 2.96861634 5.5819 2.96603356 1 P 0 ;0,1,2=319,3=0.000000
L 5.5819 2.96603356 5.58458346 2.96448287 1 P 0 ;0,1,2=319,3=0.000000
L 5.58458346 2.96448287 5.59416683 2.96448287 1 P 0 ;0,1,2=319,3=0.000000
L 5.58458346 2.96448287 5.57883327 2.9495 1 P 0 ;0,1,2=319,3=0.000000
L 5.55550039 2.9495 5.55550039 2.9805 1 P 0 ;0,1,2=319,3=0.000000
L 5.55550039 2.9805 5.5601001 2.9743003 1 P 0 ;0,1,2=319,3=0.000000
L 5.5601001 2.9495 5.55090069 2.9495 1 P 0 ;0,1,2=319,3=0.000000
L 5.53293337 2.95569961 5.53063386 2.95208278 1 P 0 ;0,1,2=319,3=0.000000
L 5.53063386 2.95208278 5.52756713 2.95001654 1 P 0 ;0,1,2=319,3=0.000000
L 5.52756713 2.95001654 5.52411644 2.9495 1 P 0 ;0,1,2=319,3=0.000000
L 5.52411644 2.9495 5.5210497 2.95001654 1 P 0 ;0,1,2=319,3=0.000000
L 5.5210497 2.95001654 5.51798297 2.95259931 1 P 0 ;0,1,2=319,3=0.000000
L 5.51798297 2.95259931 5.51606673 2.95569961 1 P 0 ;0,1,2=319,3=0.000000
L 5.51606673 2.95569961 5.51568346 2.9587999 1 P 0 ;0,1,2=319,3=0.000000
L 5.51568346 2.9587999 5.51645 2.96241575 1 P 0 ;0,1,2=319,3=0.000000
L 5.51645 2.96241575 5.51913346 2.96499951 1 P 0 ;0,1,2=319,3=0.000000
L 5.51913346 2.96499951 5.52181693 2.96603356 1 P 0 ;0,1,2=319,3=0.000000
L 5.52181693 2.96603356 5.52526693 2.96603356 1 P 0 ;0,1,2=319,3=0.000000
L 5.52181693 2.96603356 5.51951673 2.96758317 1 P 0 ;0,1,2=319,3=0.000000
L 5.51951673 2.96758317 5.5175998 2.97016594 1 P 0 ;0,1,2=319,3=0.000000
L 5.5175998 2.97016594 5.51683327 2.97326624 1 P 0 ;0,1,2=319,3=0.000000
L 5.51683327 2.97326624 5.5175998 2.97636654 1 P 0 ;0,1,2=319,3=0.000000
L 5.5175998 2.97636654 5.51951673 2.97894931 1 P 0 ;0,1,2=319,3=0.000000
L 5.51951673 2.97894931 5.52296673 2.9805 1 P 0 ;0,1,2=319,3=0.000000
L 5.52296673 2.9805 5.52641663 2.97998337 1 P 0 ;0,1,2=319,3=0.000000
L 5.52641663 2.97998337 5.52986663 2.97791624 1 P 0 ;0,1,2=319,3=0.000000
L 5.50078356 2.96241575 5.4981001 2.96603356 1 P 0 ;0,1,2=319,3=0.000000
L 5.4981001 2.96603356 5.4957999 2.9680998 1 P 0 ;0,1,2=319,3=0.000000
L 5.4957999 2.9680998 5.49273317 2.96913287 1 P 0 ;0,1,2=319,3=0.000000
L 5.49273317 2.96913287 5.4900497 2.9680998 1 P 0 ;0,1,2=319,3=0.000000
L 5.4900497 2.9680998 5.48813346 2.96603356 1 P 0 ;0,1,2=319,3=0.000000
L 5.48813346 2.96603356 5.4865998 2.96293327 1 P 0 ;0,1,2=319,3=0.000000
L 5.4865998 2.96293327 5.48621654 2.95931644 1 P 0 ;0,1,2=319,3=0.000000
L 5.48621654 2.95931644 5.4865998 2.95621614 1 P 0 ;0,1,2=319,3=0.000000
L 5.4865998 2.95621614 5.48813346 2.95311585 1 P 0 ;0,1,2=319,3=0.000000
L 5.48813346 2.95311585 5.49043366 2.95053307 1 P 0 ;0,1,2=319,3=0.000000
L 5.49043366 2.95053307 5.49311644 2.9495 1 P 0 ;0,1,2=319,3=0.000000
L 5.49311644 2.9495 5.49618317 2.95053307 1 P 0 ;0,1,2=319,3=0.000000
L 5.49618317 2.95053307 5.49886663 2.95363238 1 P 0 ;0,1,2=319,3=0.000000
L 5.49886663 2.95363238 5.5004003 2.95828327 1 P 0 ;0,1,2=319,3=0.000000
L 5.5004003 2.95828327 5.50078356 2.9634498 1 P 0 ;0,1,2=319,3=0.000000
L 5.50078356 2.9634498 5.50001713 2.97016594 1 P 0 ;0,1,2=319,3=0.000000
L 5.50001713 2.97016594 5.49886663 2.97378376 1 P 0 ;0,1,2=319,3=0.000000
L 5.49886663 2.97378376 5.49695039 2.9773997 1 P 0 ;0,1,2=319,3=0.000000
L 5.49695039 2.9773997 5.49426693 2.97998337 1 P 0 ;0,1,2=319,3=0.000000
L 5.49426693 2.97998337 5.49158346 2.9805 1 P 0 ;0,1,2=319,3=0.000000
L 5.49158346 2.9805 5.4889 2.97946683 1 P 0 ;0,1,2=319,3=0.000000
L 5.4889 2.97946683 5.48698297 2.97688307 1 P 0 ;0,1,2=319,3=0.000000
L 0.856 0.977 0.9 0.977 1 P 0 
L 0.9 0.977 0.9 0.887 1 P 0 
L 0.9 0.887 0.856 0.887 1 P 0 
L 0.856 0.887 0.856 0.977 1 P 0 
L 0.8645 0.98083317 0.8955 0.98083317 1 P 0 ;0,1,2=320,3=90.000000
L 0.8955 0.98083317 0.8955 0.99041654 1 P 0 ;0,1,2=320,3=90.000000
L 0.8955 0.99041654 0.89394931 0.99348327 1 P 0 ;0,1,2=320,3=90.000000
L 0.89394931 0.99348327 0.89188307 0.9954002 1 P 0 ;0,1,2=320,3=90.000000
L 0.89188307 0.9954002 0.8877497 0.99616673 1 P 0 ;0,1,2=320,3=90.000000
L 0.8877497 0.99616673 0.88361634 0.9954002 1 P 0 ;0,1,2=320,3=90.000000
L 0.88361634 0.9954002 0.88103356 0.9931 1 P 0 ;0,1,2=320,3=90.000000
L 0.88103356 0.9931 0.87948287 0.99041654 1 P 0 ;0,1,2=320,3=90.000000
L 0.87948287 0.99041654 0.87948287 0.98083317 1 P 0 ;0,1,2=320,3=90.000000
L 0.87948287 0.99041654 0.8645 0.99616673 1 P 0 ;0,1,2=320,3=90.000000
L 0.8645 1.01949961 0.8955 1.01949961 1 P 0 ;0,1,2=320,3=90.000000
L 0.8955 1.01949961 0.8893003 1.0148999 1 P 0 ;0,1,2=320,3=90.000000
L 0.8645 1.0148999 0.8645 1.02409931 1 P 0 ;0,1,2=320,3=90.000000
L 0.86914892 1.04206663 0.86656614 1.04436614 1 P 0 ;0,1,2=320,3=90.000000
L 0.86656614 1.04436614 0.86501654 1.04704961 1 P 0 ;0,1,2=320,3=90.000000
L 0.86501654 1.04704961 0.8645 1.05049961 1 P 0 ;0,1,2=320,3=90.000000
L 0.8645 1.05049961 0.86553307 1.0539503 1 P 0 ;0,1,2=320,3=90.000000
L 0.86553307 1.0539503 0.86759931 1.05663307 1 P 0 ;0,1,2=320,3=90.000000
L 0.86759931 1.05663307 0.87121614 1.05855 1 P 0 ;0,1,2=320,3=90.000000
L 0.87121614 1.05855 0.87534951 1.05893327 1 P 0 ;0,1,2=320,3=90.000000
L 0.87534951 1.05893327 0.87948287 1.05816673 1 P 0 ;0,1,2=320,3=90.000000
L 0.87948287 1.05816673 0.88206663 1.0562498 1 P 0 ;0,1,2=320,3=90.000000
L 0.88206663 1.0562498 0.88413287 1.05356634 1 P 0 ;0,1,2=320,3=90.000000
L 0.88413287 1.05356634 0.88464941 1.05088356 1 P 0 ;0,1,2=320,3=90.000000
L 0.88464941 1.05088356 0.88413287 1.0482001 1 P 0 ;0,1,2=320,3=90.000000
L 0.88413287 1.0482001 0.88206663 1.0447501 1 P 0 ;0,1,2=320,3=90.000000
L 0.88206663 1.0447501 0.8955 1.0458999 1 P 0 ;0,1,2=320,3=90.000000
L 0.8955 1.0458999 0.8955 1.0562498 1 P 0 ;0,1,2=320,3=90.000000
L 0.86811585 1.07498287 0.86553307 1.07766634 1 P 0 ;0,1,2=320,3=90.000000
L 0.86553307 1.07766634 0.8645 1.08073307 1 P 0 ;0,1,2=320,3=90.000000
L 0.8645 1.08073307 0.86553307 1.0837998 1 P 0 ;0,1,2=320,3=90.000000
L 0.86553307 1.0837998 0.86863238 1.08648327 1 P 0 ;0,1,2=320,3=90.000000
L 0.86863238 1.08648327 0.87328327 1.0884002 1 P 0 ;0,1,2=320,3=90.000000
L 0.87328327 1.0884002 0.87793327 1.08916673 1 P 0 ;0,1,2=320,3=90.000000
L 0.87793327 1.08916673 0.88361634 1.08916673 1 P 0 ;0,1,2=320,3=90.000000
L 0.88361634 1.08916673 0.88826624 1.0884002 1 P 0 ;0,1,2=320,3=90.000000
L 0.88826624 1.0884002 0.8923997 1.08648327 1 P 0 ;0,1,2=320,3=90.000000
L 0.8923997 1.08648327 0.89446683 1.08418307 1 P 0 ;0,1,2=320,3=90.000000
L 0.89446683 1.08418307 0.8955 1.08149961 1 P 0 ;0,1,2=320,3=90.000000
L 0.8955 1.08149961 0.89446683 1.07843287 1 P 0 ;0,1,2=320,3=90.000000
L 0.89446683 1.07843287 0.8923997 1.07613337 1 P 0 ;0,1,2=320,3=90.000000
L 0.8923997 1.07613337 0.8893003 1.0745997 1 P 0 ;0,1,2=320,3=90.000000
L 0.8893003 1.0745997 0.88516594 1.07383317 1 P 0 ;0,1,2=320,3=90.000000
L 0.88516594 1.07383317 0.8815501 1.0745997 1 P 0 ;0,1,2=320,3=90.000000
L 0.8815501 1.0745997 0.87793327 1.07651663 1 P 0 ;0,1,2=320,3=90.000000
L 0.87793327 1.07651663 0.87586604 1.07881683 1 P 0 ;0,1,2=320,3=90.000000
L 0.87586604 1.07881683 0.87534951 1.08149961 1 P 0 ;0,1,2=320,3=90.000000
L 0.87534951 1.08149961 0.87638268 1.08456634 1 P 0 ;0,1,2=320,3=90.000000
L 0.87638268 1.08456634 0.87896634 1.08686654 1 P 0 ;0,1,2=320,3=90.000000
L 0.87896634 1.08686654 0.88361634 1.08916673 1 P 0 ;0,1,2=320,3=90.000000
L 5.345 4.22501004 5.345 4.13501004 1 P 0 
L 5.345 4.13501004 5.301 4.13501004 1 P 0 
L 5.301 4.13501004 5.301 4.22501004 1 P 0 
L 5.301 4.22501004 5.345 4.22501004 1 P 0 
L 5.3445 3.82083317 5.3755 3.82083317 1 P 0 ;0,1,2=321,3=90.000000
L 5.3755 3.82083317 5.3755 3.83041654 1 P 0 ;0,1,2=321,3=90.000000
L 5.3755 3.83041654 5.37394931 3.83348327 1 P 0 ;0,1,2=321,3=90.000000
L 5.37394931 3.83348327 5.37188307 3.8354002 1 P 0 ;0,1,2=321,3=90.000000
L 5.37188307 3.8354002 5.3677497 3.83616673 1 P 0 ;0,1,2=321,3=90.000000
L 5.3677497 3.83616673 5.36361634 3.8354002 1 P 0 ;0,1,2=321,3=90.000000
L 5.36361634 3.8354002 5.36103356 3.8331 1 P 0 ;0,1,2=321,3=90.000000
L 5.36103356 3.8331 5.35948287 3.83041654 1 P 0 ;0,1,2=321,3=90.000000
L 5.35948287 3.83041654 5.35948287 3.82083317 1 P 0 ;0,1,2=321,3=90.000000
L 5.35948287 3.83041654 5.3445 3.83616673 1 P 0 ;0,1,2=321,3=90.000000
L 5.37033346 3.85221644 5.37343278 3.85451663 1 P 0 ;0,1,2=321,3=90.000000
L 5.37343278 3.85451663 5.37498337 3.8572001 1 P 0 ;0,1,2=321,3=90.000000
L 5.37498337 3.8572001 5.3755 3.86026683 1 P 0 ;0,1,2=321,3=90.000000
L 5.3755 3.86026683 5.37446683 3.8641 1 P 0 ;0,1,2=321,3=90.000000
L 5.37446683 3.8641 5.37188307 3.86678346 1 P 0 ;0,1,2=321,3=90.000000
L 5.37188307 3.86678346 5.36878376 3.86755 1 P 0 ;0,1,2=321,3=90.000000
L 5.36878376 3.86755 5.36568258 3.86716673 1 P 0 ;0,1,2=321,3=90.000000
L 5.36568258 3.86716673 5.3630998 3.86563307 1 P 0 ;0,1,2=321,3=90.000000
L 5.3630998 3.86563307 5.35793327 3.85796663 1 P 0 ;0,1,2=321,3=90.000000
L 5.35793327 3.85796663 5.35431644 3.85451663 1 P 0 ;0,1,2=321,3=90.000000
L 5.35431644 3.85451663 5.34914892 3.85221644 1 P 0 ;0,1,2=321,3=90.000000
L 5.34914892 3.85221644 5.3445 3.8514499 1 P 0 ;0,1,2=321,3=90.000000
L 5.3445 3.8514499 5.3445 3.86755 1 P 0 ;0,1,2=321,3=90.000000
L 5.3755 3.89049961 5.37446683 3.88743287 1 P 0 ;0,1,2=321,3=90.000000
L 5.37446683 3.88743287 5.37188307 3.88513337 1 P 0 ;0,1,2=321,3=90.000000
L 5.37188307 3.88513337 5.36878376 3.8835997 1 P 0 ;0,1,2=321,3=90.000000
L 5.36878376 3.8835997 5.36464941 3.8824499 1 P 0 ;0,1,2=321,3=90.000000
L 5.36464941 3.8824499 5.35999951 3.88206663 1 P 0 ;0,1,2=321,3=90.000000
L 5.35999951 3.88206663 5.35534951 3.8824499 1 P 0 ;0,1,2=321,3=90.000000
L 5.35534951 3.8824499 5.35121614 3.8835997 1 P 0 ;0,1,2=321,3=90.000000
L 5.35121614 3.8835997 5.34811585 3.88513337 1 P 0 ;0,1,2=321,3=90.000000
L 5.34811585 3.88513337 5.34553307 3.88743287 1 P 0 ;0,1,2=321,3=90.000000
L 5.34553307 3.88743287 5.3445 3.89049961 1 P 0 ;0,1,2=321,3=90.000000
L 5.3445 3.89049961 5.34553307 3.89356634 1 P 0 ;0,1,2=321,3=90.000000
L 5.34553307 3.89356634 5.34811585 3.89586654 1 P 0 ;0,1,2=321,3=90.000000
L 5.34811585 3.89586654 5.35121614 3.8974002 1 P 0 ;0,1,2=321,3=90.000000
L 5.35121614 3.8974002 5.35534951 3.89855 1 P 0 ;0,1,2=321,3=90.000000
L 5.35534951 3.89855 5.35999951 3.89893327 1 P 0 ;0,1,2=321,3=90.000000
L 5.35999951 3.89893327 5.36464941 3.89855 1 P 0 ;0,1,2=321,3=90.000000
L 5.36464941 3.89855 5.36878376 3.8974002 1 P 0 ;0,1,2=321,3=90.000000
L 5.36878376 3.8974002 5.37188307 3.89586654 1 P 0 ;0,1,2=321,3=90.000000
L 5.37188307 3.89586654 5.37446683 3.89356634 1 P 0 ;0,1,2=321,3=90.000000
L 5.37446683 3.89356634 5.3755 3.89049961 1 P 0 ;0,1,2=321,3=90.000000
L 5.3445 3.92149961 5.34501654 3.92418307 1 P 0 ;0,1,2=321,3=90.000000
L 5.34501654 3.92418307 5.34656614 3.9272498 1 P 0 ;0,1,2=321,3=90.000000
L 5.34656614 3.9272498 5.34914892 3.92916673 1 P 0 ;0,1,2=321,3=90.000000
L 5.34914892 3.92916673 5.35276673 3.92993327 1 P 0 ;0,1,2=321,3=90.000000
L 5.35276673 3.92993327 5.35638268 3.92916673 1 P 0 ;0,1,2=321,3=90.000000
L 5.35638268 3.92916673 5.35948287 3.92686654 1 P 0 ;0,1,2=321,3=90.000000
L 5.35948287 3.92686654 5.36103356 3.92341654 1 P 0 ;0,1,2=321,3=90.000000
L 5.36103356 3.92341654 5.36103356 3.91958337 1 P 0 ;0,1,2=321,3=90.000000
L 5.36103356 3.91958337 5.36206663 3.91728317 1 P 0 ;0,1,2=321,3=90.000000
L 5.36206663 3.91728317 5.36464941 3.91536614 1 P 0 ;0,1,2=321,3=90.000000
L 5.36464941 3.91536614 5.36826624 3.9145997 1 P 0 ;0,1,2=321,3=90.000000
L 5.36826624 3.9145997 5.37188307 3.9157501 1 P 0 ;0,1,2=321,3=90.000000
L 5.37188307 3.9157501 5.37446683 3.91843287 1 P 0 ;0,1,2=321,3=90.000000
L 5.37446683 3.91843287 5.3755 3.92149961 1 P 0 ;0,1,2=321,3=90.000000
L 5.3755 3.92149961 5.37446683 3.92456634 1 P 0 ;0,1,2=321,3=90.000000
L 5.37446683 3.92456634 5.37188307 3.9272498 1 P 0 ;0,1,2=321,3=90.000000
L 5.37188307 3.9272498 5.36826624 3.9284002 1 P 0 ;0,1,2=321,3=90.000000
L 5.36826624 3.9284002 5.36464941 3.92763307 1 P 0 ;0,1,2=321,3=90.000000
L 5.36464941 3.92763307 5.36206663 3.92571673 1 P 0 ;0,1,2=321,3=90.000000
L 5.36206663 3.92571673 5.36103356 3.92341654 1 P 0 ;0,1,2=321,3=90.000000
L 5.36103356 3.92341654 5.36103356 3.91958337 1 P 0 ;0,1,2=321,3=90.000000
L 5.36103356 3.91958337 5.35948287 3.91613337 1 P 0 ;0,1,2=321,3=90.000000
L 5.35948287 3.91613337 5.35638268 3.91383317 1 P 0 ;0,1,2=321,3=90.000000
L 5.35638268 3.91383317 5.35276673 3.91306663 1 P 0 ;0,1,2=321,3=90.000000
L 5.35276673 3.91306663 5.34914892 3.91383317 1 P 0 ;0,1,2=321,3=90.000000
L 5.34914892 3.91383317 5.34656614 3.9157501 1 P 0 ;0,1,2=321,3=90.000000
L 5.34656614 3.9157501 5.34501654 3.91881683 1 P 0 ;0,1,2=321,3=90.000000
L 5.34501654 3.91881683 5.3445 3.92149961 1 P 0 ;0,1,2=321,3=90.000000
L 5.251 4.13501004 5.251 4.22501004 1 P 0 
L 5.251 4.22501004 5.295 4.22501004 1 P 0 
L 5.295 4.22501004 5.295 4.13501004 1 P 0 
L 5.295 4.13501004 5.251 4.13501004 1 P 0 
L 5.3045 3.82083317 5.3355 3.82083317 1 P 0 ;0,1,2=322,3=90.000000
L 5.3355 3.82083317 5.3355 3.83041654 1 P 0 ;0,1,2=322,3=90.000000
L 5.3355 3.83041654 5.33394931 3.83348327 1 P 0 ;0,1,2=322,3=90.000000
L 5.33394931 3.83348327 5.33188307 3.8354002 1 P 0 ;0,1,2=322,3=90.000000
L 5.33188307 3.8354002 5.3277497 3.83616673 1 P 0 ;0,1,2=322,3=90.000000
L 5.3277497 3.83616673 5.32361634 3.8354002 1 P 0 ;0,1,2=322,3=90.000000
L 5.32361634 3.8354002 5.32103356 3.8331 1 P 0 ;0,1,2=322,3=90.000000
L 5.32103356 3.8331 5.31948287 3.83041654 1 P 0 ;0,1,2=322,3=90.000000
L 5.31948287 3.83041654 5.31948287 3.82083317 1 P 0 ;0,1,2=322,3=90.000000
L 5.31948287 3.83041654 5.3045 3.83616673 1 P 0 ;0,1,2=322,3=90.000000
L 5.33033346 3.85221644 5.33343278 3.85451663 1 P 0 ;0,1,2=322,3=90.000000
L 5.33343278 3.85451663 5.33498337 3.8572001 1 P 0 ;0,1,2=322,3=90.000000
L 5.33498337 3.8572001 5.3355 3.86026683 1 P 0 ;0,1,2=322,3=90.000000
L 5.3355 3.86026683 5.33446683 3.8641 1 P 0 ;0,1,2=322,3=90.000000
L 5.33446683 3.8641 5.33188307 3.86678346 1 P 0 ;0,1,2=322,3=90.000000
L 5.33188307 3.86678346 5.32878376 3.86755 1 P 0 ;0,1,2=322,3=90.000000
L 5.32878376 3.86755 5.32568258 3.86716673 1 P 0 ;0,1,2=322,3=90.000000
L 5.32568258 3.86716673 5.3230998 3.86563307 1 P 0 ;0,1,2=322,3=90.000000
L 5.3230998 3.86563307 5.31793327 3.85796663 1 P 0 ;0,1,2=322,3=90.000000
L 5.31793327 3.85796663 5.31431644 3.85451663 1 P 0 ;0,1,2=322,3=90.000000
L 5.31431644 3.85451663 5.30914892 3.85221644 1 P 0 ;0,1,2=322,3=90.000000
L 5.30914892 3.85221644 5.3045 3.8514499 1 P 0 ;0,1,2=322,3=90.000000
L 5.3045 3.8514499 5.3045 3.86755 1 P 0 ;0,1,2=322,3=90.000000
L 5.3045 3.89049961 5.3355 3.89049961 1 P 0 ;0,1,2=322,3=90.000000
L 5.3355 3.89049961 5.3293003 3.8858999 1 P 0 ;0,1,2=322,3=90.000000
L 5.3045 3.8858999 5.3045 3.89509931 1 P 0 ;0,1,2=322,3=90.000000
L 5.3355 3.92149961 5.33446683 3.91843287 1 P 0 ;0,1,2=322,3=90.000000
L 5.33446683 3.91843287 5.33188307 3.91613337 1 P 0 ;0,1,2=322,3=90.000000
L 5.33188307 3.91613337 5.32878376 3.9145997 1 P 0 ;0,1,2=322,3=90.000000
L 5.32878376 3.9145997 5.32464941 3.9134499 1 P 0 ;0,1,2=322,3=90.000000
L 5.32464941 3.9134499 5.31999951 3.91306663 1 P 0 ;0,1,2=322,3=90.000000
L 5.31999951 3.91306663 5.31534951 3.9134499 1 P 0 ;0,1,2=322,3=90.000000
L 5.31534951 3.9134499 5.31121614 3.9145997 1 P 0 ;0,1,2=322,3=90.000000
L 5.31121614 3.9145997 5.30811585 3.91613337 1 P 0 ;0,1,2=322,3=90.000000
L 5.30811585 3.91613337 5.30553307 3.91843287 1 P 0 ;0,1,2=322,3=90.000000
L 5.30553307 3.91843287 5.3045 3.92149961 1 P 0 ;0,1,2=322,3=90.000000
L 5.3045 3.92149961 5.30553307 3.92456634 1 P 0 ;0,1,2=322,3=90.000000
L 5.30553307 3.92456634 5.30811585 3.92686654 1 P 0 ;0,1,2=322,3=90.000000
L 5.30811585 3.92686654 5.31121614 3.9284002 1 P 0 ;0,1,2=322,3=90.000000
L 5.31121614 3.9284002 5.31534951 3.92955 1 P 0 ;0,1,2=322,3=90.000000
L 5.31534951 3.92955 5.31999951 3.92993327 1 P 0 ;0,1,2=322,3=90.000000
L 5.31999951 3.92993327 5.32464941 3.92955 1 P 0 ;0,1,2=322,3=90.000000
L 5.32464941 3.92955 5.32878376 3.9284002 1 P 0 ;0,1,2=322,3=90.000000
L 5.32878376 3.9284002 5.33188307 3.92686654 1 P 0 ;0,1,2=322,3=90.000000
L 5.33188307 3.92686654 5.33446683 3.92456634 1 P 0 ;0,1,2=322,3=90.000000
L 5.33446683 3.92456634 5.3355 3.92149961 1 P 0 ;0,1,2=322,3=90.000000
L 5.413 4.285 5.457 4.285 1 P 0 
L 5.457 4.285 5.457 4.195 1 P 0 
L 5.457 4.195 5.413 4.195 1 P 0 
L 5.413 4.195 5.413 4.285 1 P 0 
L 5.47916683 3.9945 5.47916683 4.0255 1 P 0 ;0,1,2=323,3=0.000000
L 5.47916683 4.0255 5.46958346 4.0255 1 P 0 ;0,1,2=323,3=0.000000
L 5.46958346 4.0255 5.46651673 4.02394931 1 P 0 ;0,1,2=323,3=0.000000
L 5.46651673 4.02394931 5.4645998 4.02188307 1 P 0 ;0,1,2=323,3=0.000000
L 5.4645998 4.02188307 5.46383327 4.0177497 1 P 0 ;0,1,2=323,3=0.000000
L 5.46383327 4.0177497 5.4645998 4.01361634 1 P 0 ;0,1,2=323,3=0.000000
L 5.4645998 4.01361634 5.4669 4.01103356 1 P 0 ;0,1,2=323,3=0.000000
L 5.4669 4.01103356 5.46958346 4.00948287 1 P 0 ;0,1,2=323,3=0.000000
L 5.46958346 4.00948287 5.47916683 4.00948287 1 P 0 ;0,1,2=323,3=0.000000
L 5.46958346 4.00948287 5.46383327 3.9945 1 P 0 ;0,1,2=323,3=0.000000
L 5.44778356 4.02033346 5.44548337 4.02343278 1 P 0 ;0,1,2=323,3=0.000000
L 5.44548337 4.02343278 5.4427999 4.02498337 1 P 0 ;0,1,2=323,3=0.000000
L 5.4427999 4.02498337 5.43973317 4.0255 1 P 0 ;0,1,2=323,3=0.000000
L 5.43973317 4.0255 5.4359 4.02446683 1 P 0 ;0,1,2=323,3=0.000000
L 5.4359 4.02446683 5.43321654 4.02188307 1 P 0 ;0,1,2=323,3=0.000000
L 5.43321654 4.02188307 5.43245 4.01878376 1 P 0 ;0,1,2=323,3=0.000000
L 5.43245 4.01878376 5.43283327 4.01568258 1 P 0 ;0,1,2=323,3=0.000000
L 5.43283327 4.01568258 5.43436693 4.0130998 1 P 0 ;0,1,2=323,3=0.000000
L 5.43436693 4.0130998 5.44203337 4.00793327 1 P 0 ;0,1,2=323,3=0.000000
L 5.44203337 4.00793327 5.44548337 4.00431644 1 P 0 ;0,1,2=323,3=0.000000
L 5.44548337 4.00431644 5.44778356 3.99914892 1 P 0 ;0,1,2=323,3=0.000000
L 5.44778356 3.99914892 5.4485501 3.9945 1 P 0 ;0,1,2=323,3=0.000000
L 5.4485501 3.9945 5.43245 3.9945 1 P 0 ;0,1,2=323,3=0.000000
L 5.41793337 3.99914892 5.41563386 3.99656614 1 P 0 ;0,1,2=323,3=0.000000
L 5.41563386 3.99656614 5.41295039 3.99501654 1 P 0 ;0,1,2=323,3=0.000000
L 5.41295039 3.99501654 5.40950039 3.9945 1 P 0 ;0,1,2=323,3=0.000000
L 5.40950039 3.9945 5.4060497 3.99553307 1 P 0 ;0,1,2=323,3=0.000000
L 5.4060497 3.99553307 5.40336693 3.99759931 1 P 0 ;0,1,2=323,3=0.000000
L 5.40336693 3.99759931 5.40145 4.00121614 1 P 0 ;0,1,2=323,3=0.000000
L 5.40145 4.00121614 5.40106673 4.00534951 1 P 0 ;0,1,2=323,3=0.000000
L 5.40106673 4.00534951 5.40183327 4.00948287 1 P 0 ;0,1,2=323,3=0.000000
L 5.40183327 4.00948287 5.4037502 4.01206663 1 P 0 ;0,1,2=323,3=0.000000
L 5.4037502 4.01206663 5.40643366 4.01413287 1 P 0 ;0,1,2=323,3=0.000000
L 5.40643366 4.01413287 5.40911644 4.01464941 1 P 0 ;0,1,2=323,3=0.000000
L 5.40911644 4.01464941 5.4117999 4.01413287 1 P 0 ;0,1,2=323,3=0.000000
L 5.4117999 4.01413287 5.4152499 4.01206663 1 P 0 ;0,1,2=323,3=0.000000
L 5.4152499 4.01206663 5.4141001 4.0255 1 P 0 ;0,1,2=323,3=0.000000
L 5.4141001 4.0255 5.4037502 4.0255 1 P 0 ;0,1,2=323,3=0.000000
L 5.37926693 3.9945 5.37850039 4.00121614 1 P 0 ;0,1,2=323,3=0.000000
L 5.37850039 4.00121614 5.3773499 4.00689921 1 P 0 ;0,1,2=323,3=0.000000
L 5.3773499 4.00689921 5.37581693 4.01206663 1 P 0 ;0,1,2=323,3=0.000000
L 5.37581693 4.01206663 5.3739 4.0177497 1 P 0 ;0,1,2=323,3=0.000000
L 5.3739 4.0177497 5.37083327 4.0255 1 P 0 ;0,1,2=323,3=0.000000
L 5.37083327 4.0255 5.38616683 4.0255 1 P 0 ;0,1,2=323,3=0.000000
L 1.375 0.775 1.375 0.731 1 P 0 
L 1.285 0.775 1.375 0.775 1 P 0 
L 1.375 0.731 1.285 0.731 1 P 0 
L 1.285 0.731 1.285 0.775 1 P 0 
L 1.50916683 0.7145 1.50916683 0.7455 1 P 0 ;0,1,2=324,3=0.000000
L 1.50916683 0.7455 1.49958346 0.7455 1 P 0 ;0,1,2=324,3=0.000000
L 1.49958346 0.7455 1.49651673 0.74394931 1 P 0 ;0,1,2=324,3=0.000000
L 1.49651673 0.74394931 1.4945998 0.74188307 1 P 0 ;0,1,2=324,3=0.000000
L 1.4945998 0.74188307 1.49383327 0.7377497 1 P 0 ;0,1,2=324,3=0.000000
L 1.49383327 0.7377497 1.4945998 0.73361634 1 P 0 ;0,1,2=324,3=0.000000
L 1.4945998 0.73361634 1.4969 0.73103356 1 P 0 ;0,1,2=324,3=0.000000
L 1.4969 0.73103356 1.49958346 0.72948287 1 P 0 ;0,1,2=324,3=0.000000
L 1.49958346 0.72948287 1.50916683 0.72948287 1 P 0 ;0,1,2=324,3=0.000000
L 1.49958346 0.72948287 1.49383327 0.7145 1 P 0 ;0,1,2=324,3=0.000000
L 1.47050039 0.7145 1.47050039 0.7455 1 P 0 ;0,1,2=324,3=0.000000
L 1.47050039 0.7455 1.4751001 0.7393003 1 P 0 ;0,1,2=324,3=0.000000
L 1.4751001 0.7145 1.46590069 0.7145 1 P 0 ;0,1,2=324,3=0.000000
L 1.44793337 0.71914892 1.44563386 0.71656614 1 P 0 ;0,1,2=324,3=0.000000
L 1.44563386 0.71656614 1.44295039 0.71501654 1 P 0 ;0,1,2=324,3=0.000000
L 1.44295039 0.71501654 1.43950039 0.7145 1 P 0 ;0,1,2=324,3=0.000000
L 1.43950039 0.7145 1.4360497 0.71553307 1 P 0 ;0,1,2=324,3=0.000000
L 1.4360497 0.71553307 1.43336693 0.71759931 1 P 0 ;0,1,2=324,3=0.000000
L 1.43336693 0.71759931 1.43145 0.72121614 1 P 0 ;0,1,2=324,3=0.000000
L 1.43145 0.72121614 1.43106673 0.72534951 1 P 0 ;0,1,2=324,3=0.000000
L 1.43106673 0.72534951 1.43183327 0.72948287 1 P 0 ;0,1,2=324,3=0.000000
L 1.43183327 0.72948287 1.4337502 0.73206663 1 P 0 ;0,1,2=324,3=0.000000
L 1.4337502 0.73206663 1.43643366 0.73413287 1 P 0 ;0,1,2=324,3=0.000000
L 1.43643366 0.73413287 1.43911644 0.73464941 1 P 0 ;0,1,2=324,3=0.000000
L 1.43911644 0.73464941 1.4417999 0.73413287 1 P 0 ;0,1,2=324,3=0.000000
L 1.4417999 0.73413287 1.4452499 0.73206663 1 P 0 ;0,1,2=324,3=0.000000
L 1.4452499 0.73206663 1.4441001 0.7455 1 P 0 ;0,1,2=324,3=0.000000
L 1.4441001 0.7455 1.4337502 0.7455 1 P 0 ;0,1,2=324,3=0.000000
L 1.40850039 0.7145 1.40581693 0.71501654 1 P 0 ;0,1,2=324,3=0.000000
L 1.40581693 0.71501654 1.4027502 0.71656614 1 P 0 ;0,1,2=324,3=0.000000
L 1.4027502 0.71656614 1.40083327 0.71914892 1 P 0 ;0,1,2=324,3=0.000000
L 1.40083327 0.71914892 1.40006673 0.72276673 1 P 0 ;0,1,2=324,3=0.000000
L 1.40006673 0.72276673 1.40083327 0.72638268 1 P 0 ;0,1,2=324,3=0.000000
L 1.40083327 0.72638268 1.40313346 0.72948287 1 P 0 ;0,1,2=324,3=0.000000
L 1.40313346 0.72948287 1.40658346 0.73103356 1 P 0 ;0,1,2=324,3=0.000000
L 1.40658346 0.73103356 1.41041663 0.73103356 1 P 0 ;0,1,2=324,3=0.000000
L 1.41041663 0.73103356 1.41271683 0.73206663 1 P 0 ;0,1,2=324,3=0.000000
L 1.41271683 0.73206663 1.41463386 0.73464941 1 P 0 ;0,1,2=324,3=0.000000
L 1.41463386 0.73464941 1.4154003 0.73826624 1 P 0 ;0,1,2=324,3=0.000000
L 1.4154003 0.73826624 1.4142499 0.74188307 1 P 0 ;0,1,2=324,3=0.000000
L 1.4142499 0.74188307 1.41156713 0.74446683 1 P 0 ;0,1,2=324,3=0.000000
L 1.41156713 0.74446683 1.40850039 0.7455 1 P 0 ;0,1,2=324,3=0.000000
L 1.40850039 0.7455 1.40543366 0.74446683 1 P 0 ;0,1,2=324,3=0.000000
L 1.40543366 0.74446683 1.4027502 0.74188307 1 P 0 ;0,1,2=324,3=0.000000
L 1.4027502 0.74188307 1.4015998 0.73826624 1 P 0 ;0,1,2=324,3=0.000000
L 1.4015998 0.73826624 1.40236693 0.73464941 1 P 0 ;0,1,2=324,3=0.000000
L 1.40236693 0.73464941 1.40428327 0.73206663 1 P 0 ;0,1,2=324,3=0.000000
L 1.40428327 0.73206663 1.40658346 0.73103356 1 P 0 ;0,1,2=324,3=0.000000
L 1.40658346 0.73103356 1.41041663 0.73103356 1 P 0 ;0,1,2=324,3=0.000000
L 1.41041663 0.73103356 1.41386663 0.72948287 1 P 0 ;0,1,2=324,3=0.000000
L 1.41386663 0.72948287 1.41616683 0.72638268 1 P 0 ;0,1,2=324,3=0.000000
L 1.41616683 0.72638268 1.41693337 0.72276673 1 P 0 ;0,1,2=324,3=0.000000
L 1.41693337 0.72276673 1.41616683 0.71914892 1 P 0 ;0,1,2=324,3=0.000000
L 1.41616683 0.71914892 1.4142499 0.71656614 1 P 0 ;0,1,2=324,3=0.000000
L 1.4142499 0.71656614 1.41118317 0.71501654 1 P 0 ;0,1,2=324,3=0.000000
L 1.41118317 0.71501654 1.40850039 0.7145 1 P 0 ;0,1,2=324,3=0.000000
L 5.43 3.085 5.474 3.085 1 P 0 
L 5.474 3.085 5.474 2.995 1 P 0 
L 5.474 2.995 5.43 2.995 1 P 0 
L 5.43 2.995 5.43 3.085 1 P 0 
L 5.3945 3.05583317 5.4255 3.05583317 1 P 0 ;0,1,2=325,3=90.000000
L 5.4255 3.05583317 5.4255 3.06541654 1 P 0 ;0,1,2=325,3=90.000000
L 5.4255 3.06541654 5.42394931 3.06848327 1 P 0 ;0,1,2=325,3=90.000000
L 5.42394931 3.06848327 5.42188307 3.0704002 1 P 0 ;0,1,2=325,3=90.000000
L 5.42188307 3.0704002 5.4177497 3.07116673 1 P 0 ;0,1,2=325,3=90.000000
L 5.4177497 3.07116673 5.41361634 3.0704002 1 P 0 ;0,1,2=325,3=90.000000
L 5.41361634 3.0704002 5.41103356 3.0681 1 P 0 ;0,1,2=325,3=90.000000
L 5.41103356 3.0681 5.40948287 3.06541654 1 P 0 ;0,1,2=325,3=90.000000
L 5.40948287 3.06541654 5.40948287 3.05583317 1 P 0 ;0,1,2=325,3=90.000000
L 5.40948287 3.06541654 5.3945 3.07116673 1 P 0 ;0,1,2=325,3=90.000000
L 5.3945 3.0991 5.4255 3.0991 1 P 0 ;0,1,2=325,3=90.000000
L 5.4255 3.0991 5.40328327 3.08491624 1 P 0 ;0,1,2=325,3=90.000000
L 5.40328327 3.08491624 5.40328327 3.10408366 1 P 0 ;0,1,2=325,3=90.000000
L 5.4255 3.12549961 5.42446683 3.12243287 1 P 0 ;0,1,2=325,3=90.000000
L 5.42446683 3.12243287 5.42188307 3.12013337 1 P 0 ;0,1,2=325,3=90.000000
L 5.42188307 3.12013337 5.41878376 3.1185997 1 P 0 ;0,1,2=325,3=90.000000
L 5.41878376 3.1185997 5.41464941 3.1174499 1 P 0 ;0,1,2=325,3=90.000000
L 5.41464941 3.1174499 5.40999951 3.11706663 1 P 0 ;0,1,2=325,3=90.000000
L 5.40999951 3.11706663 5.40534951 3.1174499 1 P 0 ;0,1,2=325,3=90.000000
L 5.40534951 3.1174499 5.40121614 3.1185997 1 P 0 ;0,1,2=325,3=90.000000
L 5.40121614 3.1185997 5.39811585 3.12013337 1 P 0 ;0,1,2=325,3=90.000000
L 5.39811585 3.12013337 5.39553307 3.12243287 1 P 0 ;0,1,2=325,3=90.000000
L 5.39553307 3.12243287 5.3945 3.12549961 1 P 0 ;0,1,2=325,3=90.000000
L 5.3945 3.12549961 5.39553307 3.12856634 1 P 0 ;0,1,2=325,3=90.000000
L 5.39553307 3.12856634 5.39811585 3.13086654 1 P 0 ;0,1,2=325,3=90.000000
L 5.39811585 3.13086654 5.40121614 3.1324002 1 P 0 ;0,1,2=325,3=90.000000
L 5.40121614 3.1324002 5.40534951 3.13355 1 P 0 ;0,1,2=325,3=90.000000
L 5.40534951 3.13355 5.40999951 3.13393327 1 P 0 ;0,1,2=325,3=90.000000
L 5.40999951 3.13393327 5.41464941 3.13355 1 P 0 ;0,1,2=325,3=90.000000
L 5.41464941 3.13355 5.41878376 3.1324002 1 P 0 ;0,1,2=325,3=90.000000
L 5.41878376 3.1324002 5.42188307 3.13086654 1 P 0 ;0,1,2=325,3=90.000000
L 5.42188307 3.13086654 5.42446683 3.12856634 1 P 0 ;0,1,2=325,3=90.000000
L 5.42446683 3.12856634 5.4255 3.12549961 1 P 0 ;0,1,2=325,3=90.000000
L 5.39914892 3.14806663 5.39656614 3.15036614 1 P 0 ;0,1,2=325,3=90.000000
L 5.39656614 3.15036614 5.39501654 3.15304961 1 P 0 ;0,1,2=325,3=90.000000
L 5.39501654 3.15304961 5.3945 3.15649961 1 P 0 ;0,1,2=325,3=90.000000
L 5.3945 3.15649961 5.39553307 3.1599503 1 P 0 ;0,1,2=325,3=90.000000
L 5.39553307 3.1599503 5.39759931 3.16263307 1 P 0 ;0,1,2=325,3=90.000000
L 5.39759931 3.16263307 5.40121614 3.16455 1 P 0 ;0,1,2=325,3=90.000000
L 5.40121614 3.16455 5.40534951 3.16493327 1 P 0 ;0,1,2=325,3=90.000000
L 5.40534951 3.16493327 5.40948287 3.16416673 1 P 0 ;0,1,2=325,3=90.000000
L 5.40948287 3.16416673 5.41206663 3.1622498 1 P 0 ;0,1,2=325,3=90.000000
L 5.41206663 3.1622498 5.41413287 3.15956634 1 P 0 ;0,1,2=325,3=90.000000
L 5.41413287 3.15956634 5.41464941 3.15688356 1 P 0 ;0,1,2=325,3=90.000000
L 5.41464941 3.15688356 5.41413287 3.1542001 1 P 0 ;0,1,2=325,3=90.000000
L 5.41413287 3.1542001 5.41206663 3.1507501 1 P 0 ;0,1,2=325,3=90.000000
L 5.41206663 3.1507501 5.4255 3.1518999 1 P 0 ;0,1,2=325,3=90.000000
L 5.4255 3.1518999 5.4255 3.1622498 1 P 0 ;0,1,2=325,3=90.000000
L 5.474 2.9885 5.474 2.8985 1 P 0 
L 5.474 2.8985 5.43 2.8985 1 P 0 
L 5.43 2.8985 5.43 2.9885 1 P 0 
L 5.43 2.9885 5.474 2.9885 1 P 0 
L 5.36916683 2.9145 5.36916683 2.9455 1 P 0 ;0,1,2=326,3=0.000000
L 5.36916683 2.9455 5.35958346 2.9455 1 P 0 ;0,1,2=326,3=0.000000
L 5.35958346 2.9455 5.35651673 2.94394931 1 P 0 ;0,1,2=326,3=0.000000
L 5.35651673 2.94394931 5.3545998 2.94188307 1 P 0 ;0,1,2=326,3=0.000000
L 5.3545998 2.94188307 5.35383327 2.9377497 1 P 0 ;0,1,2=326,3=0.000000
L 5.35383327 2.9377497 5.3545998 2.93361634 1 P 0 ;0,1,2=326,3=0.000000
L 5.3545998 2.93361634 5.3569 2.93103356 1 P 0 ;0,1,2=326,3=0.000000
L 5.3569 2.93103356 5.35958346 2.92948287 1 P 0 ;0,1,2=326,3=0.000000
L 5.35958346 2.92948287 5.36916683 2.92948287 1 P 0 ;0,1,2=326,3=0.000000
L 5.35958346 2.92948287 5.35383327 2.9145 1 P 0 ;0,1,2=326,3=0.000000
L 5.3259 2.9145 5.3259 2.9455 1 P 0 ;0,1,2=326,3=0.000000
L 5.3259 2.9455 5.34008376 2.92328327 1 P 0 ;0,1,2=326,3=0.000000
L 5.34008376 2.92328327 5.32091634 2.92328327 1 P 0 ;0,1,2=326,3=0.000000
L 5.29950039 2.9455 5.30256713 2.94446683 1 P 0 ;0,1,2=326,3=0.000000
L 5.30256713 2.94446683 5.30486663 2.94188307 1 P 0 ;0,1,2=326,3=0.000000
L 5.30486663 2.94188307 5.3064003 2.93878376 1 P 0 ;0,1,2=326,3=0.000000
L 5.3064003 2.93878376 5.3075501 2.93464941 1 P 0 ;0,1,2=326,3=0.000000
L 5.3075501 2.93464941 5.30793337 2.92999951 1 P 0 ;0,1,2=326,3=0.000000
L 5.30793337 2.92999951 5.3075501 2.92534951 1 P 0 ;0,1,2=326,3=0.000000
L 5.3075501 2.92534951 5.3064003 2.92121614 1 P 0 ;0,1,2=326,3=0.000000
L 5.3064003 2.92121614 5.30486663 2.91811585 1 P 0 ;0,1,2=326,3=0.000000
L 5.30486663 2.91811585 5.30256713 2.91553307 1 P 0 ;0,1,2=326,3=0.000000
L 5.30256713 2.91553307 5.29950039 2.9145 1 P 0 ;0,1,2=326,3=0.000000
L 5.29950039 2.9145 5.29643366 2.91553307 1 P 0 ;0,1,2=326,3=0.000000
L 5.29643366 2.91553307 5.29413346 2.91811585 1 P 0 ;0,1,2=326,3=0.000000
L 5.29413346 2.91811585 5.2925998 2.92121614 1 P 0 ;0,1,2=326,3=0.000000
L 5.2925998 2.92121614 5.29145 2.92534951 1 P 0 ;0,1,2=326,3=0.000000
L 5.29145 2.92534951 5.29106673 2.92999951 1 P 0 ;0,1,2=326,3=0.000000
L 5.29106673 2.92999951 5.29145 2.93464941 1 P 0 ;0,1,2=326,3=0.000000
L 5.29145 2.93464941 5.2925998 2.93878376 1 P 0 ;0,1,2=326,3=0.000000
L 5.2925998 2.93878376 5.29413346 2.94188307 1 P 0 ;0,1,2=326,3=0.000000
L 5.29413346 2.94188307 5.29643366 2.94446683 1 P 0 ;0,1,2=326,3=0.000000
L 5.29643366 2.94446683 5.29950039 2.9455 1 P 0 ;0,1,2=326,3=0.000000
L 5.2639 2.9145 5.2639 2.9455 1 P 0 ;0,1,2=326,3=0.000000
L 5.2639 2.9455 5.27808376 2.92328327 1 P 0 ;0,1,2=326,3=0.000000
L 5.27808376 2.92328327 5.25891634 2.92328327 1 P 0 ;0,1,2=326,3=0.000000
L 6.005 4.285 6.049 4.285 1 P 0 
L 6.049 4.285 6.049 4.195 1 P 0 
L 6.049 4.195 6.005 4.195 1 P 0 
L 6.005 4.195 6.005 4.285 1 P 0 
L 5.9195 4.20583317 5.9505 4.20583317 1 P 0 ;0,1,2=327,3=90.000000
L 5.9505 4.20583317 5.9505 4.21541654 1 P 0 ;0,1,2=327,3=90.000000
L 5.9505 4.21541654 5.94894931 4.21848327 1 P 0 ;0,1,2=327,3=90.000000
L 5.94894931 4.21848327 5.94688307 4.2204002 1 P 0 ;0,1,2=327,3=90.000000
L 5.94688307 4.2204002 5.9427497 4.22116673 1 P 0 ;0,1,2=327,3=90.000000
L 5.9427497 4.22116673 5.93861634 4.2204002 1 P 0 ;0,1,2=327,3=90.000000
L 5.93861634 4.2204002 5.93603356 4.2181 1 P 0 ;0,1,2=327,3=90.000000
L 5.93603356 4.2181 5.93448287 4.21541654 1 P 0 ;0,1,2=327,3=90.000000
L 5.93448287 4.21541654 5.93448287 4.20583317 1 P 0 ;0,1,2=327,3=90.000000
L 5.93448287 4.21541654 5.9195 4.22116673 1 P 0 ;0,1,2=327,3=90.000000
L 5.94533346 4.23721644 5.94843278 4.23951663 1 P 0 ;0,1,2=327,3=90.000000
L 5.94843278 4.23951663 5.94998337 4.2422001 1 P 0 ;0,1,2=327,3=90.000000
L 5.94998337 4.2422001 5.9505 4.24526683 1 P 0 ;0,1,2=327,3=90.000000
L 5.9505 4.24526683 5.94946683 4.2491 1 P 0 ;0,1,2=327,3=90.000000
L 5.94946683 4.2491 5.94688307 4.25178346 1 P 0 ;0,1,2=327,3=90.000000
L 5.94688307 4.25178346 5.94378376 4.25255 1 P 0 ;0,1,2=327,3=90.000000
L 5.94378376 4.25255 5.94068258 4.25216673 1 P 0 ;0,1,2=327,3=90.000000
L 5.94068258 4.25216673 5.9380998 4.25063307 1 P 0 ;0,1,2=327,3=90.000000
L 5.9380998 4.25063307 5.93293327 4.24296663 1 P 0 ;0,1,2=327,3=90.000000
L 5.93293327 4.24296663 5.92931644 4.23951663 1 P 0 ;0,1,2=327,3=90.000000
L 5.92931644 4.23951663 5.92414892 4.23721644 1 P 0 ;0,1,2=327,3=90.000000
L 5.92414892 4.23721644 5.9195 4.2364499 1 P 0 ;0,1,2=327,3=90.000000
L 5.9195 4.2364499 5.9195 4.25255 1 P 0 ;0,1,2=327,3=90.000000
L 5.9195 4.27473307 5.92621614 4.27549961 1 P 0 ;0,1,2=327,3=90.000000
L 5.92621614 4.27549961 5.93189921 4.2766501 1 P 0 ;0,1,2=327,3=90.000000
L 5.93189921 4.2766501 5.93706663 4.27818307 1 P 0 ;0,1,2=327,3=90.000000
L 5.93706663 4.27818307 5.9427497 4.2801 1 P 0 ;0,1,2=327,3=90.000000
L 5.9427497 4.2801 5.9505 4.28316673 1 P 0 ;0,1,2=327,3=90.000000
L 5.9505 4.28316673 5.9505 4.26783317 1 P 0 ;0,1,2=327,3=90.000000
L 5.92311585 4.29998287 5.92053307 4.30266634 1 P 0 ;0,1,2=327,3=90.000000
L 5.92053307 4.30266634 5.9195 4.30573307 1 P 0 ;0,1,2=327,3=90.000000
L 5.9195 4.30573307 5.92053307 4.3087998 1 P 0 ;0,1,2=327,3=90.000000
L 5.92053307 4.3087998 5.92363238 4.31148327 1 P 0 ;0,1,2=327,3=90.000000
L 5.92363238 4.31148327 5.92828327 4.3134002 1 P 0 ;0,1,2=327,3=90.000000
L 5.92828327 4.3134002 5.93293327 4.31416673 1 P 0 ;0,1,2=327,3=90.000000
L 5.93293327 4.31416673 5.93861634 4.31416673 1 P 0 ;0,1,2=327,3=90.000000
L 5.93861634 4.31416673 5.94326624 4.3134002 1 P 0 ;0,1,2=327,3=90.000000
L 5.94326624 4.3134002 5.9473997 4.31148327 1 P 0 ;0,1,2=327,3=90.000000
L 5.9473997 4.31148327 5.94946683 4.30918307 1 P 0 ;0,1,2=327,3=90.000000
L 5.94946683 4.30918307 5.9505 4.30649961 1 P 0 ;0,1,2=327,3=90.000000
L 5.9505 4.30649961 5.94946683 4.30343287 1 P 0 ;0,1,2=327,3=90.000000
L 5.94946683 4.30343287 5.9473997 4.30113337 1 P 0 ;0,1,2=327,3=90.000000
L 5.9473997 4.30113337 5.9443003 4.2995997 1 P 0 ;0,1,2=327,3=90.000000
L 5.9443003 4.2995997 5.94016594 4.29883317 1 P 0 ;0,1,2=327,3=90.000000
L 5.94016594 4.29883317 5.9365501 4.2995997 1 P 0 ;0,1,2=327,3=90.000000
L 5.9365501 4.2995997 5.93293327 4.30151663 1 P 0 ;0,1,2=327,3=90.000000
L 5.93293327 4.30151663 5.93086604 4.30381683 1 P 0 ;0,1,2=327,3=90.000000
L 5.93086604 4.30381683 5.93034951 4.30649961 1 P 0 ;0,1,2=327,3=90.000000
L 5.93034951 4.30649961 5.93138268 4.30956634 1 P 0 ;0,1,2=327,3=90.000000
L 5.93138268 4.30956634 5.93396634 4.31186654 1 P 0 ;0,1,2=327,3=90.000000
L 5.93396634 4.31186654 5.93861634 4.31416673 1 P 0 ;0,1,2=327,3=90.000000
L 6.118 4.285 6.162 4.285 1 P 0 
L 6.162 4.285 6.162 4.195 1 P 0 
L 6.162 4.195 6.118 4.195 1 P 0 
L 6.118 4.195 6.118 4.285 1 P 0 
L 6.1745 4.20083317 6.2055 4.20083317 1 P 0 ;0,1,2=328,3=90.000000
L 6.2055 4.20083317 6.2055 4.21041654 1 P 0 ;0,1,2=328,3=90.000000
L 6.2055 4.21041654 6.20394931 4.21348327 1 P 0 ;0,1,2=328,3=90.000000
L 6.20394931 4.21348327 6.20188307 4.2154002 1 P 0 ;0,1,2=328,3=90.000000
L 6.20188307 4.2154002 6.1977497 4.21616673 1 P 0 ;0,1,2=328,3=90.000000
L 6.1977497 4.21616673 6.19361634 4.2154002 1 P 0 ;0,1,2=328,3=90.000000
L 6.19361634 4.2154002 6.19103356 4.2131 1 P 0 ;0,1,2=328,3=90.000000
L 6.19103356 4.2131 6.18948287 4.21041654 1 P 0 ;0,1,2=328,3=90.000000
L 6.18948287 4.21041654 6.18948287 4.20083317 1 P 0 ;0,1,2=328,3=90.000000
L 6.18948287 4.21041654 6.1745 4.21616673 1 P 0 ;0,1,2=328,3=90.000000
L 6.20033346 4.23221644 6.20343278 4.23451663 1 P 0 ;0,1,2=328,3=90.000000
L 6.20343278 4.23451663 6.20498337 4.2372001 1 P 0 ;0,1,2=328,3=90.000000
L 6.20498337 4.2372001 6.2055 4.24026683 1 P 0 ;0,1,2=328,3=90.000000
L 6.2055 4.24026683 6.20446683 4.2441 1 P 0 ;0,1,2=328,3=90.000000
L 6.20446683 4.2441 6.20188307 4.24678346 1 P 0 ;0,1,2=328,3=90.000000
L 6.20188307 4.24678346 6.19878376 4.24755 1 P 0 ;0,1,2=328,3=90.000000
L 6.19878376 4.24755 6.19568258 4.24716673 1 P 0 ;0,1,2=328,3=90.000000
L 6.19568258 4.24716673 6.1930998 4.24563307 1 P 0 ;0,1,2=328,3=90.000000
L 6.1930998 4.24563307 6.18793327 4.23796663 1 P 0 ;0,1,2=328,3=90.000000
L 6.18793327 4.23796663 6.18431644 4.23451663 1 P 0 ;0,1,2=328,3=90.000000
L 6.18431644 4.23451663 6.17914892 4.23221644 1 P 0 ;0,1,2=328,3=90.000000
L 6.17914892 4.23221644 6.1745 4.2314499 1 P 0 ;0,1,2=328,3=90.000000
L 6.1745 4.2314499 6.1745 4.24755 1 P 0 ;0,1,2=328,3=90.000000
L 6.1745 4.27049961 6.17501654 4.27318307 1 P 0 ;0,1,2=328,3=90.000000
L 6.17501654 4.27318307 6.17656614 4.2762498 1 P 0 ;0,1,2=328,3=90.000000
L 6.17656614 4.2762498 6.17914892 4.27816673 1 P 0 ;0,1,2=328,3=90.000000
L 6.17914892 4.27816673 6.18276673 4.27893327 1 P 0 ;0,1,2=328,3=90.000000
L 6.18276673 4.27893327 6.18638268 4.27816673 1 P 0 ;0,1,2=328,3=90.000000
L 6.18638268 4.27816673 6.18948287 4.27586654 1 P 0 ;0,1,2=328,3=90.000000
L 6.18948287 4.27586654 6.19103356 4.27241654 1 P 0 ;0,1,2=328,3=90.000000
L 6.19103356 4.27241654 6.19103356 4.26858337 1 P 0 ;0,1,2=328,3=90.000000
L 6.19103356 4.26858337 6.19206663 4.26628317 1 P 0 ;0,1,2=328,3=90.000000
L 6.19206663 4.26628317 6.19464941 4.26436614 1 P 0 ;0,1,2=328,3=90.000000
L 6.19464941 4.26436614 6.19826624 4.2635997 1 P 0 ;0,1,2=328,3=90.000000
L 6.19826624 4.2635997 6.20188307 4.2647501 1 P 0 ;0,1,2=328,3=90.000000
L 6.20188307 4.2647501 6.20446683 4.26743287 1 P 0 ;0,1,2=328,3=90.000000
L 6.20446683 4.26743287 6.2055 4.27049961 1 P 0 ;0,1,2=328,3=90.000000
L 6.2055 4.27049961 6.20446683 4.27356634 1 P 0 ;0,1,2=328,3=90.000000
L 6.20446683 4.27356634 6.20188307 4.2762498 1 P 0 ;0,1,2=328,3=90.000000
L 6.20188307 4.2762498 6.19826624 4.2774002 1 P 0 ;0,1,2=328,3=90.000000
L 6.19826624 4.2774002 6.19464941 4.27663307 1 P 0 ;0,1,2=328,3=90.000000
L 6.19464941 4.27663307 6.19206663 4.27471673 1 P 0 ;0,1,2=328,3=90.000000
L 6.19206663 4.27471673 6.19103356 4.27241654 1 P 0 ;0,1,2=328,3=90.000000
L 6.19103356 4.27241654 6.19103356 4.26858337 1 P 0 ;0,1,2=328,3=90.000000
L 6.19103356 4.26858337 6.18948287 4.26513337 1 P 0 ;0,1,2=328,3=90.000000
L 6.18948287 4.26513337 6.18638268 4.26283317 1 P 0 ;0,1,2=328,3=90.000000
L 6.18638268 4.26283317 6.18276673 4.26206663 1 P 0 ;0,1,2=328,3=90.000000
L 6.18276673 4.26206663 6.17914892 4.26283317 1 P 0 ;0,1,2=328,3=90.000000
L 6.17914892 4.26283317 6.17656614 4.2647501 1 P 0 ;0,1,2=328,3=90.000000
L 6.17656614 4.2647501 6.17501654 4.26781683 1 P 0 ;0,1,2=328,3=90.000000
L 6.17501654 4.26781683 6.1745 4.27049961 1 P 0 ;0,1,2=328,3=90.000000
L 6.2055 4.30149961 6.20446683 4.29843287 1 P 0 ;0,1,2=328,3=90.000000
L 6.20446683 4.29843287 6.20188307 4.29613337 1 P 0 ;0,1,2=328,3=90.000000
L 6.20188307 4.29613337 6.19878376 4.2945997 1 P 0 ;0,1,2=328,3=90.000000
L 6.19878376 4.2945997 6.19464941 4.2934499 1 P 0 ;0,1,2=328,3=90.000000
L 6.19464941 4.2934499 6.18999951 4.29306663 1 P 0 ;0,1,2=328,3=90.000000
L 6.18999951 4.29306663 6.18534951 4.2934499 1 P 0 ;0,1,2=328,3=90.000000
L 6.18534951 4.2934499 6.18121614 4.2945997 1 P 0 ;0,1,2=328,3=90.000000
L 6.18121614 4.2945997 6.17811585 4.29613337 1 P 0 ;0,1,2=328,3=90.000000
L 6.17811585 4.29613337 6.17553307 4.29843287 1 P 0 ;0,1,2=328,3=90.000000
L 6.17553307 4.29843287 6.1745 4.30149961 1 P 0 ;0,1,2=328,3=90.000000
L 6.1745 4.30149961 6.17553307 4.30456634 1 P 0 ;0,1,2=328,3=90.000000
L 6.17553307 4.30456634 6.17811585 4.30686654 1 P 0 ;0,1,2=328,3=90.000000
L 6.17811585 4.30686654 6.18121614 4.3084002 1 P 0 ;0,1,2=328,3=90.000000
L 6.18121614 4.3084002 6.18534951 4.30955 1 P 0 ;0,1,2=328,3=90.000000
L 6.18534951 4.30955 6.18999951 4.30993327 1 P 0 ;0,1,2=328,3=90.000000
L 6.18999951 4.30993327 6.19464941 4.30955 1 P 0 ;0,1,2=328,3=90.000000
L 6.19464941 4.30955 6.19878376 4.3084002 1 P 0 ;0,1,2=328,3=90.000000
L 6.19878376 4.3084002 6.20188307 4.30686654 1 P 0 ;0,1,2=328,3=90.000000
L 6.20188307 4.30686654 6.20446683 4.30456634 1 P 0 ;0,1,2=328,3=90.000000
L 6.20446683 4.30456634 6.2055 4.30149961 1 P 0 ;0,1,2=328,3=90.000000
L 5.653 4.15 5.697 4.15 1 P 0 
L 5.697 4.15 5.697 4.06 1 P 0 
L 5.697 4.06 5.653 4.06 1 P 0 
L 5.653 4.06 5.653 4.15 1 P 0 
L 5.7025 4.02166654 5.7275 4.02166654 1 P 0 ;0,1,2=329,3=90.000000
L 5.7275 4.02166654 5.7275 4.02833327 1 P 0 ;0,1,2=329,3=90.000000
L 5.7275 4.02833327 5.72624941 4.03046663 1 P 0 ;0,1,2=329,3=90.000000
L 5.72624941 4.03046663 5.72458317 4.0318001 1 P 0 ;0,1,2=329,3=90.000000
L 5.72458317 4.0318001 5.7212498 4.03233337 1 P 0 ;0,1,2=329,3=90.000000
L 5.7212498 4.03233337 5.71791634 4.0318001 1 P 0 ;0,1,2=329,3=90.000000
L 5.71791634 4.0318001 5.71583346 4.0302 1 P 0 ;0,1,2=329,3=90.000000
L 5.71583346 4.0302 5.71458297 4.02833327 1 P 0 ;0,1,2=329,3=90.000000
L 5.71458297 4.02833327 5.71458297 4.02166654 1 P 0 ;0,1,2=329,3=90.000000
L 5.71458297 4.02833327 5.7025 4.03233337 1 P 0 ;0,1,2=329,3=90.000000
L 5.7025 4.0489997 5.7275 4.0489997 1 P 0 ;0,1,2=329,3=90.000000
L 5.7275 4.0489997 5.7225003 4.0457999 1 P 0 ;0,1,2=329,3=90.000000
L 5.7025 4.0457999 5.7025 4.05219951 1 P 0 ;0,1,2=329,3=90.000000
L 5.7025 4.0709997 5.70291654 4.07286644 1 P 0 ;0,1,2=329,3=90.000000
L 5.70291654 4.07286644 5.70416624 4.0749998 1 P 0 ;0,1,2=329,3=90.000000
L 5.70416624 4.0749998 5.70624911 4.07633337 1 P 0 ;0,1,2=329,3=90.000000
L 5.70624911 4.07633337 5.70916673 4.07686663 1 P 0 ;0,1,2=329,3=90.000000
L 5.70916673 4.07686663 5.71208278 4.07633337 1 P 0 ;0,1,2=329,3=90.000000
L 5.71208278 4.07633337 5.71458297 4.07473327 1 P 0 ;0,1,2=329,3=90.000000
L 5.71458297 4.07473327 5.71583346 4.07233327 1 P 0 ;0,1,2=329,3=90.000000
L 5.71583346 4.07233327 5.71583346 4.06966663 1 P 0 ;0,1,2=329,3=90.000000
L 5.71583346 4.06966663 5.71666663 4.06806654 1 P 0 ;0,1,2=329,3=90.000000
L 5.71666663 4.06806654 5.71874951 4.06673297 1 P 0 ;0,1,2=329,3=90.000000
L 5.71874951 4.06673297 5.72166634 4.0661998 1 P 0 ;0,1,2=329,3=90.000000
L 5.72166634 4.0661998 5.72458317 4.0670001 1 P 0 ;0,1,2=329,3=90.000000
L 5.72458317 4.0670001 5.72666683 4.06886634 1 P 0 ;0,1,2=329,3=90.000000
L 5.72666683 4.06886634 5.7275 4.0709997 1 P 0 ;0,1,2=329,3=90.000000
L 5.7275 4.0709997 5.72666683 4.07313307 1 P 0 ;0,1,2=329,3=90.000000
L 5.72666683 4.07313307 5.72458317 4.0749998 1 P 0 ;0,1,2=329,3=90.000000
L 5.72458317 4.0749998 5.72166634 4.0758001 1 P 0 ;0,1,2=329,3=90.000000
L 5.72166634 4.0758001 5.71874951 4.07526644 1 P 0 ;0,1,2=329,3=90.000000
L 5.71874951 4.07526644 5.71666663 4.07393337 1 P 0 ;0,1,2=329,3=90.000000
L 5.71666663 4.07393337 5.71583346 4.07233327 1 P 0 ;0,1,2=329,3=90.000000
L 5.71583346 4.07233327 5.71583346 4.06966663 1 P 0 ;0,1,2=329,3=90.000000
L 5.71583346 4.06966663 5.71458297 4.06726663 1 P 0 ;0,1,2=329,3=90.000000
L 5.71458297 4.06726663 5.71208278 4.06566654 1 P 0 ;0,1,2=329,3=90.000000
L 5.71208278 4.06566654 5.70916673 4.06513327 1 P 0 ;0,1,2=329,3=90.000000
L 5.70916673 4.06513327 5.70624911 4.06566654 1 P 0 ;0,1,2=329,3=90.000000
L 5.70624911 4.06566654 5.70416624 4.0670001 1 P 0 ;0,1,2=329,3=90.000000
L 5.70416624 4.0670001 5.70291654 4.06913346 1 P 0 ;0,1,2=329,3=90.000000
L 5.70291654 4.06913346 5.7025 4.0709997 1 P 0 ;0,1,2=329,3=90.000000
L 5.7275 4.0929997 5.72666683 4.09086634 1 P 0 ;0,1,2=329,3=90.000000
L 5.72666683 4.09086634 5.72458317 4.08926663 1 P 0 ;0,1,2=329,3=90.000000
L 5.72458317 4.08926663 5.72208366 4.0881998 1 P 0 ;0,1,2=329,3=90.000000
L 5.72208366 4.0881998 5.71874951 4.0873999 1 P 0 ;0,1,2=329,3=90.000000
L 5.71874951 4.0873999 5.71499961 4.08713327 1 P 0 ;0,1,2=329,3=90.000000
L 5.71499961 4.08713327 5.71124961 4.0873999 1 P 0 ;0,1,2=329,3=90.000000
L 5.71124961 4.0873999 5.70791624 4.0881998 1 P 0 ;0,1,2=329,3=90.000000
L 5.70791624 4.0881998 5.70541604 4.08926663 1 P 0 ;0,1,2=329,3=90.000000
L 5.70541604 4.08926663 5.70333307 4.09086634 1 P 0 ;0,1,2=329,3=90.000000
L 5.70333307 4.09086634 5.7025 4.0929997 1 P 0 ;0,1,2=329,3=90.000000
L 5.7025 4.0929997 5.70333307 4.09513307 1 P 0 ;0,1,2=329,3=90.000000
L 5.70333307 4.09513307 5.70541604 4.09673327 1 P 0 ;0,1,2=329,3=90.000000
L 5.70541604 4.09673327 5.70791624 4.0978001 1 P 0 ;0,1,2=329,3=90.000000
L 5.70791624 4.0978001 5.71124961 4.0986 1 P 0 ;0,1,2=329,3=90.000000
L 5.71124961 4.0986 5.71499961 4.09886663 1 P 0 ;0,1,2=329,3=90.000000
L 5.71499961 4.09886663 5.71874951 4.0986 1 P 0 ;0,1,2=329,3=90.000000
L 5.71874951 4.0986 5.72208366 4.0978001 1 P 0 ;0,1,2=329,3=90.000000
L 5.72208366 4.0978001 5.72458317 4.09673327 1 P 0 ;0,1,2=329,3=90.000000
L 5.72458317 4.09673327 5.72666683 4.09513307 1 P 0 ;0,1,2=329,3=90.000000
L 5.72666683 4.09513307 5.7275 4.0929997 1 P 0 ;0,1,2=329,3=90.000000
L 5.835 4.097 5.835 4.053 1 P 0 
L 5.745 4.097 5.835 4.097 1 P 0 
L 5.835 4.053 5.745 4.053 1 P 0 
L 5.745 4.053 5.745 4.097 1 P 0 
L 5.88416683 3.9395 5.88416683 3.9705 1 P 0 ;0,1,2=330,3=0.000000
L 5.88416683 3.9705 5.87458346 3.9705 1 P 0 ;0,1,2=330,3=0.000000
L 5.87458346 3.9705 5.87151673 3.96894931 1 P 0 ;0,1,2=330,3=0.000000
L 5.87151673 3.96894931 5.8695998 3.96688307 1 P 0 ;0,1,2=330,3=0.000000
L 5.8695998 3.96688307 5.86883327 3.9627497 1 P 0 ;0,1,2=330,3=0.000000
L 5.86883327 3.9627497 5.8695998 3.95861634 1 P 0 ;0,1,2=330,3=0.000000
L 5.8695998 3.95861634 5.8719 3.95603356 1 P 0 ;0,1,2=330,3=0.000000
L 5.8719 3.95603356 5.87458346 3.95448287 1 P 0 ;0,1,2=330,3=0.000000
L 5.87458346 3.95448287 5.88416683 3.95448287 1 P 0 ;0,1,2=330,3=0.000000
L 5.87458346 3.95448287 5.86883327 3.9395 1 P 0 ;0,1,2=330,3=0.000000
L 5.85278356 3.96533346 5.85048337 3.96843278 1 P 0 ;0,1,2=330,3=0.000000
L 5.85048337 3.96843278 5.8477999 3.96998337 1 P 0 ;0,1,2=330,3=0.000000
L 5.8477999 3.96998337 5.84473317 3.9705 1 P 0 ;0,1,2=330,3=0.000000
L 5.84473317 3.9705 5.8409 3.96946683 1 P 0 ;0,1,2=330,3=0.000000
L 5.8409 3.96946683 5.83821654 3.96688307 1 P 0 ;0,1,2=330,3=0.000000
L 5.83821654 3.96688307 5.83745 3.96378376 1 P 0 ;0,1,2=330,3=0.000000
L 5.83745 3.96378376 5.83783327 3.96068258 1 P 0 ;0,1,2=330,3=0.000000
L 5.83783327 3.96068258 5.83936693 3.9580998 1 P 0 ;0,1,2=330,3=0.000000
L 5.83936693 3.9580998 5.84703337 3.95293327 1 P 0 ;0,1,2=330,3=0.000000
L 5.84703337 3.95293327 5.85048337 3.94931644 1 P 0 ;0,1,2=330,3=0.000000
L 5.85048337 3.94931644 5.85278356 3.94414892 1 P 0 ;0,1,2=330,3=0.000000
L 5.85278356 3.94414892 5.8535501 3.9395 1 P 0 ;0,1,2=330,3=0.000000
L 5.8535501 3.9395 5.83745 3.9395 1 P 0 ;0,1,2=330,3=0.000000
L 5.82178356 3.95241575 5.8191001 3.95603356 1 P 0 ;0,1,2=330,3=0.000000
L 5.8191001 3.95603356 5.8167999 3.9580998 1 P 0 ;0,1,2=330,3=0.000000
L 5.8167999 3.9580998 5.81373317 3.95913287 1 P 0 ;0,1,2=330,3=0.000000
L 5.81373317 3.95913287 5.8110497 3.9580998 1 P 0 ;0,1,2=330,3=0.000000
L 5.8110497 3.9580998 5.80913346 3.95603356 1 P 0 ;0,1,2=330,3=0.000000
L 5.80913346 3.95603356 5.8075998 3.95293327 1 P 0 ;0,1,2=330,3=0.000000
L 5.8075998 3.95293327 5.80721654 3.94931644 1 P 0 ;0,1,2=330,3=0.000000
L 5.80721654 3.94931644 5.8075998 3.94621614 1 P 0 ;0,1,2=330,3=0.000000
L 5.8075998 3.94621614 5.80913346 3.94311585 1 P 0 ;0,1,2=330,3=0.000000
L 5.80913346 3.94311585 5.81143366 3.94053307 1 P 0 ;0,1,2=330,3=0.000000
L 5.81143366 3.94053307 5.81411644 3.9395 1 P 0 ;0,1,2=330,3=0.000000
L 5.81411644 3.9395 5.81718317 3.94053307 1 P 0 ;0,1,2=330,3=0.000000
L 5.81718317 3.94053307 5.81986663 3.94363238 1 P 0 ;0,1,2=330,3=0.000000
L 5.81986663 3.94363238 5.8214003 3.94828327 1 P 0 ;0,1,2=330,3=0.000000
L 5.8214003 3.94828327 5.82178356 3.9534498 1 P 0 ;0,1,2=330,3=0.000000
L 5.82178356 3.9534498 5.82101713 3.96016594 1 P 0 ;0,1,2=330,3=0.000000
L 5.82101713 3.96016594 5.81986663 3.96378376 1 P 0 ;0,1,2=330,3=0.000000
L 5.81986663 3.96378376 5.81795039 3.9673997 1 P 0 ;0,1,2=330,3=0.000000
L 5.81795039 3.9673997 5.81526693 3.96998337 1 P 0 ;0,1,2=330,3=0.000000
L 5.81526693 3.96998337 5.81258346 3.9705 1 P 0 ;0,1,2=330,3=0.000000
L 5.81258346 3.9705 5.8099 3.96946683 1 P 0 ;0,1,2=330,3=0.000000
L 5.8099 3.96946683 5.80798297 3.96688307 1 P 0 ;0,1,2=330,3=0.000000
L 5.79078356 3.96533346 5.78848337 3.96843278 1 P 0 ;0,1,2=330,3=0.000000
L 5.78848337 3.96843278 5.7857999 3.96998337 1 P 0 ;0,1,2=330,3=0.000000
L 5.7857999 3.96998337 5.78273317 3.9705 1 P 0 ;0,1,2=330,3=0.000000
L 5.78273317 3.9705 5.7789 3.96946683 1 P 0 ;0,1,2=330,3=0.000000
L 5.7789 3.96946683 5.77621654 3.96688307 1 P 0 ;0,1,2=330,3=0.000000
L 5.77621654 3.96688307 5.77545 3.96378376 1 P 0 ;0,1,2=330,3=0.000000
L 5.77545 3.96378376 5.77583327 3.96068258 1 P 0 ;0,1,2=330,3=0.000000
L 5.77583327 3.96068258 5.77736693 3.9580998 1 P 0 ;0,1,2=330,3=0.000000
L 5.77736693 3.9580998 5.78503337 3.95293327 1 P 0 ;0,1,2=330,3=0.000000
L 5.78503337 3.95293327 5.78848337 3.94931644 1 P 0 ;0,1,2=330,3=0.000000
L 5.78848337 3.94931644 5.79078356 3.94414892 1 P 0 ;0,1,2=330,3=0.000000
L 5.79078356 3.94414892 5.7915501 3.9395 1 P 0 ;0,1,2=330,3=0.000000
L 5.7915501 3.9395 5.77545 3.9395 1 P 0 ;0,1,2=330,3=0.000000
L 5.835 4.142 5.835 4.098 1 P 0 
L 5.745 4.142 5.835 4.142 1 P 0 
L 5.835 4.098 5.745 4.098 1 P 0 
L 5.745 4.098 5.745 4.142 1 P 0 
L 5.88416683 3.9795 5.88416683 4.0105 1 P 0 ;0,1,2=331,3=0.000000
L 5.88416683 4.0105 5.87458346 4.0105 1 P 0 ;0,1,2=331,3=0.000000
L 5.87458346 4.0105 5.87151673 4.00894931 1 P 0 ;0,1,2=331,3=0.000000
L 5.87151673 4.00894931 5.8695998 4.00688307 1 P 0 ;0,1,2=331,3=0.000000
L 5.8695998 4.00688307 5.86883327 4.0027497 1 P 0 ;0,1,2=331,3=0.000000
L 5.86883327 4.0027497 5.8695998 3.99861634 1 P 0 ;0,1,2=331,3=0.000000
L 5.8695998 3.99861634 5.8719 3.99603356 1 P 0 ;0,1,2=331,3=0.000000
L 5.8719 3.99603356 5.87458346 3.99448287 1 P 0 ;0,1,2=331,3=0.000000
L 5.87458346 3.99448287 5.88416683 3.99448287 1 P 0 ;0,1,2=331,3=0.000000
L 5.87458346 3.99448287 5.86883327 3.9795 1 P 0 ;0,1,2=331,3=0.000000
L 5.85278356 4.00533346 5.85048337 4.00843278 1 P 0 ;0,1,2=331,3=0.000000
L 5.85048337 4.00843278 5.8477999 4.00998337 1 P 0 ;0,1,2=331,3=0.000000
L 5.8477999 4.00998337 5.84473317 4.0105 1 P 0 ;0,1,2=331,3=0.000000
L 5.84473317 4.0105 5.8409 4.00946683 1 P 0 ;0,1,2=331,3=0.000000
L 5.8409 4.00946683 5.83821654 4.00688307 1 P 0 ;0,1,2=331,3=0.000000
L 5.83821654 4.00688307 5.83745 4.00378376 1 P 0 ;0,1,2=331,3=0.000000
L 5.83745 4.00378376 5.83783327 4.00068258 1 P 0 ;0,1,2=331,3=0.000000
L 5.83783327 4.00068258 5.83936693 3.9980998 1 P 0 ;0,1,2=331,3=0.000000
L 5.83936693 3.9980998 5.84703337 3.99293327 1 P 0 ;0,1,2=331,3=0.000000
L 5.84703337 3.99293327 5.85048337 3.98931644 1 P 0 ;0,1,2=331,3=0.000000
L 5.85048337 3.98931644 5.85278356 3.98414892 1 P 0 ;0,1,2=331,3=0.000000
L 5.85278356 3.98414892 5.8535501 3.9795 1 P 0 ;0,1,2=331,3=0.000000
L 5.8535501 3.9795 5.83745 3.9795 1 P 0 ;0,1,2=331,3=0.000000
L 5.82293337 3.98414892 5.82063386 3.98156614 1 P 0 ;0,1,2=331,3=0.000000
L 5.82063386 3.98156614 5.81795039 3.98001654 1 P 0 ;0,1,2=331,3=0.000000
L 5.81795039 3.98001654 5.81450039 3.9795 1 P 0 ;0,1,2=331,3=0.000000
L 5.81450039 3.9795 5.8110497 3.98053307 1 P 0 ;0,1,2=331,3=0.000000
L 5.8110497 3.98053307 5.80836693 3.98259931 1 P 0 ;0,1,2=331,3=0.000000
L 5.80836693 3.98259931 5.80645 3.98621614 1 P 0 ;0,1,2=331,3=0.000000
L 5.80645 3.98621614 5.80606673 3.99034951 1 P 0 ;0,1,2=331,3=0.000000
L 5.80606673 3.99034951 5.80683327 3.99448287 1 P 0 ;0,1,2=331,3=0.000000
L 5.80683327 3.99448287 5.8087502 3.99706663 1 P 0 ;0,1,2=331,3=0.000000
L 5.8087502 3.99706663 5.81143366 3.99913287 1 P 0 ;0,1,2=331,3=0.000000
L 5.81143366 3.99913287 5.81411644 3.99964941 1 P 0 ;0,1,2=331,3=0.000000
L 5.81411644 3.99964941 5.8167999 3.99913287 1 P 0 ;0,1,2=331,3=0.000000
L 5.8167999 3.99913287 5.8202499 3.99706663 1 P 0 ;0,1,2=331,3=0.000000
L 5.8202499 3.99706663 5.8191001 4.0105 1 P 0 ;0,1,2=331,3=0.000000
L 5.8191001 4.0105 5.8087502 4.0105 1 P 0 ;0,1,2=331,3=0.000000
L 5.79078356 3.99241575 5.7881001 3.99603356 1 P 0 ;0,1,2=331,3=0.000000
L 5.7881001 3.99603356 5.7857999 3.9980998 1 P 0 ;0,1,2=331,3=0.000000
L 5.7857999 3.9980998 5.78273317 3.99913287 1 P 0 ;0,1,2=331,3=0.000000
L 5.78273317 3.99913287 5.7800497 3.9980998 1 P 0 ;0,1,2=331,3=0.000000
L 5.7800497 3.9980998 5.77813346 3.99603356 1 P 0 ;0,1,2=331,3=0.000000
L 5.77813346 3.99603356 5.7765998 3.99293327 1 P 0 ;0,1,2=331,3=0.000000
L 5.7765998 3.99293327 5.77621654 3.98931644 1 P 0 ;0,1,2=331,3=0.000000
L 5.77621654 3.98931644 5.7765998 3.98621614 1 P 0 ;0,1,2=331,3=0.000000
L 5.7765998 3.98621614 5.77813346 3.98311585 1 P 0 ;0,1,2=331,3=0.000000
L 5.77813346 3.98311585 5.78043366 3.98053307 1 P 0 ;0,1,2=331,3=0.000000
L 5.78043366 3.98053307 5.78311644 3.9795 1 P 0 ;0,1,2=331,3=0.000000
L 5.78311644 3.9795 5.78618317 3.98053307 1 P 0 ;0,1,2=331,3=0.000000
L 5.78618317 3.98053307 5.78886663 3.98363238 1 P 0 ;0,1,2=331,3=0.000000
L 5.78886663 3.98363238 5.7904003 3.98828327 1 P 0 ;0,1,2=331,3=0.000000
L 5.7904003 3.98828327 5.79078356 3.9934498 1 P 0 ;0,1,2=331,3=0.000000
L 5.79078356 3.9934498 5.79001713 4.00016594 1 P 0 ;0,1,2=331,3=0.000000
L 5.79001713 4.00016594 5.78886663 4.00378376 1 P 0 ;0,1,2=331,3=0.000000
L 5.78886663 4.00378376 5.78695039 4.0073997 1 P 0 ;0,1,2=331,3=0.000000
L 5.78695039 4.0073997 5.78426693 4.00998337 1 P 0 ;0,1,2=331,3=0.000000
L 5.78426693 4.00998337 5.78158346 4.0105 1 P 0 ;0,1,2=331,3=0.000000
L 5.78158346 4.0105 5.7789 4.00946683 1 P 0 ;0,1,2=331,3=0.000000
L 5.7789 4.00946683 5.77698297 4.00688307 1 P 0 ;0,1,2=331,3=0.000000
L 5.595 4.137 5.595 4.093 1 P 0 
L 5.505 4.137 5.595 4.137 1 P 0 
L 5.595 4.093 5.505 4.093 1 P 0 
L 5.505 4.093 5.505 4.137 1 P 0 
L 5.56916683 3.9495 5.56916683 3.9805 1 P 0 ;0,1,2=332,3=0.000000
L 5.56916683 3.9805 5.55958346 3.9805 1 P 0 ;0,1,2=332,3=0.000000
L 5.55958346 3.9805 5.55651673 3.97894931 1 P 0 ;0,1,2=332,3=0.000000
L 5.55651673 3.97894931 5.5545998 3.97688307 1 P 0 ;0,1,2=332,3=0.000000
L 5.5545998 3.97688307 5.55383327 3.9727497 1 P 0 ;0,1,2=332,3=0.000000
L 5.55383327 3.9727497 5.5545998 3.96861634 1 P 0 ;0,1,2=332,3=0.000000
L 5.5545998 3.96861634 5.5569 3.96603356 1 P 0 ;0,1,2=332,3=0.000000
L 5.5569 3.96603356 5.55958346 3.96448287 1 P 0 ;0,1,2=332,3=0.000000
L 5.55958346 3.96448287 5.56916683 3.96448287 1 P 0 ;0,1,2=332,3=0.000000
L 5.55958346 3.96448287 5.55383327 3.9495 1 P 0 ;0,1,2=332,3=0.000000
L 5.53050039 3.9495 5.53050039 3.9805 1 P 0 ;0,1,2=332,3=0.000000
L 5.53050039 3.9805 5.5351001 3.9743003 1 P 0 ;0,1,2=332,3=0.000000
L 5.5351001 3.9495 5.52590069 3.9495 1 P 0 ;0,1,2=332,3=0.000000
L 5.49950039 3.9805 5.50256713 3.97946683 1 P 0 ;0,1,2=332,3=0.000000
L 5.50256713 3.97946683 5.50486663 3.97688307 1 P 0 ;0,1,2=332,3=0.000000
L 5.50486663 3.97688307 5.5064003 3.97378376 1 P 0 ;0,1,2=332,3=0.000000
L 5.5064003 3.97378376 5.5075501 3.96964941 1 P 0 ;0,1,2=332,3=0.000000
L 5.5075501 3.96964941 5.50793337 3.96499951 1 P 0 ;0,1,2=332,3=0.000000
L 5.50793337 3.96499951 5.5075501 3.96034951 1 P 0 ;0,1,2=332,3=0.000000
L 5.5075501 3.96034951 5.5064003 3.95621614 1 P 0 ;0,1,2=332,3=0.000000
L 5.5064003 3.95621614 5.50486663 3.95311585 1 P 0 ;0,1,2=332,3=0.000000
L 5.50486663 3.95311585 5.50256713 3.95053307 1 P 0 ;0,1,2=332,3=0.000000
L 5.50256713 3.95053307 5.49950039 3.9495 1 P 0 ;0,1,2=332,3=0.000000
L 5.49950039 3.9495 5.49643366 3.95053307 1 P 0 ;0,1,2=332,3=0.000000
L 5.49643366 3.95053307 5.49413346 3.95311585 1 P 0 ;0,1,2=332,3=0.000000
L 5.49413346 3.95311585 5.4925998 3.95621614 1 P 0 ;0,1,2=332,3=0.000000
L 5.4925998 3.95621614 5.49145 3.96034951 1 P 0 ;0,1,2=332,3=0.000000
L 5.49145 3.96034951 5.49106673 3.96499951 1 P 0 ;0,1,2=332,3=0.000000
L 5.49106673 3.96499951 5.49145 3.96964941 1 P 0 ;0,1,2=332,3=0.000000
L 5.49145 3.96964941 5.4925998 3.97378376 1 P 0 ;0,1,2=332,3=0.000000
L 5.4925998 3.97378376 5.49413346 3.97688307 1 P 0 ;0,1,2=332,3=0.000000
L 5.49413346 3.97688307 5.49643366 3.97946683 1 P 0 ;0,1,2=332,3=0.000000
L 5.49643366 3.97946683 5.49950039 3.9805 1 P 0 ;0,1,2=332,3=0.000000
L 5.46850039 3.9495 5.46581693 3.95001654 1 P 0 ;0,1,2=332,3=0.000000
L 5.46581693 3.95001654 5.4627502 3.95156614 1 P 0 ;0,1,2=332,3=0.000000
L 5.4627502 3.95156614 5.46083327 3.95414892 1 P 0 ;0,1,2=332,3=0.000000
L 5.46083327 3.95414892 5.46006673 3.95776673 1 P 0 ;0,1,2=332,3=0.000000
L 5.46006673 3.95776673 5.46083327 3.96138268 1 P 0 ;0,1,2=332,3=0.000000
L 5.46083327 3.96138268 5.46313346 3.96448287 1 P 0 ;0,1,2=332,3=0.000000
L 5.46313346 3.96448287 5.46658346 3.96603356 1 P 0 ;0,1,2=332,3=0.000000
L 5.46658346 3.96603356 5.47041663 3.96603356 1 P 0 ;0,1,2=332,3=0.000000
L 5.47041663 3.96603356 5.47271683 3.96706663 1 P 0 ;0,1,2=332,3=0.000000
L 5.47271683 3.96706663 5.47463386 3.96964941 1 P 0 ;0,1,2=332,3=0.000000
L 5.47463386 3.96964941 5.4754003 3.97326624 1 P 0 ;0,1,2=332,3=0.000000
L 5.4754003 3.97326624 5.4742499 3.97688307 1 P 0 ;0,1,2=332,3=0.000000
L 5.4742499 3.97688307 5.47156713 3.97946683 1 P 0 ;0,1,2=332,3=0.000000
L 5.47156713 3.97946683 5.46850039 3.9805 1 P 0 ;0,1,2=332,3=0.000000
L 5.46850039 3.9805 5.46543366 3.97946683 1 P 0 ;0,1,2=332,3=0.000000
L 5.46543366 3.97946683 5.4627502 3.97688307 1 P 0 ;0,1,2=332,3=0.000000
L 5.4627502 3.97688307 5.4615998 3.97326624 1 P 0 ;0,1,2=332,3=0.000000
L 5.4615998 3.97326624 5.46236693 3.96964941 1 P 0 ;0,1,2=332,3=0.000000
L 5.46236693 3.96964941 5.46428327 3.96706663 1 P 0 ;0,1,2=332,3=0.000000
L 5.46428327 3.96706663 5.46658346 3.96603356 1 P 0 ;0,1,2=332,3=0.000000
L 5.46658346 3.96603356 5.47041663 3.96603356 1 P 0 ;0,1,2=332,3=0.000000
L 5.47041663 3.96603356 5.47386663 3.96448287 1 P 0 ;0,1,2=332,3=0.000000
L 5.47386663 3.96448287 5.47616683 3.96138268 1 P 0 ;0,1,2=332,3=0.000000
L 5.47616683 3.96138268 5.47693337 3.95776673 1 P 0 ;0,1,2=332,3=0.000000
L 5.47693337 3.95776673 5.47616683 3.95414892 1 P 0 ;0,1,2=332,3=0.000000
L 5.47616683 3.95414892 5.4742499 3.95156614 1 P 0 ;0,1,2=332,3=0.000000
L 5.4742499 3.95156614 5.47118317 3.95001654 1 P 0 ;0,1,2=332,3=0.000000
L 5.47118317 3.95001654 5.46850039 3.9495 1 P 0 ;0,1,2=332,3=0.000000
L 5.595 4.092 5.595 4.048 1 P 0 
L 5.505 4.092 5.595 4.092 1 P 0 
L 5.595 4.048 5.505 4.048 1 P 0 
L 5.505 4.048 5.505 4.092 1 P 0 
L 5.56916683 3.9095 5.56916683 3.9405 1 P 0 ;0,1,2=333,3=0.000000
L 5.56916683 3.9405 5.55958346 3.9405 1 P 0 ;0,1,2=333,3=0.000000
L 5.55958346 3.9405 5.55651673 3.93894931 1 P 0 ;0,1,2=333,3=0.000000
L 5.55651673 3.93894931 5.5545998 3.93688307 1 P 0 ;0,1,2=333,3=0.000000
L 5.5545998 3.93688307 5.55383327 3.9327497 1 P 0 ;0,1,2=333,3=0.000000
L 5.55383327 3.9327497 5.5545998 3.92861634 1 P 0 ;0,1,2=333,3=0.000000
L 5.5545998 3.92861634 5.5569 3.92603356 1 P 0 ;0,1,2=333,3=0.000000
L 5.5569 3.92603356 5.55958346 3.92448287 1 P 0 ;0,1,2=333,3=0.000000
L 5.55958346 3.92448287 5.56916683 3.92448287 1 P 0 ;0,1,2=333,3=0.000000
L 5.55958346 3.92448287 5.55383327 3.9095 1 P 0 ;0,1,2=333,3=0.000000
L 5.53050039 3.9095 5.53050039 3.9405 1 P 0 ;0,1,2=333,3=0.000000
L 5.53050039 3.9405 5.5351001 3.9343003 1 P 0 ;0,1,2=333,3=0.000000
L 5.5351001 3.9095 5.52590069 3.9095 1 P 0 ;0,1,2=333,3=0.000000
L 5.50793337 3.91569961 5.50563386 3.91208278 1 P 0 ;0,1,2=333,3=0.000000
L 5.50563386 3.91208278 5.50256713 3.91001654 1 P 0 ;0,1,2=333,3=0.000000
L 5.50256713 3.91001654 5.49911644 3.9095 1 P 0 ;0,1,2=333,3=0.000000
L 5.49911644 3.9095 5.4960497 3.91001654 1 P 0 ;0,1,2=333,3=0.000000
L 5.4960497 3.91001654 5.49298297 3.91259931 1 P 0 ;0,1,2=333,3=0.000000
L 5.49298297 3.91259931 5.49106673 3.91569961 1 P 0 ;0,1,2=333,3=0.000000
L 5.49106673 3.91569961 5.49068346 3.9187999 1 P 0 ;0,1,2=333,3=0.000000
L 5.49068346 3.9187999 5.49145 3.92241575 1 P 0 ;0,1,2=333,3=0.000000
L 5.49145 3.92241575 5.49413346 3.92499951 1 P 0 ;0,1,2=333,3=0.000000
L 5.49413346 3.92499951 5.49681693 3.92603356 1 P 0 ;0,1,2=333,3=0.000000
L 5.49681693 3.92603356 5.50026693 3.92603356 1 P 0 ;0,1,2=333,3=0.000000
L 5.49681693 3.92603356 5.49451673 3.92758317 1 P 0 ;0,1,2=333,3=0.000000
L 5.49451673 3.92758317 5.4925998 3.93016594 1 P 0 ;0,1,2=333,3=0.000000
L 5.4925998 3.93016594 5.49183327 3.93326624 1 P 0 ;0,1,2=333,3=0.000000
L 5.49183327 3.93326624 5.4925998 3.93636654 1 P 0 ;0,1,2=333,3=0.000000
L 5.4925998 3.93636654 5.49451673 3.93894931 1 P 0 ;0,1,2=333,3=0.000000
L 5.49451673 3.93894931 5.49796673 3.9405 1 P 0 ;0,1,2=333,3=0.000000
L 5.49796673 3.9405 5.50141663 3.93998337 1 P 0 ;0,1,2=333,3=0.000000
L 5.50141663 3.93998337 5.50486663 3.93791624 1 P 0 ;0,1,2=333,3=0.000000
L 5.47501713 3.91311585 5.47233366 3.91053307 1 P 0 ;0,1,2=333,3=0.000000
L 5.47233366 3.91053307 5.46926693 3.9095 1 P 0 ;0,1,2=333,3=0.000000
L 5.46926693 3.9095 5.4662002 3.91053307 1 P 0 ;0,1,2=333,3=0.000000
L 5.4662002 3.91053307 5.46351673 3.91363238 1 P 0 ;0,1,2=333,3=0.000000
L 5.46351673 3.91363238 5.4615998 3.91828327 1 P 0 ;0,1,2=333,3=0.000000
L 5.4615998 3.91828327 5.46083327 3.92293327 1 P 0 ;0,1,2=333,3=0.000000
L 5.46083327 3.92293327 5.46083327 3.92861634 1 P 0 ;0,1,2=333,3=0.000000
L 5.46083327 3.92861634 5.4615998 3.93326624 1 P 0 ;0,1,2=333,3=0.000000
L 5.4615998 3.93326624 5.46351673 3.9373997 1 P 0 ;0,1,2=333,3=0.000000
L 5.46351673 3.9373997 5.46581693 3.93946683 1 P 0 ;0,1,2=333,3=0.000000
L 5.46581693 3.93946683 5.46850039 3.9405 1 P 0 ;0,1,2=333,3=0.000000
L 5.46850039 3.9405 5.47156713 3.93946683 1 P 0 ;0,1,2=333,3=0.000000
L 5.47156713 3.93946683 5.47386663 3.9373997 1 P 0 ;0,1,2=333,3=0.000000
L 5.47386663 3.9373997 5.4754003 3.9343003 1 P 0 ;0,1,2=333,3=0.000000
L 5.4754003 3.9343003 5.47616683 3.93016594 1 P 0 ;0,1,2=333,3=0.000000
L 5.47616683 3.93016594 5.4754003 3.9265501 1 P 0 ;0,1,2=333,3=0.000000
L 5.4754003 3.9265501 5.47348337 3.92293327 1 P 0 ;0,1,2=333,3=0.000000
L 5.47348337 3.92293327 5.47118317 3.92086604 1 P 0 ;0,1,2=333,3=0.000000
L 5.47118317 3.92086604 5.46850039 3.92034951 1 P 0 ;0,1,2=333,3=0.000000
L 5.46850039 3.92034951 5.46543366 3.92138268 1 P 0 ;0,1,2=333,3=0.000000
L 5.46543366 3.92138268 5.46313346 3.92396634 1 P 0 ;0,1,2=333,3=0.000000
L 5.46313346 3.92396634 5.46083327 3.92861634 1 P 0 ;0,1,2=333,3=0.000000
L 0.766 0.977 0.81 0.977 1 P 0 
L 0.766 0.887 0.766 0.977 1 P 0 
L 0.81 0.977 0.81 0.887 1 P 0 
L 0.81 0.887 0.766 0.887 1 P 0 
L 0.7845 1.03083317 0.8155 1.03083317 1 P 0 ;0,1,2=334,3=90.000000
L 0.8155 1.03083317 0.8155 1.04041654 1 P 0 ;0,1,2=334,3=90.000000
L 0.8155 1.04041654 0.81394931 1.04348327 1 P 0 ;0,1,2=334,3=90.000000
L 0.81394931 1.04348327 0.81188307 1.0454002 1 P 0 ;0,1,2=334,3=90.000000
L 0.81188307 1.0454002 0.8077497 1.04616673 1 P 0 ;0,1,2=334,3=90.000000
L 0.8077497 1.04616673 0.80361634 1.0454002 1 P 0 ;0,1,2=334,3=90.000000
L 0.80361634 1.0454002 0.80103356 1.0431 1 P 0 ;0,1,2=334,3=90.000000
L 0.80103356 1.0431 0.79948287 1.04041654 1 P 0 ;0,1,2=334,3=90.000000
L 0.79948287 1.04041654 0.79948287 1.03083317 1 P 0 ;0,1,2=334,3=90.000000
L 0.79948287 1.04041654 0.7845 1.04616673 1 P 0 ;0,1,2=334,3=90.000000
L 0.7845 1.06949961 0.8155 1.06949961 1 P 0 ;0,1,2=334,3=90.000000
L 0.8155 1.06949961 0.8093003 1.0648999 1 P 0 ;0,1,2=334,3=90.000000
L 0.7845 1.0648999 0.7845 1.07409931 1 P 0 ;0,1,2=334,3=90.000000
L 0.79741575 1.09321644 0.80103356 1.0958999 1 P 0 ;0,1,2=334,3=90.000000
L 0.80103356 1.0958999 0.8030998 1.0982001 1 P 0 ;0,1,2=334,3=90.000000
L 0.8030998 1.0982001 0.80413287 1.10126683 1 P 0 ;0,1,2=334,3=90.000000
L 0.80413287 1.10126683 0.8030998 1.1039503 1 P 0 ;0,1,2=334,3=90.000000
L 0.8030998 1.1039503 0.80103356 1.10586654 1 P 0 ;0,1,2=334,3=90.000000
L 0.80103356 1.10586654 0.79793327 1.1074002 1 P 0 ;0,1,2=334,3=90.000000
L 0.79793327 1.1074002 0.79431644 1.10778346 1 P 0 ;0,1,2=334,3=90.000000
L 0.79431644 1.10778346 0.79121614 1.1074002 1 P 0 ;0,1,2=334,3=90.000000
L 0.79121614 1.1074002 0.78811585 1.10586654 1 P 0 ;0,1,2=334,3=90.000000
L 0.78811585 1.10586654 0.78553307 1.10356634 1 P 0 ;0,1,2=334,3=90.000000
L 0.78553307 1.10356634 0.7845 1.10088356 1 P 0 ;0,1,2=334,3=90.000000
L 0.7845 1.10088356 0.78553307 1.09781683 1 P 0 ;0,1,2=334,3=90.000000
L 0.78553307 1.09781683 0.78863238 1.09513337 1 P 0 ;0,1,2=334,3=90.000000
L 0.78863238 1.09513337 0.79328327 1.0935997 1 P 0 ;0,1,2=334,3=90.000000
L 0.79328327 1.0935997 0.7984498 1.09321644 1 P 0 ;0,1,2=334,3=90.000000
L 0.7984498 1.09321644 0.80516594 1.09398287 1 P 0 ;0,1,2=334,3=90.000000
L 0.80516594 1.09398287 0.80878376 1.09513337 1 P 0 ;0,1,2=334,3=90.000000
L 0.80878376 1.09513337 0.8123997 1.09704961 1 P 0 ;0,1,2=334,3=90.000000
L 0.8123997 1.09704961 0.81498337 1.09973307 1 P 0 ;0,1,2=334,3=90.000000
L 0.81498337 1.09973307 0.8155 1.10241654 1 P 0 ;0,1,2=334,3=90.000000
L 0.8155 1.10241654 0.81446683 1.1051 1 P 0 ;0,1,2=334,3=90.000000
L 0.81446683 1.1051 0.81188307 1.10701703 1 P 0 ;0,1,2=334,3=90.000000
L 0.8155 1.13149961 0.81446683 1.12843287 1 P 0 ;0,1,2=334,3=90.000000
L 0.81446683 1.12843287 0.81188307 1.12613337 1 P 0 ;0,1,2=334,3=90.000000
L 0.81188307 1.12613337 0.80878376 1.1245997 1 P 0 ;0,1,2=334,3=90.000000
L 0.80878376 1.1245997 0.80464941 1.1234499 1 P 0 ;0,1,2=334,3=90.000000
L 0.80464941 1.1234499 0.79999951 1.12306663 1 P 0 ;0,1,2=334,3=90.000000
L 0.79999951 1.12306663 0.79534951 1.1234499 1 P 0 ;0,1,2=334,3=90.000000
L 0.79534951 1.1234499 0.79121614 1.1245997 1 P 0 ;0,1,2=334,3=90.000000
L 0.79121614 1.1245997 0.78811585 1.12613337 1 P 0 ;0,1,2=334,3=90.000000
L 0.78811585 1.12613337 0.78553307 1.12843287 1 P 0 ;0,1,2=334,3=90.000000
L 0.78553307 1.12843287 0.7845 1.13149961 1 P 0 ;0,1,2=334,3=90.000000
L 0.7845 1.13149961 0.78553307 1.13456634 1 P 0 ;0,1,2=334,3=90.000000
L 0.78553307 1.13456634 0.78811585 1.13686654 1 P 0 ;0,1,2=334,3=90.000000
L 0.78811585 1.13686654 0.79121614 1.1384002 1 P 0 ;0,1,2=334,3=90.000000
L 0.79121614 1.1384002 0.79534951 1.13955 1 P 0 ;0,1,2=334,3=90.000000
L 0.79534951 1.13955 0.79999951 1.13993327 1 P 0 ;0,1,2=334,3=90.000000
L 0.79999951 1.13993327 0.80464941 1.13955 1 P 0 ;0,1,2=334,3=90.000000
L 0.80464941 1.13955 0.80878376 1.1384002 1 P 0 ;0,1,2=334,3=90.000000
L 0.80878376 1.1384002 0.81188307 1.13686654 1 P 0 ;0,1,2=334,3=90.000000
L 0.81188307 1.13686654 0.81446683 1.13456634 1 P 0 ;0,1,2=334,3=90.000000
L 0.81446683 1.13456634 0.8155 1.13149961 1 P 0 ;0,1,2=334,3=90.000000
L 5.533 4.285 5.577 4.285 1 P 0 
L 5.577 4.285 5.577 4.195 1 P 0 
L 5.577 4.195 5.533 4.195 1 P 0 
L 5.533 4.195 5.533 4.285 1 P 0 
L 5.5845 4.17166654 5.6095 4.17166654 1 P 0 ;0,1,2=335,3=90.000000
L 5.6095 4.17166654 5.6095 4.17833327 1 P 0 ;0,1,2=335,3=90.000000
L 5.6095 4.17833327 5.60824941 4.18046663 1 P 0 ;0,1,2=335,3=90.000000
L 5.60824941 4.18046663 5.60658317 4.1818001 1 P 0 ;0,1,2=335,3=90.000000
L 5.60658317 4.1818001 5.6032498 4.18233337 1 P 0 ;0,1,2=335,3=90.000000
L 5.6032498 4.18233337 5.59991634 4.1818001 1 P 0 ;0,1,2=335,3=90.000000
L 5.59991634 4.1818001 5.59783346 4.1802 1 P 0 ;0,1,2=335,3=90.000000
L 5.59783346 4.1802 5.59658297 4.17833327 1 P 0 ;0,1,2=335,3=90.000000
L 5.59658297 4.17833327 5.59658297 4.17166654 1 P 0 ;0,1,2=335,3=90.000000
L 5.59658297 4.17833327 5.5845 4.18233337 1 P 0 ;0,1,2=335,3=90.000000
L 5.60533337 4.19393317 5.60783287 4.19553327 1 P 0 ;0,1,2=335,3=90.000000
L 5.60783287 4.19553327 5.60908337 4.1974 1 P 0 ;0,1,2=335,3=90.000000
L 5.60908337 4.1974 5.6095 4.19953337 1 P 0 ;0,1,2=335,3=90.000000
L 5.6095 4.19953337 5.60866683 4.2022 1 P 0 ;0,1,2=335,3=90.000000
L 5.60866683 4.2022 5.60658317 4.20406673 1 P 0 ;0,1,2=335,3=90.000000
L 5.60658317 4.20406673 5.60408366 4.2046 1 P 0 ;0,1,2=335,3=90.000000
L 5.60408366 4.2046 5.60158268 4.20433337 1 P 0 ;0,1,2=335,3=90.000000
L 5.60158268 4.20433337 5.5994998 4.20326644 1 P 0 ;0,1,2=335,3=90.000000
L 5.5994998 4.20326644 5.59533327 4.19793327 1 P 0 ;0,1,2=335,3=90.000000
L 5.59533327 4.19793327 5.59241644 4.19553327 1 P 0 ;0,1,2=335,3=90.000000
L 5.59241644 4.19553327 5.58824911 4.19393317 1 P 0 ;0,1,2=335,3=90.000000
L 5.58824911 4.19393317 5.5845 4.1933999 1 P 0 ;0,1,2=335,3=90.000000
L 5.5845 4.1933999 5.5845 4.2046 1 P 0 ;0,1,2=335,3=90.000000
L 5.58824911 4.21513327 5.58616624 4.21673297 1 P 0 ;0,1,2=335,3=90.000000
L 5.58616624 4.21673297 5.58491654 4.2185997 1 P 0 ;0,1,2=335,3=90.000000
L 5.58491654 4.2185997 5.5845 4.2209997 1 P 0 ;0,1,2=335,3=90.000000
L 5.5845 4.2209997 5.58533307 4.2234002 1 P 0 ;0,1,2=335,3=90.000000
L 5.58533307 4.2234002 5.58699941 4.22526644 1 P 0 ;0,1,2=335,3=90.000000
L 5.58699941 4.22526644 5.58991624 4.2266 1 P 0 ;0,1,2=335,3=90.000000
L 5.58991624 4.2266 5.59324961 4.22686663 1 P 0 ;0,1,2=335,3=90.000000
L 5.59324961 4.22686663 5.59658297 4.22633337 1 P 0 ;0,1,2=335,3=90.000000
L 5.59658297 4.22633337 5.59866663 4.2249998 1 P 0 ;0,1,2=335,3=90.000000
L 5.59866663 4.2249998 5.60033297 4.22313307 1 P 0 ;0,1,2=335,3=90.000000
L 5.60033297 4.22313307 5.60074951 4.22126683 1 P 0 ;0,1,2=335,3=90.000000
L 5.60074951 4.22126683 5.60033297 4.2194 1 P 0 ;0,1,2=335,3=90.000000
L 5.60033297 4.2194 5.59866663 4.2170001 1 P 0 ;0,1,2=335,3=90.000000
L 5.59866663 4.2170001 5.6095 4.2177999 1 P 0 ;0,1,2=335,3=90.000000
L 5.6095 4.2177999 5.6095 4.2249998 1 P 0 ;0,1,2=335,3=90.000000
L 5.5845 4.2429997 5.58491654 4.24486644 1 P 0 ;0,1,2=335,3=90.000000
L 5.58491654 4.24486644 5.58616624 4.2469998 1 P 0 ;0,1,2=335,3=90.000000
L 5.58616624 4.2469998 5.58824911 4.24833337 1 P 0 ;0,1,2=335,3=90.000000
L 5.58824911 4.24833337 5.59116673 4.24886663 1 P 0 ;0,1,2=335,3=90.000000
L 5.59116673 4.24886663 5.59408278 4.24833337 1 P 0 ;0,1,2=335,3=90.000000
L 5.59408278 4.24833337 5.59658297 4.24673327 1 P 0 ;0,1,2=335,3=90.000000
L 5.59658297 4.24673327 5.59783346 4.24433327 1 P 0 ;0,1,2=335,3=90.000000
L 5.59783346 4.24433327 5.59783346 4.24166663 1 P 0 ;0,1,2=335,3=90.000000
L 5.59783346 4.24166663 5.59866663 4.24006654 1 P 0 ;0,1,2=335,3=90.000000
L 5.59866663 4.24006654 5.60074951 4.23873297 1 P 0 ;0,1,2=335,3=90.000000
L 5.60074951 4.23873297 5.60366634 4.2381998 1 P 0 ;0,1,2=335,3=90.000000
L 5.60366634 4.2381998 5.60658317 4.2390001 1 P 0 ;0,1,2=335,3=90.000000
L 5.60658317 4.2390001 5.60866683 4.24086634 1 P 0 ;0,1,2=335,3=90.000000
L 5.60866683 4.24086634 5.6095 4.2429997 1 P 0 ;0,1,2=335,3=90.000000
L 5.6095 4.2429997 5.60866683 4.24513307 1 P 0 ;0,1,2=335,3=90.000000
L 5.60866683 4.24513307 5.60658317 4.2469998 1 P 0 ;0,1,2=335,3=90.000000
L 5.60658317 4.2469998 5.60366634 4.2478001 1 P 0 ;0,1,2=335,3=90.000000
L 5.60366634 4.2478001 5.60074951 4.24726644 1 P 0 ;0,1,2=335,3=90.000000
L 5.60074951 4.24726644 5.59866663 4.24593337 1 P 0 ;0,1,2=335,3=90.000000
L 5.59866663 4.24593337 5.59783346 4.24433327 1 P 0 ;0,1,2=335,3=90.000000
L 5.59783346 4.24433327 5.59783346 4.24166663 1 P 0 ;0,1,2=335,3=90.000000
L 5.59783346 4.24166663 5.59658297 4.23926663 1 P 0 ;0,1,2=335,3=90.000000
L 5.59658297 4.23926663 5.59408278 4.23766654 1 P 0 ;0,1,2=335,3=90.000000
L 5.59408278 4.23766654 5.59116673 4.23713327 1 P 0 ;0,1,2=335,3=90.000000
L 5.59116673 4.23713327 5.58824911 4.23766654 1 P 0 ;0,1,2=335,3=90.000000
L 5.58824911 4.23766654 5.58616624 4.2390001 1 P 0 ;0,1,2=335,3=90.000000
L 5.58616624 4.2390001 5.58491654 4.24113346 1 P 0 ;0,1,2=335,3=90.000000
L 5.58491654 4.24113346 5.5845 4.2429997 1 P 0 ;0,1,2=335,3=90.000000
L 5.648 4.285 5.692 4.285 1 P 0 
L 5.692 4.285 5.692 4.195 1 P 0 
L 5.692 4.195 5.648 4.195 1 P 0 
L 5.648 4.195 5.648 4.285 1 P 0 
L 5.7045 4.17166654 5.7295 4.17166654 1 P 0 ;0,1,2=336,3=90.000000
L 5.7295 4.17166654 5.7295 4.17833327 1 P 0 ;0,1,2=336,3=90.000000
L 5.7295 4.17833327 5.72824941 4.18046663 1 P 0 ;0,1,2=336,3=90.000000
L 5.72824941 4.18046663 5.72658317 4.1818001 1 P 0 ;0,1,2=336,3=90.000000
L 5.72658317 4.1818001 5.7232498 4.18233337 1 P 0 ;0,1,2=336,3=90.000000
L 5.7232498 4.18233337 5.71991634 4.1818001 1 P 0 ;0,1,2=336,3=90.000000
L 5.71991634 4.1818001 5.71783346 4.1802 1 P 0 ;0,1,2=336,3=90.000000
L 5.71783346 4.1802 5.71658297 4.17833327 1 P 0 ;0,1,2=336,3=90.000000
L 5.71658297 4.17833327 5.71658297 4.17166654 1 P 0 ;0,1,2=336,3=90.000000
L 5.71658297 4.17833327 5.7045 4.18233337 1 P 0 ;0,1,2=336,3=90.000000
L 5.72533337 4.19393317 5.72783287 4.19553327 1 P 0 ;0,1,2=336,3=90.000000
L 5.72783287 4.19553327 5.72908337 4.1974 1 P 0 ;0,1,2=336,3=90.000000
L 5.72908337 4.1974 5.7295 4.19953337 1 P 0 ;0,1,2=336,3=90.000000
L 5.7295 4.19953337 5.72866683 4.2022 1 P 0 ;0,1,2=336,3=90.000000
L 5.72866683 4.2022 5.72658317 4.20406673 1 P 0 ;0,1,2=336,3=90.000000
L 5.72658317 4.20406673 5.72408366 4.2046 1 P 0 ;0,1,2=336,3=90.000000
L 5.72408366 4.2046 5.72158268 4.20433337 1 P 0 ;0,1,2=336,3=90.000000
L 5.72158268 4.20433337 5.7194998 4.20326644 1 P 0 ;0,1,2=336,3=90.000000
L 5.7194998 4.20326644 5.71533327 4.19793327 1 P 0 ;0,1,2=336,3=90.000000
L 5.71533327 4.19793327 5.71241644 4.19553327 1 P 0 ;0,1,2=336,3=90.000000
L 5.71241644 4.19553327 5.70824911 4.19393317 1 P 0 ;0,1,2=336,3=90.000000
L 5.70824911 4.19393317 5.7045 4.1933999 1 P 0 ;0,1,2=336,3=90.000000
L 5.7045 4.1933999 5.7045 4.2046 1 P 0 ;0,1,2=336,3=90.000000
L 5.70824911 4.21513327 5.70616624 4.21673297 1 P 0 ;0,1,2=336,3=90.000000
L 5.70616624 4.21673297 5.70491654 4.2185997 1 P 0 ;0,1,2=336,3=90.000000
L 5.70491654 4.2185997 5.7045 4.2209997 1 P 0 ;0,1,2=336,3=90.000000
L 5.7045 4.2209997 5.70533307 4.2234002 1 P 0 ;0,1,2=336,3=90.000000
L 5.70533307 4.2234002 5.70699941 4.22526644 1 P 0 ;0,1,2=336,3=90.000000
L 5.70699941 4.22526644 5.70991624 4.2266 1 P 0 ;0,1,2=336,3=90.000000
L 5.70991624 4.2266 5.71324961 4.22686663 1 P 0 ;0,1,2=336,3=90.000000
L 5.71324961 4.22686663 5.71658297 4.22633337 1 P 0 ;0,1,2=336,3=90.000000
L 5.71658297 4.22633337 5.71866663 4.2249998 1 P 0 ;0,1,2=336,3=90.000000
L 5.71866663 4.2249998 5.72033297 4.22313307 1 P 0 ;0,1,2=336,3=90.000000
L 5.72033297 4.22313307 5.72074951 4.22126683 1 P 0 ;0,1,2=336,3=90.000000
L 5.72074951 4.22126683 5.72033297 4.2194 1 P 0 ;0,1,2=336,3=90.000000
L 5.72033297 4.2194 5.71866663 4.2170001 1 P 0 ;0,1,2=336,3=90.000000
L 5.71866663 4.2170001 5.7295 4.2177999 1 P 0 ;0,1,2=336,3=90.000000
L 5.7295 4.2177999 5.7295 4.2249998 1 P 0 ;0,1,2=336,3=90.000000
L 5.70741604 4.23846634 5.70533307 4.24033317 1 P 0 ;0,1,2=336,3=90.000000
L 5.70533307 4.24033317 5.7045 4.24246654 1 P 0 ;0,1,2=336,3=90.000000
L 5.7045 4.24246654 5.70533307 4.2445999 1 P 0 ;0,1,2=336,3=90.000000
L 5.70533307 4.2445999 5.70783258 4.24646663 1 P 0 ;0,1,2=336,3=90.000000
L 5.70783258 4.24646663 5.71158327 4.2478001 1 P 0 ;0,1,2=336,3=90.000000
L 5.71158327 4.2478001 5.71533327 4.24833337 1 P 0 ;0,1,2=336,3=90.000000
L 5.71533327 4.24833337 5.71991634 4.24833337 1 P 0 ;0,1,2=336,3=90.000000
L 5.71991634 4.24833337 5.72366634 4.2478001 1 P 0 ;0,1,2=336,3=90.000000
L 5.72366634 4.2478001 5.7269997 4.24646663 1 P 0 ;0,1,2=336,3=90.000000
L 5.7269997 4.24646663 5.72866683 4.24486644 1 P 0 ;0,1,2=336,3=90.000000
L 5.72866683 4.24486644 5.7295 4.2429997 1 P 0 ;0,1,2=336,3=90.000000
L 5.7295 4.2429997 5.72866683 4.24086634 1 P 0 ;0,1,2=336,3=90.000000
L 5.72866683 4.24086634 5.7269997 4.23926663 1 P 0 ;0,1,2=336,3=90.000000
L 5.7269997 4.23926663 5.7245003 4.2381998 1 P 0 ;0,1,2=336,3=90.000000
L 5.7245003 4.2381998 5.72116614 4.23766654 1 P 0 ;0,1,2=336,3=90.000000
L 5.72116614 4.23766654 5.7182501 4.2381998 1 P 0 ;0,1,2=336,3=90.000000
L 5.7182501 4.2381998 5.71533327 4.23953327 1 P 0 ;0,1,2=336,3=90.000000
L 5.71533327 4.23953327 5.71366614 4.24113346 1 P 0 ;0,1,2=336,3=90.000000
L 5.71366614 4.24113346 5.71324961 4.2429997 1 P 0 ;0,1,2=336,3=90.000000
L 5.71324961 4.2429997 5.71408278 4.24513307 1 P 0 ;0,1,2=336,3=90.000000
L 5.71408278 4.24513307 5.71616644 4.24673327 1 P 0 ;0,1,2=336,3=90.000000
L 5.71616644 4.24673327 5.71991634 4.24833337 1 P 0 ;0,1,2=336,3=90.000000
L 5.413 4.1 5.413 4.19 1 P 0 
L 5.413 4.19 5.457 4.19 1 P 0 
L 5.457 4.19 5.457 4.1 1 P 0 
L 5.457 4.1 5.413 4.1 1 P 0 
L 5.47916683 4.0345 5.47916683 4.0655 1 P 0 ;0,1,2=337,3=0.000000
L 5.47916683 4.0655 5.46958346 4.0655 1 P 0 ;0,1,2=337,3=0.000000
L 5.46958346 4.0655 5.46651673 4.06394931 1 P 0 ;0,1,2=337,3=0.000000
L 5.46651673 4.06394931 5.4645998 4.06188307 1 P 0 ;0,1,2=337,3=0.000000
L 5.4645998 4.06188307 5.46383327 4.0577497 1 P 0 ;0,1,2=337,3=0.000000
L 5.46383327 4.0577497 5.4645998 4.05361634 1 P 0 ;0,1,2=337,3=0.000000
L 5.4645998 4.05361634 5.4669 4.05103356 1 P 0 ;0,1,2=337,3=0.000000
L 5.4669 4.05103356 5.46958346 4.04948287 1 P 0 ;0,1,2=337,3=0.000000
L 5.46958346 4.04948287 5.47916683 4.04948287 1 P 0 ;0,1,2=337,3=0.000000
L 5.46958346 4.04948287 5.46383327 4.0345 1 P 0 ;0,1,2=337,3=0.000000
L 5.44050039 4.0345 5.44050039 4.0655 1 P 0 ;0,1,2=337,3=0.000000
L 5.44050039 4.0655 5.4451001 4.0593003 1 P 0 ;0,1,2=337,3=0.000000
L 5.4451001 4.0345 5.43590069 4.0345 1 P 0 ;0,1,2=337,3=0.000000
L 5.41793337 4.04069961 5.41563386 4.03708278 1 P 0 ;0,1,2=337,3=0.000000
L 5.41563386 4.03708278 5.41256713 4.03501654 1 P 0 ;0,1,2=337,3=0.000000
L 5.41256713 4.03501654 5.40911644 4.0345 1 P 0 ;0,1,2=337,3=0.000000
L 5.40911644 4.0345 5.4060497 4.03501654 1 P 0 ;0,1,2=337,3=0.000000
L 5.4060497 4.03501654 5.40298297 4.03759931 1 P 0 ;0,1,2=337,3=0.000000
L 5.40298297 4.03759931 5.40106673 4.04069961 1 P 0 ;0,1,2=337,3=0.000000
L 5.40106673 4.04069961 5.40068346 4.0437999 1 P 0 ;0,1,2=337,3=0.000000
L 5.40068346 4.0437999 5.40145 4.04741575 1 P 0 ;0,1,2=337,3=0.000000
L 5.40145 4.04741575 5.40413346 4.04999951 1 P 0 ;0,1,2=337,3=0.000000
L 5.40413346 4.04999951 5.40681693 4.05103356 1 P 0 ;0,1,2=337,3=0.000000
L 5.40681693 4.05103356 5.41026693 4.05103356 1 P 0 ;0,1,2=337,3=0.000000
L 5.40681693 4.05103356 5.40451673 4.05258317 1 P 0 ;0,1,2=337,3=0.000000
L 5.40451673 4.05258317 5.4025998 4.05516594 1 P 0 ;0,1,2=337,3=0.000000
L 5.4025998 4.05516594 5.40183327 4.05826624 1 P 0 ;0,1,2=337,3=0.000000
L 5.40183327 4.05826624 5.4025998 4.06136654 1 P 0 ;0,1,2=337,3=0.000000
L 5.4025998 4.06136654 5.40451673 4.06394931 1 P 0 ;0,1,2=337,3=0.000000
L 5.40451673 4.06394931 5.40796673 4.0655 1 P 0 ;0,1,2=337,3=0.000000
L 5.40796673 4.0655 5.41141663 4.06498337 1 P 0 ;0,1,2=337,3=0.000000
L 5.41141663 4.06498337 5.41486663 4.06291624 1 P 0 ;0,1,2=337,3=0.000000
L 5.37850039 4.0345 5.37581693 4.03501654 1 P 0 ;0,1,2=337,3=0.000000
L 5.37581693 4.03501654 5.3727502 4.03656614 1 P 0 ;0,1,2=337,3=0.000000
L 5.3727502 4.03656614 5.37083327 4.03914892 1 P 0 ;0,1,2=337,3=0.000000
L 5.37083327 4.03914892 5.37006673 4.04276673 1 P 0 ;0,1,2=337,3=0.000000
L 5.37006673 4.04276673 5.37083327 4.04638268 1 P 0 ;0,1,2=337,3=0.000000
L 5.37083327 4.04638268 5.37313346 4.04948287 1 P 0 ;0,1,2=337,3=0.000000
L 5.37313346 4.04948287 5.37658346 4.05103356 1 P 0 ;0,1,2=337,3=0.000000
L 5.37658346 4.05103356 5.38041663 4.05103356 1 P 0 ;0,1,2=337,3=0.000000
L 5.38041663 4.05103356 5.38271683 4.05206663 1 P 0 ;0,1,2=337,3=0.000000
L 5.38271683 4.05206663 5.38463386 4.05464941 1 P 0 ;0,1,2=337,3=0.000000
L 5.38463386 4.05464941 5.3854003 4.05826624 1 P 0 ;0,1,2=337,3=0.000000
L 5.3854003 4.05826624 5.3842499 4.06188307 1 P 0 ;0,1,2=337,3=0.000000
L 5.3842499 4.06188307 5.38156713 4.06446683 1 P 0 ;0,1,2=337,3=0.000000
L 5.38156713 4.06446683 5.37850039 4.0655 1 P 0 ;0,1,2=337,3=0.000000
L 5.37850039 4.0655 5.37543366 4.06446683 1 P 0 ;0,1,2=337,3=0.000000
L 5.37543366 4.06446683 5.3727502 4.06188307 1 P 0 ;0,1,2=337,3=0.000000
L 5.3727502 4.06188307 5.3715998 4.05826624 1 P 0 ;0,1,2=337,3=0.000000
L 5.3715998 4.05826624 5.37236693 4.05464941 1 P 0 ;0,1,2=337,3=0.000000
L 5.37236693 4.05464941 5.37428327 4.05206663 1 P 0 ;0,1,2=337,3=0.000000
L 5.37428327 4.05206663 5.37658346 4.05103356 1 P 0 ;0,1,2=337,3=0.000000
L 5.37658346 4.05103356 5.38041663 4.05103356 1 P 0 ;0,1,2=337,3=0.000000
L 5.38041663 4.05103356 5.38386663 4.04948287 1 P 0 ;0,1,2=337,3=0.000000
L 5.38386663 4.04948287 5.38616683 4.04638268 1 P 0 ;0,1,2=337,3=0.000000
L 5.38616683 4.04638268 5.38693337 4.04276673 1 P 0 ;0,1,2=337,3=0.000000
L 5.38693337 4.04276673 5.38616683 4.03914892 1 P 0 ;0,1,2=337,3=0.000000
L 5.38616683 4.03914892 5.3842499 4.03656614 1 P 0 ;0,1,2=337,3=0.000000
L 5.3842499 4.03656614 5.38118317 4.03501654 1 P 0 ;0,1,2=337,3=0.000000
L 5.38118317 4.03501654 5.37850039 4.0345 1 P 0 ;0,1,2=337,3=0.000000
L 0.721 0.977 0.765 0.977 1 P 0 
L 0.721 0.887 0.721 0.977 1 P 0 
L 0.765 0.977 0.765 0.887 1 P 0 
L 0.765 0.887 0.721 0.887 1 P 0 
L 0.6895 1.00583317 0.7205 1.00583317 1 P 0 ;0,1,2=338,3=90.000000
L 0.7205 1.00583317 0.7205 1.01541654 1 P 0 ;0,1,2=338,3=90.000000
L 0.7205 1.01541654 0.71894931 1.01848327 1 P 0 ;0,1,2=338,3=90.000000
L 0.71894931 1.01848327 0.71688307 1.0204002 1 P 0 ;0,1,2=338,3=90.000000
L 0.71688307 1.0204002 0.7127497 1.02116673 1 P 0 ;0,1,2=338,3=90.000000
L 0.7127497 1.02116673 0.70861634 1.0204002 1 P 0 ;0,1,2=338,3=90.000000
L 0.70861634 1.0204002 0.70603356 1.0181 1 P 0 ;0,1,2=338,3=90.000000
L 0.70603356 1.0181 0.70448287 1.01541654 1 P 0 ;0,1,2=338,3=90.000000
L 0.70448287 1.01541654 0.70448287 1.00583317 1 P 0 ;0,1,2=338,3=90.000000
L 0.70448287 1.01541654 0.6895 1.02116673 1 P 0 ;0,1,2=338,3=90.000000
L 0.6895 1.04449961 0.7205 1.04449961 1 P 0 ;0,1,2=338,3=90.000000
L 0.7205 1.04449961 0.7143003 1.0398999 1 P 0 ;0,1,2=338,3=90.000000
L 0.6895 1.0398999 0.6895 1.04909931 1 P 0 ;0,1,2=338,3=90.000000
L 0.70241575 1.06821644 0.70603356 1.0708999 1 P 0 ;0,1,2=338,3=90.000000
L 0.70603356 1.0708999 0.7080998 1.0732001 1 P 0 ;0,1,2=338,3=90.000000
L 0.7080998 1.0732001 0.70913287 1.07626683 1 P 0 ;0,1,2=338,3=90.000000
L 0.70913287 1.07626683 0.7080998 1.0789503 1 P 0 ;0,1,2=338,3=90.000000
L 0.7080998 1.0789503 0.70603356 1.08086654 1 P 0 ;0,1,2=338,3=90.000000
L 0.70603356 1.08086654 0.70293327 1.0824002 1 P 0 ;0,1,2=338,3=90.000000
L 0.70293327 1.0824002 0.69931644 1.08278346 1 P 0 ;0,1,2=338,3=90.000000
L 0.69931644 1.08278346 0.69621614 1.0824002 1 P 0 ;0,1,2=338,3=90.000000
L 0.69621614 1.0824002 0.69311585 1.08086654 1 P 0 ;0,1,2=338,3=90.000000
L 0.69311585 1.08086654 0.69053307 1.07856634 1 P 0 ;0,1,2=338,3=90.000000
L 0.69053307 1.07856634 0.6895 1.07588356 1 P 0 ;0,1,2=338,3=90.000000
L 0.6895 1.07588356 0.69053307 1.07281683 1 P 0 ;0,1,2=338,3=90.000000
L 0.69053307 1.07281683 0.69363238 1.07013337 1 P 0 ;0,1,2=338,3=90.000000
L 0.69363238 1.07013337 0.69828327 1.0685997 1 P 0 ;0,1,2=338,3=90.000000
L 0.69828327 1.0685997 0.7034498 1.06821644 1 P 0 ;0,1,2=338,3=90.000000
L 0.7034498 1.06821644 0.71016594 1.06898287 1 P 0 ;0,1,2=338,3=90.000000
L 0.71016594 1.06898287 0.71378376 1.07013337 1 P 0 ;0,1,2=338,3=90.000000
L 0.71378376 1.07013337 0.7173997 1.07204961 1 P 0 ;0,1,2=338,3=90.000000
L 0.7173997 1.07204961 0.71998337 1.07473307 1 P 0 ;0,1,2=338,3=90.000000
L 0.71998337 1.07473307 0.7205 1.07741654 1 P 0 ;0,1,2=338,3=90.000000
L 0.7205 1.07741654 0.71946683 1.0801 1 P 0 ;0,1,2=338,3=90.000000
L 0.71946683 1.0801 0.71688307 1.08201703 1 P 0 ;0,1,2=338,3=90.000000
L 0.71533346 1.09921644 0.71843278 1.10151663 1 P 0 ;0,1,2=338,3=90.000000
L 0.71843278 1.10151663 0.71998337 1.1042001 1 P 0 ;0,1,2=338,3=90.000000
L 0.71998337 1.1042001 0.7205 1.10726683 1 P 0 ;0,1,2=338,3=90.000000
L 0.7205 1.10726683 0.71946683 1.1111 1 P 0 ;0,1,2=338,3=90.000000
L 0.71946683 1.1111 0.71688307 1.11378346 1 P 0 ;0,1,2=338,3=90.000000
L 0.71688307 1.11378346 0.71378376 1.11455 1 P 0 ;0,1,2=338,3=90.000000
L 0.71378376 1.11455 0.71068258 1.11416673 1 P 0 ;0,1,2=338,3=90.000000
L 0.71068258 1.11416673 0.7080998 1.11263307 1 P 0 ;0,1,2=338,3=90.000000
L 0.7080998 1.11263307 0.70293327 1.10496663 1 P 0 ;0,1,2=338,3=90.000000
L 0.70293327 1.10496663 0.69931644 1.10151663 1 P 0 ;0,1,2=338,3=90.000000
L 0.69931644 1.10151663 0.69414892 1.09921644 1 P 0 ;0,1,2=338,3=90.000000
L 0.69414892 1.09921644 0.6895 1.0984499 1 P 0 ;0,1,2=338,3=90.000000
L 0.6895 1.0984499 0.6895 1.11455 1 P 0 ;0,1,2=338,3=90.000000
L 5.768 4.285 5.812 4.285 1 P 0 
L 5.812 4.285 5.812 4.195 1 P 0 
L 5.812 4.195 5.768 4.195 1 P 0 
L 5.768 4.195 5.768 4.285 1 P 0 
L 5.8545 4.18583317 5.8855 4.18583317 1 P 0 ;0,1,2=339,3=90.000000
L 5.8855 4.18583317 5.8855 4.19541654 1 P 0 ;0,1,2=339,3=90.000000
L 5.8855 4.19541654 5.88394931 4.19848327 1 P 0 ;0,1,2=339,3=90.000000
L 5.88394931 4.19848327 5.88188307 4.2004002 1 P 0 ;0,1,2=339,3=90.000000
L 5.88188307 4.2004002 5.8777497 4.20116673 1 P 0 ;0,1,2=339,3=90.000000
L 5.8777497 4.20116673 5.87361634 4.2004002 1 P 0 ;0,1,2=339,3=90.000000
L 5.87361634 4.2004002 5.87103356 4.1981 1 P 0 ;0,1,2=339,3=90.000000
L 5.87103356 4.1981 5.86948287 4.19541654 1 P 0 ;0,1,2=339,3=90.000000
L 5.86948287 4.19541654 5.86948287 4.18583317 1 P 0 ;0,1,2=339,3=90.000000
L 5.86948287 4.19541654 5.8545 4.20116673 1 P 0 ;0,1,2=339,3=90.000000
L 5.88033346 4.21721644 5.88343278 4.21951663 1 P 0 ;0,1,2=339,3=90.000000
L 5.88343278 4.21951663 5.88498337 4.2222001 1 P 0 ;0,1,2=339,3=90.000000
L 5.88498337 4.2222001 5.8855 4.22526683 1 P 0 ;0,1,2=339,3=90.000000
L 5.8855 4.22526683 5.88446683 4.2291 1 P 0 ;0,1,2=339,3=90.000000
L 5.88446683 4.2291 5.88188307 4.23178346 1 P 0 ;0,1,2=339,3=90.000000
L 5.88188307 4.23178346 5.87878376 4.23255 1 P 0 ;0,1,2=339,3=90.000000
L 5.87878376 4.23255 5.87568258 4.23216673 1 P 0 ;0,1,2=339,3=90.000000
L 5.87568258 4.23216673 5.8730998 4.23063307 1 P 0 ;0,1,2=339,3=90.000000
L 5.8730998 4.23063307 5.86793327 4.22296663 1 P 0 ;0,1,2=339,3=90.000000
L 5.86793327 4.22296663 5.86431644 4.21951663 1 P 0 ;0,1,2=339,3=90.000000
L 5.86431644 4.21951663 5.85914892 4.21721644 1 P 0 ;0,1,2=339,3=90.000000
L 5.85914892 4.21721644 5.8545 4.2164499 1 P 0 ;0,1,2=339,3=90.000000
L 5.8545 4.2164499 5.8545 4.23255 1 P 0 ;0,1,2=339,3=90.000000
L 5.86741575 4.24821644 5.87103356 4.2508999 1 P 0 ;0,1,2=339,3=90.000000
L 5.87103356 4.2508999 5.8730998 4.2532001 1 P 0 ;0,1,2=339,3=90.000000
L 5.8730998 4.2532001 5.87413287 4.25626683 1 P 0 ;0,1,2=339,3=90.000000
L 5.87413287 4.25626683 5.8730998 4.2589503 1 P 0 ;0,1,2=339,3=90.000000
L 5.8730998 4.2589503 5.87103356 4.26086654 1 P 0 ;0,1,2=339,3=90.000000
L 5.87103356 4.26086654 5.86793327 4.2624002 1 P 0 ;0,1,2=339,3=90.000000
L 5.86793327 4.2624002 5.86431644 4.26278346 1 P 0 ;0,1,2=339,3=90.000000
L 5.86431644 4.26278346 5.86121614 4.2624002 1 P 0 ;0,1,2=339,3=90.000000
L 5.86121614 4.2624002 5.85811585 4.26086654 1 P 0 ;0,1,2=339,3=90.000000
L 5.85811585 4.26086654 5.85553307 4.25856634 1 P 0 ;0,1,2=339,3=90.000000
L 5.85553307 4.25856634 5.8545 4.25588356 1 P 0 ;0,1,2=339,3=90.000000
L 5.8545 4.25588356 5.85553307 4.25281683 1 P 0 ;0,1,2=339,3=90.000000
L 5.85553307 4.25281683 5.85863238 4.25013337 1 P 0 ;0,1,2=339,3=90.000000
L 5.85863238 4.25013337 5.86328327 4.2485997 1 P 0 ;0,1,2=339,3=90.000000
L 5.86328327 4.2485997 5.8684498 4.24821644 1 P 0 ;0,1,2=339,3=90.000000
L 5.8684498 4.24821644 5.87516594 4.24898287 1 P 0 ;0,1,2=339,3=90.000000
L 5.87516594 4.24898287 5.87878376 4.25013337 1 P 0 ;0,1,2=339,3=90.000000
L 5.87878376 4.25013337 5.8823997 4.25204961 1 P 0 ;0,1,2=339,3=90.000000
L 5.8823997 4.25204961 5.88498337 4.25473307 1 P 0 ;0,1,2=339,3=90.000000
L 5.88498337 4.25473307 5.8855 4.25741654 1 P 0 ;0,1,2=339,3=90.000000
L 5.8855 4.25741654 5.88446683 4.2601 1 P 0 ;0,1,2=339,3=90.000000
L 5.88446683 4.2601 5.88188307 4.26201703 1 P 0 ;0,1,2=339,3=90.000000
L 5.8545 4.28649961 5.8855 4.28649961 1 P 0 ;0,1,2=339,3=90.000000
L 5.8855 4.28649961 5.8793003 4.2818999 1 P 0 ;0,1,2=339,3=90.000000
L 5.8545 4.2818999 5.8545 4.29109931 1 P 0 ;0,1,2=339,3=90.000000
L 0.743 0.883 0.743 0.793 1 P 0 
L 0.743 0.793 0.699 0.793 1 P 0 
L 0.699 0.793 0.699 0.883 1 P 0 
L 0.699 0.883 0.743 0.883 1 P 0 
L 0.6645 0.79633317 0.6955 0.79633317 1 P 0 ;0,1,2=340,3=90.000000
L 0.6955 0.79633317 0.6955 0.80591654 1 P 0 ;0,1,2=340,3=90.000000
L 0.6955 0.80591654 0.69394931 0.80898327 1 P 0 ;0,1,2=340,3=90.000000
L 0.69394931 0.80898327 0.69188307 0.8109002 1 P 0 ;0,1,2=340,3=90.000000
L 0.69188307 0.8109002 0.6877497 0.81166673 1 P 0 ;0,1,2=340,3=90.000000
L 0.6877497 0.81166673 0.68361634 0.8109002 1 P 0 ;0,1,2=340,3=90.000000
L 0.68361634 0.8109002 0.68103356 0.8086 1 P 0 ;0,1,2=340,3=90.000000
L 0.68103356 0.8086 0.67948287 0.80591654 1 P 0 ;0,1,2=340,3=90.000000
L 0.67948287 0.80591654 0.67948287 0.79633317 1 P 0 ;0,1,2=340,3=90.000000
L 0.67948287 0.80591654 0.6645 0.81166673 1 P 0 ;0,1,2=340,3=90.000000
L 0.6645 0.8396 0.6955 0.8396 1 P 0 ;0,1,2=340,3=90.000000
L 0.6955 0.8396 0.67328327 0.82541624 1 P 0 ;0,1,2=340,3=90.000000
L 0.67328327 0.82541624 0.67328327 0.84458366 1 P 0 ;0,1,2=340,3=90.000000
L 0.66914892 0.85756663 0.66656614 0.85986614 1 P 0 ;0,1,2=340,3=90.000000
L 0.66656614 0.85986614 0.66501654 0.86254961 1 P 0 ;0,1,2=340,3=90.000000
L 0.66501654 0.86254961 0.6645 0.86599961 1 P 0 ;0,1,2=340,3=90.000000
L 0.6645 0.86599961 0.66553307 0.8694503 1 P 0 ;0,1,2=340,3=90.000000
L 0.66553307 0.8694503 0.66759931 0.87213307 1 P 0 ;0,1,2=340,3=90.000000
L 0.66759931 0.87213307 0.67121614 0.87405 1 P 0 ;0,1,2=340,3=90.000000
L 0.67121614 0.87405 0.67534951 0.87443327 1 P 0 ;0,1,2=340,3=90.000000
L 0.67534951 0.87443327 0.67948287 0.87366673 1 P 0 ;0,1,2=340,3=90.000000
L 0.67948287 0.87366673 0.68206663 0.8717498 1 P 0 ;0,1,2=340,3=90.000000
L 0.68206663 0.8717498 0.68413287 0.86906634 1 P 0 ;0,1,2=340,3=90.000000
L 0.68413287 0.86906634 0.68464941 0.86638356 1 P 0 ;0,1,2=340,3=90.000000
L 0.68464941 0.86638356 0.68413287 0.8637001 1 P 0 ;0,1,2=340,3=90.000000
L 0.68413287 0.8637001 0.68206663 0.8602501 1 P 0 ;0,1,2=340,3=90.000000
L 0.68206663 0.8602501 0.6955 0.8613999 1 P 0 ;0,1,2=340,3=90.000000
L 0.6955 0.8613999 0.6955 0.8717498 1 P 0 ;0,1,2=340,3=90.000000
L 5.488 2.39 5.532 2.39 1 P 0 
L 5.532 2.39 5.532 2.3 1 P 0 
L 5.532 2.3 5.488 2.3 1 P 0 
L 5.488 2.3 5.488 2.39 1 P 0 
L 5.4895 2.41583317 5.5205 2.41583317 1 P 0 ;0,1,2=341,3=90.000000
L 5.5205 2.41583317 5.5205 2.42541654 1 P 0 ;0,1,2=341,3=90.000000
L 5.5205 2.42541654 5.51894931 2.42848327 1 P 0 ;0,1,2=341,3=90.000000
L 5.51894931 2.42848327 5.51688307 2.4304002 1 P 0 ;0,1,2=341,3=90.000000
L 5.51688307 2.4304002 5.5127497 2.43116673 1 P 0 ;0,1,2=341,3=90.000000
L 5.5127497 2.43116673 5.50861634 2.4304002 1 P 0 ;0,1,2=341,3=90.000000
L 5.50861634 2.4304002 5.50603356 2.4281 1 P 0 ;0,1,2=341,3=90.000000
L 5.50603356 2.4281 5.50448287 2.42541654 1 P 0 ;0,1,2=341,3=90.000000
L 5.50448287 2.42541654 5.50448287 2.41583317 1 P 0 ;0,1,2=341,3=90.000000
L 5.50448287 2.42541654 5.4895 2.43116673 1 P 0 ;0,1,2=341,3=90.000000
L 5.51533346 2.44721644 5.51843278 2.44951663 1 P 0 ;0,1,2=341,3=90.000000
L 5.51843278 2.44951663 5.51998337 2.4522001 1 P 0 ;0,1,2=341,3=90.000000
L 5.51998337 2.4522001 5.5205 2.45526683 1 P 0 ;0,1,2=341,3=90.000000
L 5.5205 2.45526683 5.51946683 2.4591 1 P 0 ;0,1,2=341,3=90.000000
L 5.51946683 2.4591 5.51688307 2.46178346 1 P 0 ;0,1,2=341,3=90.000000
L 5.51688307 2.46178346 5.51378376 2.46255 1 P 0 ;0,1,2=341,3=90.000000
L 5.51378376 2.46255 5.51068258 2.46216673 1 P 0 ;0,1,2=341,3=90.000000
L 5.51068258 2.46216673 5.5080998 2.46063307 1 P 0 ;0,1,2=341,3=90.000000
L 5.5080998 2.46063307 5.50293327 2.45296663 1 P 0 ;0,1,2=341,3=90.000000
L 5.50293327 2.45296663 5.49931644 2.44951663 1 P 0 ;0,1,2=341,3=90.000000
L 5.49931644 2.44951663 5.49414892 2.44721644 1 P 0 ;0,1,2=341,3=90.000000
L 5.49414892 2.44721644 5.4895 2.4464499 1 P 0 ;0,1,2=341,3=90.000000
L 5.4895 2.4464499 5.4895 2.46255 1 P 0 ;0,1,2=341,3=90.000000
L 5.4895 2.4901 5.5205 2.4901 1 P 0 ;0,1,2=341,3=90.000000
L 5.5205 2.4901 5.49828327 2.47591624 1 P 0 ;0,1,2=341,3=90.000000
L 5.49828327 2.47591624 5.49828327 2.49508366 1 P 0 ;0,1,2=341,3=90.000000
L 5.4895 2.5211 5.5205 2.5211 1 P 0 ;0,1,2=341,3=90.000000
L 5.5205 2.5211 5.49828327 2.50691624 1 P 0 ;0,1,2=341,3=90.000000
L 5.49828327 2.50691624 5.49828327 2.52608366 1 P 0 ;0,1,2=341,3=90.000000
L 5.533 2.39 5.577 2.39 1 P 0 
L 5.533 2.3 5.533 2.39 1 P 0 
L 5.577 2.39 5.577 2.3 1 P 0 
L 5.577 2.3 5.533 2.3 1 P 0 
L 5.5345 2.41583317 5.5655 2.41583317 1 P 0 ;0,1,2=342,3=90.000000
L 5.5655 2.41583317 5.5655 2.42541654 1 P 0 ;0,1,2=342,3=90.000000
L 5.5655 2.42541654 5.56394931 2.42848327 1 P 0 ;0,1,2=342,3=90.000000
L 5.56394931 2.42848327 5.56188307 2.4304002 1 P 0 ;0,1,2=342,3=90.000000
L 5.56188307 2.4304002 5.5577497 2.43116673 1 P 0 ;0,1,2=342,3=90.000000
L 5.5577497 2.43116673 5.55361634 2.4304002 1 P 0 ;0,1,2=342,3=90.000000
L 5.55361634 2.4304002 5.55103356 2.4281 1 P 0 ;0,1,2=342,3=90.000000
L 5.55103356 2.4281 5.54948287 2.42541654 1 P 0 ;0,1,2=342,3=90.000000
L 5.54948287 2.42541654 5.54948287 2.41583317 1 P 0 ;0,1,2=342,3=90.000000
L 5.54948287 2.42541654 5.5345 2.43116673 1 P 0 ;0,1,2=342,3=90.000000
L 5.56033346 2.44721644 5.56343278 2.44951663 1 P 0 ;0,1,2=342,3=90.000000
L 5.56343278 2.44951663 5.56498337 2.4522001 1 P 0 ;0,1,2=342,3=90.000000
L 5.56498337 2.4522001 5.5655 2.45526683 1 P 0 ;0,1,2=342,3=90.000000
L 5.5655 2.45526683 5.56446683 2.4591 1 P 0 ;0,1,2=342,3=90.000000
L 5.56446683 2.4591 5.56188307 2.46178346 1 P 0 ;0,1,2=342,3=90.000000
L 5.56188307 2.46178346 5.55878376 2.46255 1 P 0 ;0,1,2=342,3=90.000000
L 5.55878376 2.46255 5.55568258 2.46216673 1 P 0 ;0,1,2=342,3=90.000000
L 5.55568258 2.46216673 5.5530998 2.46063307 1 P 0 ;0,1,2=342,3=90.000000
L 5.5530998 2.46063307 5.54793327 2.45296663 1 P 0 ;0,1,2=342,3=90.000000
L 5.54793327 2.45296663 5.54431644 2.44951663 1 P 0 ;0,1,2=342,3=90.000000
L 5.54431644 2.44951663 5.53914892 2.44721644 1 P 0 ;0,1,2=342,3=90.000000
L 5.53914892 2.44721644 5.5345 2.4464499 1 P 0 ;0,1,2=342,3=90.000000
L 5.5345 2.4464499 5.5345 2.46255 1 P 0 ;0,1,2=342,3=90.000000
L 5.5345 2.4901 5.5655 2.4901 1 P 0 ;0,1,2=342,3=90.000000
L 5.5655 2.4901 5.54328327 2.47591624 1 P 0 ;0,1,2=342,3=90.000000
L 5.54328327 2.47591624 5.54328327 2.49508366 1 P 0 ;0,1,2=342,3=90.000000
L 5.54741575 2.50921644 5.55103356 2.5118999 1 P 0 ;0,1,2=342,3=90.000000
L 5.55103356 2.5118999 5.5530998 2.5142001 1 P 0 ;0,1,2=342,3=90.000000
L 5.5530998 2.5142001 5.55413287 2.51726683 1 P 0 ;0,1,2=342,3=90.000000
L 5.55413287 2.51726683 5.5530998 2.5199503 1 P 0 ;0,1,2=342,3=90.000000
L 5.5530998 2.5199503 5.55103356 2.52186654 1 P 0 ;0,1,2=342,3=90.000000
L 5.55103356 2.52186654 5.54793327 2.5234002 1 P 0 ;0,1,2=342,3=90.000000
L 5.54793327 2.5234002 5.54431644 2.52378346 1 P 0 ;0,1,2=342,3=90.000000
L 5.54431644 2.52378346 5.54121614 2.5234002 1 P 0 ;0,1,2=342,3=90.000000
L 5.54121614 2.5234002 5.53811585 2.52186654 1 P 0 ;0,1,2=342,3=90.000000
L 5.53811585 2.52186654 5.53553307 2.51956634 1 P 0 ;0,1,2=342,3=90.000000
L 5.53553307 2.51956634 5.5345 2.51688356 1 P 0 ;0,1,2=342,3=90.000000
L 5.5345 2.51688356 5.53553307 2.51381683 1 P 0 ;0,1,2=342,3=90.000000
L 5.53553307 2.51381683 5.53863238 2.51113337 1 P 0 ;0,1,2=342,3=90.000000
L 5.53863238 2.51113337 5.54328327 2.5095997 1 P 0 ;0,1,2=342,3=90.000000
L 5.54328327 2.5095997 5.5484498 2.50921644 1 P 0 ;0,1,2=342,3=90.000000
L 5.5484498 2.50921644 5.55516594 2.50998287 1 P 0 ;0,1,2=342,3=90.000000
L 5.55516594 2.50998287 5.55878376 2.51113337 1 P 0 ;0,1,2=342,3=90.000000
L 5.55878376 2.51113337 5.5623997 2.51304961 1 P 0 ;0,1,2=342,3=90.000000
L 5.5623997 2.51304961 5.56498337 2.51573307 1 P 0 ;0,1,2=342,3=90.000000
L 5.56498337 2.51573307 5.5655 2.51841654 1 P 0 ;0,1,2=342,3=90.000000
L 5.5655 2.51841654 5.56446683 2.5211 1 P 0 ;0,1,2=342,3=90.000000
L 5.56446683 2.5211 5.56188307 2.52301703 1 P 0 ;0,1,2=342,3=90.000000
L 5.622 2.39 5.622 2.3 1 P 0 
L 5.578 2.39 5.622 2.39 1 P 0 
L 5.578 2.3 5.578 2.39 1 P 0 
L 5.622 2.3 5.578 2.3 1 P 0 
L 5.5795 2.41583317 5.6105 2.41583317 1 P 0 ;0,1,2=343,3=90.000000
L 5.6105 2.41583317 5.6105 2.42541654 1 P 0 ;0,1,2=343,3=90.000000
L 5.6105 2.42541654 5.60894931 2.42848327 1 P 0 ;0,1,2=343,3=90.000000
L 5.60894931 2.42848327 5.60688307 2.4304002 1 P 0 ;0,1,2=343,3=90.000000
L 5.60688307 2.4304002 5.6027497 2.43116673 1 P 0 ;0,1,2=343,3=90.000000
L 5.6027497 2.43116673 5.59861634 2.4304002 1 P 0 ;0,1,2=343,3=90.000000
L 5.59861634 2.4304002 5.59603356 2.4281 1 P 0 ;0,1,2=343,3=90.000000
L 5.59603356 2.4281 5.59448287 2.42541654 1 P 0 ;0,1,2=343,3=90.000000
L 5.59448287 2.42541654 5.59448287 2.41583317 1 P 0 ;0,1,2=343,3=90.000000
L 5.59448287 2.42541654 5.5795 2.43116673 1 P 0 ;0,1,2=343,3=90.000000
L 5.60533346 2.44721644 5.60843278 2.44951663 1 P 0 ;0,1,2=343,3=90.000000
L 5.60843278 2.44951663 5.60998337 2.4522001 1 P 0 ;0,1,2=343,3=90.000000
L 5.60998337 2.4522001 5.6105 2.45526683 1 P 0 ;0,1,2=343,3=90.000000
L 5.6105 2.45526683 5.60946683 2.4591 1 P 0 ;0,1,2=343,3=90.000000
L 5.60946683 2.4591 5.60688307 2.46178346 1 P 0 ;0,1,2=343,3=90.000000
L 5.60688307 2.46178346 5.60378376 2.46255 1 P 0 ;0,1,2=343,3=90.000000
L 5.60378376 2.46255 5.60068258 2.46216673 1 P 0 ;0,1,2=343,3=90.000000
L 5.60068258 2.46216673 5.5980998 2.46063307 1 P 0 ;0,1,2=343,3=90.000000
L 5.5980998 2.46063307 5.59293327 2.45296663 1 P 0 ;0,1,2=343,3=90.000000
L 5.59293327 2.45296663 5.58931644 2.44951663 1 P 0 ;0,1,2=343,3=90.000000
L 5.58931644 2.44951663 5.58414892 2.44721644 1 P 0 ;0,1,2=343,3=90.000000
L 5.58414892 2.44721644 5.5795 2.4464499 1 P 0 ;0,1,2=343,3=90.000000
L 5.5795 2.4464499 5.5795 2.46255 1 P 0 ;0,1,2=343,3=90.000000
L 5.5795 2.4901 5.6105 2.4901 1 P 0 ;0,1,2=343,3=90.000000
L 5.6105 2.4901 5.58828327 2.47591624 1 P 0 ;0,1,2=343,3=90.000000
L 5.58828327 2.47591624 5.58828327 2.49508366 1 P 0 ;0,1,2=343,3=90.000000
L 5.58311585 2.50998287 5.58053307 2.51266634 1 P 0 ;0,1,2=343,3=90.000000
L 5.58053307 2.51266634 5.5795 2.51573307 1 P 0 ;0,1,2=343,3=90.000000
L 5.5795 2.51573307 5.58053307 2.5187998 1 P 0 ;0,1,2=343,3=90.000000
L 5.58053307 2.5187998 5.58363238 2.52148327 1 P 0 ;0,1,2=343,3=90.000000
L 5.58363238 2.52148327 5.58828327 2.5234002 1 P 0 ;0,1,2=343,3=90.000000
L 5.58828327 2.5234002 5.59293327 2.52416673 1 P 0 ;0,1,2=343,3=90.000000
L 5.59293327 2.52416673 5.59861634 2.52416673 1 P 0 ;0,1,2=343,3=90.000000
L 5.59861634 2.52416673 5.60326624 2.5234002 1 P 0 ;0,1,2=343,3=90.000000
L 5.60326624 2.5234002 5.6073997 2.52148327 1 P 0 ;0,1,2=343,3=90.000000
L 5.6073997 2.52148327 5.60946683 2.51918307 1 P 0 ;0,1,2=343,3=90.000000
L 5.60946683 2.51918307 5.6105 2.51649961 1 P 0 ;0,1,2=343,3=90.000000
L 5.6105 2.51649961 5.60946683 2.51343287 1 P 0 ;0,1,2=343,3=90.000000
L 5.60946683 2.51343287 5.6073997 2.51113337 1 P 0 ;0,1,2=343,3=90.000000
L 5.6073997 2.51113337 5.6043003 2.5095997 1 P 0 ;0,1,2=343,3=90.000000
L 5.6043003 2.5095997 5.60016594 2.50883317 1 P 0 ;0,1,2=343,3=90.000000
L 5.60016594 2.50883317 5.5965501 2.5095997 1 P 0 ;0,1,2=343,3=90.000000
L 5.5965501 2.5095997 5.59293327 2.51151663 1 P 0 ;0,1,2=343,3=90.000000
L 5.59293327 2.51151663 5.59086604 2.51381683 1 P 0 ;0,1,2=343,3=90.000000
L 5.59086604 2.51381683 5.59034951 2.51649961 1 P 0 ;0,1,2=343,3=90.000000
L 5.59034951 2.51649961 5.59138268 2.51956634 1 P 0 ;0,1,2=343,3=90.000000
L 5.59138268 2.51956634 5.59396634 2.52186654 1 P 0 ;0,1,2=343,3=90.000000
L 5.59396634 2.52186654 5.59861634 2.52416673 1 P 0 ;0,1,2=343,3=90.000000
L 5.455 2.297 5.455 2.253 1 P 0 
L 5.365 2.297 5.455 2.297 1 P 0 
L 5.455 2.253 5.365 2.253 1 P 0 
L 5.365 2.253 5.365 2.297 1 P 0 
L 5.44916683 2.2145 5.44916683 2.2455 1 P 0 ;0,1,2=344,3=0.000000
L 5.44916683 2.2455 5.43958346 2.2455 1 P 0 ;0,1,2=344,3=0.000000
L 5.43958346 2.2455 5.43651673 2.24394931 1 P 0 ;0,1,2=344,3=0.000000
L 5.43651673 2.24394931 5.4345998 2.24188307 1 P 0 ;0,1,2=344,3=0.000000
L 5.4345998 2.24188307 5.43383327 2.2377497 1 P 0 ;0,1,2=344,3=0.000000
L 5.43383327 2.2377497 5.4345998 2.23361634 1 P 0 ;0,1,2=344,3=0.000000
L 5.4345998 2.23361634 5.4369 2.23103356 1 P 0 ;0,1,2=344,3=0.000000
L 5.4369 2.23103356 5.43958346 2.22948287 1 P 0 ;0,1,2=344,3=0.000000
L 5.43958346 2.22948287 5.44916683 2.22948287 1 P 0 ;0,1,2=344,3=0.000000
L 5.43958346 2.22948287 5.43383327 2.2145 1 P 0 ;0,1,2=344,3=0.000000
L 5.41778356 2.24033346 5.41548337 2.24343278 1 P 0 ;0,1,2=344,3=0.000000
L 5.41548337 2.24343278 5.4127999 2.24498337 1 P 0 ;0,1,2=344,3=0.000000
L 5.4127999 2.24498337 5.40973317 2.2455 1 P 0 ;0,1,2=344,3=0.000000
L 5.40973317 2.2455 5.4059 2.24446683 1 P 0 ;0,1,2=344,3=0.000000
L 5.4059 2.24446683 5.40321654 2.24188307 1 P 0 ;0,1,2=344,3=0.000000
L 5.40321654 2.24188307 5.40245 2.23878376 1 P 0 ;0,1,2=344,3=0.000000
L 5.40245 2.23878376 5.40283327 2.23568258 1 P 0 ;0,1,2=344,3=0.000000
L 5.40283327 2.23568258 5.40436693 2.2330998 1 P 0 ;0,1,2=344,3=0.000000
L 5.40436693 2.2330998 5.41203337 2.22793327 1 P 0 ;0,1,2=344,3=0.000000
L 5.41203337 2.22793327 5.41548337 2.22431644 1 P 0 ;0,1,2=344,3=0.000000
L 5.41548337 2.22431644 5.41778356 2.21914892 1 P 0 ;0,1,2=344,3=0.000000
L 5.41778356 2.21914892 5.4185501 2.2145 1 P 0 ;0,1,2=344,3=0.000000
L 5.4185501 2.2145 5.40245 2.2145 1 P 0 ;0,1,2=344,3=0.000000
L 5.3749 2.2145 5.3749 2.2455 1 P 0 ;0,1,2=344,3=0.000000
L 5.3749 2.2455 5.38908376 2.22328327 1 P 0 ;0,1,2=344,3=0.000000
L 5.38908376 2.22328327 5.36991634 2.22328327 1 P 0 ;0,1,2=344,3=0.000000
L 5.35693337 2.22069961 5.35463386 2.21708278 1 P 0 ;0,1,2=344,3=0.000000
L 5.35463386 2.21708278 5.35156713 2.21501654 1 P 0 ;0,1,2=344,3=0.000000
L 5.35156713 2.21501654 5.34811644 2.2145 1 P 0 ;0,1,2=344,3=0.000000
L 5.34811644 2.2145 5.3450497 2.21501654 1 P 0 ;0,1,2=344,3=0.000000
L 5.3450497 2.21501654 5.34198297 2.21759931 1 P 0 ;0,1,2=344,3=0.000000
L 5.34198297 2.21759931 5.34006673 2.22069961 1 P 0 ;0,1,2=344,3=0.000000
L 5.34006673 2.22069961 5.33968346 2.2237999 1 P 0 ;0,1,2=344,3=0.000000
L 5.33968346 2.2237999 5.34045 2.22741575 1 P 0 ;0,1,2=344,3=0.000000
L 5.34045 2.22741575 5.34313346 2.22999951 1 P 0 ;0,1,2=344,3=0.000000
L 5.34313346 2.22999951 5.34581693 2.23103356 1 P 0 ;0,1,2=344,3=0.000000
L 5.34581693 2.23103356 5.34926693 2.23103356 1 P 0 ;0,1,2=344,3=0.000000
L 5.34581693 2.23103356 5.34351673 2.23258317 1 P 0 ;0,1,2=344,3=0.000000
L 5.34351673 2.23258317 5.3415998 2.23516594 1 P 0 ;0,1,2=344,3=0.000000
L 5.3415998 2.23516594 5.34083327 2.23826624 1 P 0 ;0,1,2=344,3=0.000000
L 5.34083327 2.23826624 5.3415998 2.24136654 1 P 0 ;0,1,2=344,3=0.000000
L 5.3415998 2.24136654 5.34351673 2.24394931 1 P 0 ;0,1,2=344,3=0.000000
L 5.34351673 2.24394931 5.34696673 2.2455 1 P 0 ;0,1,2=344,3=0.000000
L 5.34696673 2.2455 5.35041663 2.24498337 1 P 0 ;0,1,2=344,3=0.000000
L 5.35041663 2.24498337 5.35386663 2.24291624 1 P 0 ;0,1,2=344,3=0.000000
L 6.355 1.102 6.445 1.102 1 P 0 
L 6.445 1.102 6.445 1.058 1 P 0 
L 6.445 1.058 6.355 1.058 1 P 0 
L 6.355 1.058 6.355 1.102 1 P 0 
L 6.43416683 1.1495 6.43416683 1.1805 1 P 0 ;0,1,2=345,3=0.000000
L 6.43416683 1.1805 6.42458346 1.1805 1 P 0 ;0,1,2=345,3=0.000000
L 6.42458346 1.1805 6.42151673 1.17894931 1 P 0 ;0,1,2=345,3=0.000000
L 6.42151673 1.17894931 6.4195998 1.17688307 1 P 0 ;0,1,2=345,3=0.000000
L 6.4195998 1.17688307 6.41883327 1.1727497 1 P 0 ;0,1,2=345,3=0.000000
L 6.41883327 1.1727497 6.4195998 1.16861634 1 P 0 ;0,1,2=345,3=0.000000
L 6.4195998 1.16861634 6.4219 1.16603356 1 P 0 ;0,1,2=345,3=0.000000
L 6.4219 1.16603356 6.42458346 1.16448287 1 P 0 ;0,1,2=345,3=0.000000
L 6.42458346 1.16448287 6.43416683 1.16448287 1 P 0 ;0,1,2=345,3=0.000000
L 6.42458346 1.16448287 6.41883327 1.1495 1 P 0 ;0,1,2=345,3=0.000000
L 6.3909 1.1495 6.3909 1.1805 1 P 0 ;0,1,2=345,3=0.000000
L 6.3909 1.1805 6.40508376 1.15828327 1 P 0 ;0,1,2=345,3=0.000000
L 6.40508376 1.15828327 6.38591634 1.15828327 1 P 0 ;0,1,2=345,3=0.000000
L 6.36450039 1.1495 6.36450039 1.1805 1 P 0 ;0,1,2=345,3=0.000000
L 6.36450039 1.1805 6.3691001 1.1743003 1 P 0 ;0,1,2=345,3=0.000000
L 6.3691001 1.1495 6.35990069 1.1495 1 P 0 ;0,1,2=345,3=0.000000
L 6.33426693 1.1495 6.33350039 1.15621614 1 P 0 ;0,1,2=345,3=0.000000
L 6.33350039 1.15621614 6.3323499 1.16189921 1 P 0 ;0,1,2=345,3=0.000000
L 6.3323499 1.16189921 6.33081693 1.16706663 1 P 0 ;0,1,2=345,3=0.000000
L 6.33081693 1.16706663 6.3289 1.1727497 1 P 0 ;0,1,2=345,3=0.000000
L 6.3289 1.1727497 6.32583327 1.1805 1 P 0 ;0,1,2=345,3=0.000000
L 6.32583327 1.1805 6.34116683 1.1805 1 P 0 ;0,1,2=345,3=0.000000
L 6.355 1.042 6.445 1.042 1 P 0 
L 6.445 1.042 6.445 0.998 1 P 0 
L 6.445 0.998 6.355 0.998 1 P 0 
L 6.355 0.998 6.355 1.042 1 P 0 
L 6.43416683 1.1095 6.43416683 1.1405 1 P 0 ;0,1,2=346,3=0.000000
L 6.43416683 1.1405 6.42458346 1.1405 1 P 0 ;0,1,2=346,3=0.000000
L 6.42458346 1.1405 6.42151673 1.13894931 1 P 0 ;0,1,2=346,3=0.000000
L 6.42151673 1.13894931 6.4195998 1.13688307 1 P 0 ;0,1,2=346,3=0.000000
L 6.4195998 1.13688307 6.41883327 1.1327497 1 P 0 ;0,1,2=346,3=0.000000
L 6.41883327 1.1327497 6.4195998 1.12861634 1 P 0 ;0,1,2=346,3=0.000000
L 6.4195998 1.12861634 6.4219 1.12603356 1 P 0 ;0,1,2=346,3=0.000000
L 6.4219 1.12603356 6.42458346 1.12448287 1 P 0 ;0,1,2=346,3=0.000000
L 6.42458346 1.12448287 6.43416683 1.12448287 1 P 0 ;0,1,2=346,3=0.000000
L 6.42458346 1.12448287 6.41883327 1.1095 1 P 0 ;0,1,2=346,3=0.000000
L 6.3909 1.1095 6.3909 1.1405 1 P 0 ;0,1,2=346,3=0.000000
L 6.3909 1.1405 6.40508376 1.11828327 1 P 0 ;0,1,2=346,3=0.000000
L 6.40508376 1.11828327 6.38591634 1.11828327 1 P 0 ;0,1,2=346,3=0.000000
L 6.36450039 1.1095 6.36450039 1.1405 1 P 0 ;0,1,2=346,3=0.000000
L 6.36450039 1.1405 6.3691001 1.1343003 1 P 0 ;0,1,2=346,3=0.000000
L 6.3691001 1.1095 6.35990069 1.1095 1 P 0 ;0,1,2=346,3=0.000000
L 6.34193337 1.11414892 6.33963386 1.11156614 1 P 0 ;0,1,2=346,3=0.000000
L 6.33963386 1.11156614 6.33695039 1.11001654 1 P 0 ;0,1,2=346,3=0.000000
L 6.33695039 1.11001654 6.33350039 1.1095 1 P 0 ;0,1,2=346,3=0.000000
L 6.33350039 1.1095 6.3300497 1.11053307 1 P 0 ;0,1,2=346,3=0.000000
L 6.3300497 1.11053307 6.32736693 1.11259931 1 P 0 ;0,1,2=346,3=0.000000
L 6.32736693 1.11259931 6.32545 1.11621614 1 P 0 ;0,1,2=346,3=0.000000
L 6.32545 1.11621614 6.32506673 1.12034951 1 P 0 ;0,1,2=346,3=0.000000
L 6.32506673 1.12034951 6.32583327 1.12448287 1 P 0 ;0,1,2=346,3=0.000000
L 6.32583327 1.12448287 6.3277502 1.12706663 1 P 0 ;0,1,2=346,3=0.000000
L 6.3277502 1.12706663 6.33043366 1.12913287 1 P 0 ;0,1,2=346,3=0.000000
L 6.33043366 1.12913287 6.33311644 1.12964941 1 P 0 ;0,1,2=346,3=0.000000
L 6.33311644 1.12964941 6.3357999 1.12913287 1 P 0 ;0,1,2=346,3=0.000000
L 6.3357999 1.12913287 6.3392499 1.12706663 1 P 0 ;0,1,2=346,3=0.000000
L 6.3392499 1.12706663 6.3381001 1.1405 1 P 0 ;0,1,2=346,3=0.000000
L 6.3381001 1.1405 6.3277502 1.1405 1 P 0 ;0,1,2=346,3=0.000000
L 6.355 0.987 6.445 0.987 1 P 0 
L 6.445 0.987 6.445 0.943 1 P 0 
L 6.445 0.943 6.355 0.943 1 P 0 
L 6.355 0.943 6.355 0.987 1 P 0 
L 6.43916683 0.8945 6.43916683 0.9255 1 P 0 ;0,1,2=347,3=0.000000
L 6.43916683 0.9255 6.42958346 0.9255 1 P 0 ;0,1,2=347,3=0.000000
L 6.42958346 0.9255 6.42651673 0.92394931 1 P 0 ;0,1,2=347,3=0.000000
L 6.42651673 0.92394931 6.4245998 0.92188307 1 P 0 ;0,1,2=347,3=0.000000
L 6.4245998 0.92188307 6.42383327 0.9177497 1 P 0 ;0,1,2=347,3=0.000000
L 6.42383327 0.9177497 6.4245998 0.91361634 1 P 0 ;0,1,2=347,3=0.000000
L 6.4245998 0.91361634 6.4269 0.91103356 1 P 0 ;0,1,2=347,3=0.000000
L 6.4269 0.91103356 6.42958346 0.90948287 1 P 0 ;0,1,2=347,3=0.000000
L 6.42958346 0.90948287 6.43916683 0.90948287 1 P 0 ;0,1,2=347,3=0.000000
L 6.42958346 0.90948287 6.42383327 0.8945 1 P 0 ;0,1,2=347,3=0.000000
L 6.3959 0.8945 6.3959 0.9255 1 P 0 ;0,1,2=347,3=0.000000
L 6.3959 0.9255 6.41008376 0.90328327 1 P 0 ;0,1,2=347,3=0.000000
L 6.41008376 0.90328327 6.39091634 0.90328327 1 P 0 ;0,1,2=347,3=0.000000
L 6.36950039 0.8945 6.36950039 0.9255 1 P 0 ;0,1,2=347,3=0.000000
L 6.36950039 0.9255 6.3741001 0.9193003 1 P 0 ;0,1,2=347,3=0.000000
L 6.3741001 0.8945 6.36490069 0.8945 1 P 0 ;0,1,2=347,3=0.000000
L 6.33850039 0.8945 6.33850039 0.9255 1 P 0 ;0,1,2=347,3=0.000000
L 6.33850039 0.9255 6.3431001 0.9193003 1 P 0 ;0,1,2=347,3=0.000000
L 6.3431001 0.8945 6.33390069 0.8945 1 P 0 ;0,1,2=347,3=0.000000
L 6.04101998 1.97465 6.04101998 1.88465 1 P 0 
L 6.04101998 1.88465 5.99701998 1.88465 1 P 0 
L 5.99701998 1.88465 5.99701998 1.97465 1 P 0 
L 5.99701998 1.97465 6.04101998 1.97465 1 P 0 
L 5.9795 2.03083317 6.0105 2.03083317 1 P 0 ;0,1,2=348,3=90.000000
L 6.0105 2.03083317 6.0105 2.04041654 1 P 0 ;0,1,2=348,3=90.000000
L 6.0105 2.04041654 6.00894931 2.04348327 1 P 0 ;0,1,2=348,3=90.000000
L 6.00894931 2.04348327 6.00688307 2.0454002 1 P 0 ;0,1,2=348,3=90.000000
L 6.00688307 2.0454002 6.0027497 2.04616673 1 P 0 ;0,1,2=348,3=90.000000
L 6.0027497 2.04616673 5.99861634 2.0454002 1 P 0 ;0,1,2=348,3=90.000000
L 5.99861634 2.0454002 5.99603356 2.0431 1 P 0 ;0,1,2=348,3=90.000000
L 5.99603356 2.0431 5.99448287 2.04041654 1 P 0 ;0,1,2=348,3=90.000000
L 5.99448287 2.04041654 5.99448287 2.03083317 1 P 0 ;0,1,2=348,3=90.000000
L 5.99448287 2.04041654 5.9795 2.04616673 1 P 0 ;0,1,2=348,3=90.000000
L 5.98569961 2.06106663 5.98208278 2.06336614 1 P 0 ;0,1,2=348,3=90.000000
L 5.98208278 2.06336614 5.98001654 2.06643287 1 P 0 ;0,1,2=348,3=90.000000
L 5.98001654 2.06643287 5.9795 2.06988356 1 P 0 ;0,1,2=348,3=90.000000
L 5.9795 2.06988356 5.98001654 2.0729503 1 P 0 ;0,1,2=348,3=90.000000
L 5.98001654 2.0729503 5.98259931 2.07601703 1 P 0 ;0,1,2=348,3=90.000000
L 5.98259931 2.07601703 5.98569961 2.07793327 1 P 0 ;0,1,2=348,3=90.000000
L 5.98569961 2.07793327 5.9887999 2.07831654 1 P 0 ;0,1,2=348,3=90.000000
L 5.9887999 2.07831654 5.99241575 2.07755 1 P 0 ;0,1,2=348,3=90.000000
L 5.99241575 2.07755 5.99499951 2.07486654 1 P 0 ;0,1,2=348,3=90.000000
L 5.99499951 2.07486654 5.99603356 2.07218307 1 P 0 ;0,1,2=348,3=90.000000
L 5.99603356 2.07218307 5.99603356 2.06873307 1 P 0 ;0,1,2=348,3=90.000000
L 5.99603356 2.07218307 5.99758317 2.07448327 1 P 0 ;0,1,2=348,3=90.000000
L 5.99758317 2.07448327 6.00016594 2.0764002 1 P 0 ;0,1,2=348,3=90.000000
L 6.00016594 2.0764002 6.00326624 2.07716673 1 P 0 ;0,1,2=348,3=90.000000
L 6.00326624 2.07716673 6.00636654 2.0764002 1 P 0 ;0,1,2=348,3=90.000000
L 6.00636654 2.0764002 6.00894931 2.07448327 1 P 0 ;0,1,2=348,3=90.000000
L 6.00894931 2.07448327 6.0105 2.07103327 1 P 0 ;0,1,2=348,3=90.000000
L 6.0105 2.07103327 6.00998337 2.06758337 1 P 0 ;0,1,2=348,3=90.000000
L 6.00998337 2.06758337 6.00791624 2.06413337 1 P 0 ;0,1,2=348,3=90.000000
L 6.0105 2.10049961 6.00946683 2.09743287 1 P 0 ;0,1,2=348,3=90.000000
L 6.00946683 2.09743287 6.00688307 2.09513337 1 P 0 ;0,1,2=348,3=90.000000
L 6.00688307 2.09513337 6.00378376 2.0935997 1 P 0 ;0,1,2=348,3=90.000000
L 6.00378376 2.0935997 5.99964941 2.0924499 1 P 0 ;0,1,2=348,3=90.000000
L 5.99964941 2.0924499 5.99499951 2.09206663 1 P 0 ;0,1,2=348,3=90.000000
L 5.99499951 2.09206663 5.99034951 2.0924499 1 P 0 ;0,1,2=348,3=90.000000
L 5.99034951 2.0924499 5.98621614 2.0935997 1 P 0 ;0,1,2=348,3=90.000000
L 5.98621614 2.0935997 5.98311585 2.09513337 1 P 0 ;0,1,2=348,3=90.000000
L 5.98311585 2.09513337 5.98053307 2.09743287 1 P 0 ;0,1,2=348,3=90.000000
L 5.98053307 2.09743287 5.9795 2.10049961 1 P 0 ;0,1,2=348,3=90.000000
L 5.9795 2.10049961 5.98053307 2.10356634 1 P 0 ;0,1,2=348,3=90.000000
L 5.98053307 2.10356634 5.98311585 2.10586654 1 P 0 ;0,1,2=348,3=90.000000
L 5.98311585 2.10586654 5.98621614 2.1074002 1 P 0 ;0,1,2=348,3=90.000000
L 5.98621614 2.1074002 5.99034951 2.10855 1 P 0 ;0,1,2=348,3=90.000000
L 5.99034951 2.10855 5.99499951 2.10893327 1 P 0 ;0,1,2=348,3=90.000000
L 5.99499951 2.10893327 5.99964941 2.10855 1 P 0 ;0,1,2=348,3=90.000000
L 5.99964941 2.10855 6.00378376 2.1074002 1 P 0 ;0,1,2=348,3=90.000000
L 6.00378376 2.1074002 6.00688307 2.10586654 1 P 0 ;0,1,2=348,3=90.000000
L 6.00688307 2.10586654 6.00946683 2.10356634 1 P 0 ;0,1,2=348,3=90.000000
L 6.00946683 2.10356634 6.0105 2.10049961 1 P 0 ;0,1,2=348,3=90.000000
L 6.0105 2.13149961 6.00946683 2.12843287 1 P 0 ;0,1,2=348,3=90.000000
L 6.00946683 2.12843287 6.00688307 2.12613337 1 P 0 ;0,1,2=348,3=90.000000
L 6.00688307 2.12613337 6.00378376 2.1245997 1 P 0 ;0,1,2=348,3=90.000000
L 6.00378376 2.1245997 5.99964941 2.1234499 1 P 0 ;0,1,2=348,3=90.000000
L 5.99964941 2.1234499 5.99499951 2.12306663 1 P 0 ;0,1,2=348,3=90.000000
L 5.99499951 2.12306663 5.99034951 2.1234499 1 P 0 ;0,1,2=348,3=90.000000
L 5.99034951 2.1234499 5.98621614 2.1245997 1 P 0 ;0,1,2=348,3=90.000000
L 5.98621614 2.1245997 5.98311585 2.12613337 1 P 0 ;0,1,2=348,3=90.000000
L 5.98311585 2.12613337 5.98053307 2.12843287 1 P 0 ;0,1,2=348,3=90.000000
L 5.98053307 2.12843287 5.9795 2.13149961 1 P 0 ;0,1,2=348,3=90.000000
L 5.9795 2.13149961 5.98053307 2.13456634 1 P 0 ;0,1,2=348,3=90.000000
L 5.98053307 2.13456634 5.98311585 2.13686654 1 P 0 ;0,1,2=348,3=90.000000
L 5.98311585 2.13686654 5.98621614 2.1384002 1 P 0 ;0,1,2=348,3=90.000000
L 5.98621614 2.1384002 5.99034951 2.13955 1 P 0 ;0,1,2=348,3=90.000000
L 5.99034951 2.13955 5.99499951 2.13993327 1 P 0 ;0,1,2=348,3=90.000000
L 5.99499951 2.13993327 5.99964941 2.13955 1 P 0 ;0,1,2=348,3=90.000000
L 5.99964941 2.13955 6.00378376 2.1384002 1 P 0 ;0,1,2=348,3=90.000000
L 6.00378376 2.1384002 6.00688307 2.13686654 1 P 0 ;0,1,2=348,3=90.000000
L 6.00688307 2.13686654 6.00946683 2.13456634 1 P 0 ;0,1,2=348,3=90.000000
L 6.00946683 2.13456634 6.0105 2.13149961 1 P 0 ;0,1,2=348,3=90.000000
L 6.09101998 1.97465 6.09101998 1.88465 1 P 0 
L 6.09101998 1.88465 6.04701998 1.88465 1 P 0 
L 6.04701998 1.88465 6.04701998 1.97465 1 P 0 
L 6.04701998 1.97465 6.09101998 1.97465 1 P 0 
L 6.0495 2.03133317 6.0805 2.03133317 1 P 0 ;0,1,2=349,3=90.000000
L 6.0805 2.03133317 6.0805 2.04091654 1 P 0 ;0,1,2=349,3=90.000000
L 6.0805 2.04091654 6.07894931 2.04398327 1 P 0 ;0,1,2=349,3=90.000000
L 6.07894931 2.04398327 6.07688307 2.0459002 1 P 0 ;0,1,2=349,3=90.000000
L 6.07688307 2.0459002 6.0727497 2.04666673 1 P 0 ;0,1,2=349,3=90.000000
L 6.0727497 2.04666673 6.06861634 2.0459002 1 P 0 ;0,1,2=349,3=90.000000
L 6.06861634 2.0459002 6.06603356 2.0436 1 P 0 ;0,1,2=349,3=90.000000
L 6.06603356 2.0436 6.06448287 2.04091654 1 P 0 ;0,1,2=349,3=90.000000
L 6.06448287 2.04091654 6.06448287 2.03133317 1 P 0 ;0,1,2=349,3=90.000000
L 6.06448287 2.04091654 6.0495 2.04666673 1 P 0 ;0,1,2=349,3=90.000000
L 6.06241575 2.06271644 6.06603356 2.0653999 1 P 0 ;0,1,2=349,3=90.000000
L 6.06603356 2.0653999 6.0680998 2.0677001 1 P 0 ;0,1,2=349,3=90.000000
L 6.0680998 2.0677001 6.06913287 2.07076683 1 P 0 ;0,1,2=349,3=90.000000
L 6.06913287 2.07076683 6.0680998 2.0734503 1 P 0 ;0,1,2=349,3=90.000000
L 6.0680998 2.0734503 6.06603356 2.07536654 1 P 0 ;0,1,2=349,3=90.000000
L 6.06603356 2.07536654 6.06293327 2.0769002 1 P 0 ;0,1,2=349,3=90.000000
L 6.06293327 2.0769002 6.05931644 2.07728346 1 P 0 ;0,1,2=349,3=90.000000
L 6.05931644 2.07728346 6.05621614 2.0769002 1 P 0 ;0,1,2=349,3=90.000000
L 6.05621614 2.0769002 6.05311585 2.07536654 1 P 0 ;0,1,2=349,3=90.000000
L 6.05311585 2.07536654 6.05053307 2.07306634 1 P 0 ;0,1,2=349,3=90.000000
L 6.05053307 2.07306634 6.0495 2.07038356 1 P 0 ;0,1,2=349,3=90.000000
L 6.0495 2.07038356 6.05053307 2.06731683 1 P 0 ;0,1,2=349,3=90.000000
L 6.05053307 2.06731683 6.05363238 2.06463337 1 P 0 ;0,1,2=349,3=90.000000
L 6.05363238 2.06463337 6.05828327 2.0630997 1 P 0 ;0,1,2=349,3=90.000000
L 6.05828327 2.0630997 6.0634498 2.06271644 1 P 0 ;0,1,2=349,3=90.000000
L 6.0634498 2.06271644 6.07016594 2.06348287 1 P 0 ;0,1,2=349,3=90.000000
L 6.07016594 2.06348287 6.07378376 2.06463337 1 P 0 ;0,1,2=349,3=90.000000
L 6.07378376 2.06463337 6.0773997 2.06654961 1 P 0 ;0,1,2=349,3=90.000000
L 6.0773997 2.06654961 6.07998337 2.06923307 1 P 0 ;0,1,2=349,3=90.000000
L 6.07998337 2.06923307 6.0805 2.07191654 1 P 0 ;0,1,2=349,3=90.000000
L 6.0805 2.07191654 6.07946683 2.0746 1 P 0 ;0,1,2=349,3=90.000000
L 6.07946683 2.0746 6.07688307 2.07651703 1 P 0 ;0,1,2=349,3=90.000000
L 6.05414892 2.09256663 6.05156614 2.09486614 1 P 0 ;0,1,2=349,3=90.000000
L 6.05156614 2.09486614 6.05001654 2.09754961 1 P 0 ;0,1,2=349,3=90.000000
L 6.05001654 2.09754961 6.0495 2.10099961 1 P 0 ;0,1,2=349,3=90.000000
L 6.0495 2.10099961 6.05053307 2.1044503 1 P 0 ;0,1,2=349,3=90.000000
L 6.05053307 2.1044503 6.05259931 2.10713307 1 P 0 ;0,1,2=349,3=90.000000
L 6.05259931 2.10713307 6.05621614 2.10905 1 P 0 ;0,1,2=349,3=90.000000
L 6.05621614 2.10905 6.06034951 2.10943327 1 P 0 ;0,1,2=349,3=90.000000
L 6.06034951 2.10943327 6.06448287 2.10866673 1 P 0 ;0,1,2=349,3=90.000000
L 6.06448287 2.10866673 6.06706663 2.1067498 1 P 0 ;0,1,2=349,3=90.000000
L 6.06706663 2.1067498 6.06913287 2.10406634 1 P 0 ;0,1,2=349,3=90.000000
L 6.06913287 2.10406634 6.06964941 2.10138356 1 P 0 ;0,1,2=349,3=90.000000
L 6.06964941 2.10138356 6.06913287 2.0987001 1 P 0 ;0,1,2=349,3=90.000000
L 6.06913287 2.0987001 6.06706663 2.0952501 1 P 0 ;0,1,2=349,3=90.000000
L 6.06706663 2.0952501 6.0805 2.0963999 1 P 0 ;0,1,2=349,3=90.000000
L 6.0805 2.0963999 6.0805 2.1067498 1 P 0 ;0,1,2=349,3=90.000000
L 5.99101998 1.97465 5.99101998 1.88465 1 P 0 
L 5.99101998 1.88465 5.94701998 1.88465 1 P 0 
L 5.94701998 1.88465 5.94701998 1.97465 1 P 0 
L 5.94701998 1.97465 5.99101998 1.97465 1 P 0 
L 5.9145 2.04133317 5.9455 2.04133317 1 P 0 ;0,1,2=350,3=90.000000
L 5.9455 2.04133317 5.9455 2.05091654 1 P 0 ;0,1,2=350,3=90.000000
L 5.9455 2.05091654 5.94394931 2.05398327 1 P 0 ;0,1,2=350,3=90.000000
L 5.94394931 2.05398327 5.94188307 2.0559002 1 P 0 ;0,1,2=350,3=90.000000
L 5.94188307 2.0559002 5.9377497 2.05666673 1 P 0 ;0,1,2=350,3=90.000000
L 5.9377497 2.05666673 5.93361634 2.0559002 1 P 0 ;0,1,2=350,3=90.000000
L 5.93361634 2.0559002 5.93103356 2.0536 1 P 0 ;0,1,2=350,3=90.000000
L 5.93103356 2.0536 5.92948287 2.05091654 1 P 0 ;0,1,2=350,3=90.000000
L 5.92948287 2.05091654 5.92948287 2.04133317 1 P 0 ;0,1,2=350,3=90.000000
L 5.92948287 2.05091654 5.9145 2.05666673 1 P 0 ;0,1,2=350,3=90.000000
L 5.92741575 2.07271644 5.93103356 2.0753999 1 P 0 ;0,1,2=350,3=90.000000
L 5.93103356 2.0753999 5.9330998 2.0777001 1 P 0 ;0,1,2=350,3=90.000000
L 5.9330998 2.0777001 5.93413287 2.08076683 1 P 0 ;0,1,2=350,3=90.000000
L 5.93413287 2.08076683 5.9330998 2.0834503 1 P 0 ;0,1,2=350,3=90.000000
L 5.9330998 2.0834503 5.93103356 2.08536654 1 P 0 ;0,1,2=350,3=90.000000
L 5.93103356 2.08536654 5.92793327 2.0869002 1 P 0 ;0,1,2=350,3=90.000000
L 5.92793327 2.0869002 5.92431644 2.08728346 1 P 0 ;0,1,2=350,3=90.000000
L 5.92431644 2.08728346 5.92121614 2.0869002 1 P 0 ;0,1,2=350,3=90.000000
L 5.92121614 2.0869002 5.91811585 2.08536654 1 P 0 ;0,1,2=350,3=90.000000
L 5.91811585 2.08536654 5.91553307 2.08306634 1 P 0 ;0,1,2=350,3=90.000000
L 5.91553307 2.08306634 5.9145 2.08038356 1 P 0 ;0,1,2=350,3=90.000000
L 5.9145 2.08038356 5.91553307 2.07731683 1 P 0 ;0,1,2=350,3=90.000000
L 5.91553307 2.07731683 5.91863238 2.07463337 1 P 0 ;0,1,2=350,3=90.000000
L 5.91863238 2.07463337 5.92328327 2.0730997 1 P 0 ;0,1,2=350,3=90.000000
L 5.92328327 2.0730997 5.9284498 2.07271644 1 P 0 ;0,1,2=350,3=90.000000
L 5.9284498 2.07271644 5.93516594 2.07348287 1 P 0 ;0,1,2=350,3=90.000000
L 5.93516594 2.07348287 5.93878376 2.07463337 1 P 0 ;0,1,2=350,3=90.000000
L 5.93878376 2.07463337 5.9423997 2.07654961 1 P 0 ;0,1,2=350,3=90.000000
L 5.9423997 2.07654961 5.94498337 2.07923307 1 P 0 ;0,1,2=350,3=90.000000
L 5.94498337 2.07923307 5.9455 2.08191654 1 P 0 ;0,1,2=350,3=90.000000
L 5.9455 2.08191654 5.94446683 2.0846 1 P 0 ;0,1,2=350,3=90.000000
L 5.94446683 2.0846 5.94188307 2.08651703 1 P 0 ;0,1,2=350,3=90.000000
L 5.91811585 2.10448287 5.91553307 2.10716634 1 P 0 ;0,1,2=350,3=90.000000
L 5.91553307 2.10716634 5.9145 2.11023307 1 P 0 ;0,1,2=350,3=90.000000
L 5.9145 2.11023307 5.91553307 2.1132998 1 P 0 ;0,1,2=350,3=90.000000
L 5.91553307 2.1132998 5.91863238 2.11598327 1 P 0 ;0,1,2=350,3=90.000000
L 5.91863238 2.11598327 5.92328327 2.1179002 1 P 0 ;0,1,2=350,3=90.000000
L 5.92328327 2.1179002 5.92793327 2.11866673 1 P 0 ;0,1,2=350,3=90.000000
L 5.92793327 2.11866673 5.93361634 2.11866673 1 P 0 ;0,1,2=350,3=90.000000
L 5.93361634 2.11866673 5.93826624 2.1179002 1 P 0 ;0,1,2=350,3=90.000000
L 5.93826624 2.1179002 5.9423997 2.11598327 1 P 0 ;0,1,2=350,3=90.000000
L 5.9423997 2.11598327 5.94446683 2.11368307 1 P 0 ;0,1,2=350,3=90.000000
L 5.94446683 2.11368307 5.9455 2.11099961 1 P 0 ;0,1,2=350,3=90.000000
L 5.9455 2.11099961 5.94446683 2.10793287 1 P 0 ;0,1,2=350,3=90.000000
L 5.94446683 2.10793287 5.9423997 2.10563337 1 P 0 ;0,1,2=350,3=90.000000
L 5.9423997 2.10563337 5.9393003 2.1040997 1 P 0 ;0,1,2=350,3=90.000000
L 5.9393003 2.1040997 5.93516594 2.10333317 1 P 0 ;0,1,2=350,3=90.000000
L 5.93516594 2.10333317 5.9315501 2.1040997 1 P 0 ;0,1,2=350,3=90.000000
L 5.9315501 2.1040997 5.92793327 2.10601663 1 P 0 ;0,1,2=350,3=90.000000
L 5.92793327 2.10601663 5.92586604 2.10831683 1 P 0 ;0,1,2=350,3=90.000000
L 5.92586604 2.10831683 5.92534951 2.11099961 1 P 0 ;0,1,2=350,3=90.000000
L 5.92534951 2.11099961 5.92638268 2.11406634 1 P 0 ;0,1,2=350,3=90.000000
L 5.92638268 2.11406634 5.92896634 2.11636654 1 P 0 ;0,1,2=350,3=90.000000
L 5.92896634 2.11636654 5.93361634 2.11866673 1 P 0 ;0,1,2=350,3=90.000000
L 5.94101998 1.97465 5.94101998 1.88465 1 P 0 
L 5.89701998 1.88465 5.89701998 1.97465 1 P 0 
L 5.89701998 1.97465 5.94101998 1.97465 1 P 0 
L 5.94101998 1.88465 5.89701998 1.88465 1 P 0 
L 5.8745 2.04133317 5.9055 2.04133317 1 P 0 ;0,1,2=351,3=90.000000
L 5.9055 2.04133317 5.9055 2.05091654 1 P 0 ;0,1,2=351,3=90.000000
L 5.9055 2.05091654 5.90394931 2.05398327 1 P 0 ;0,1,2=351,3=90.000000
L 5.90394931 2.05398327 5.90188307 2.0559002 1 P 0 ;0,1,2=351,3=90.000000
L 5.90188307 2.0559002 5.8977497 2.05666673 1 P 0 ;0,1,2=351,3=90.000000
L 5.8977497 2.05666673 5.89361634 2.0559002 1 P 0 ;0,1,2=351,3=90.000000
L 5.89361634 2.0559002 5.89103356 2.0536 1 P 0 ;0,1,2=351,3=90.000000
L 5.89103356 2.0536 5.88948287 2.05091654 1 P 0 ;0,1,2=351,3=90.000000
L 5.88948287 2.05091654 5.88948287 2.04133317 1 P 0 ;0,1,2=351,3=90.000000
L 5.88948287 2.05091654 5.8745 2.05666673 1 P 0 ;0,1,2=351,3=90.000000
L 5.88741575 2.07271644 5.89103356 2.0753999 1 P 0 ;0,1,2=351,3=90.000000
L 5.89103356 2.0753999 5.8930998 2.0777001 1 P 0 ;0,1,2=351,3=90.000000
L 5.8930998 2.0777001 5.89413287 2.08076683 1 P 0 ;0,1,2=351,3=90.000000
L 5.89413287 2.08076683 5.8930998 2.0834503 1 P 0 ;0,1,2=351,3=90.000000
L 5.8930998 2.0834503 5.89103356 2.08536654 1 P 0 ;0,1,2=351,3=90.000000
L 5.89103356 2.08536654 5.88793327 2.0869002 1 P 0 ;0,1,2=351,3=90.000000
L 5.88793327 2.0869002 5.88431644 2.08728346 1 P 0 ;0,1,2=351,3=90.000000
L 5.88431644 2.08728346 5.88121614 2.0869002 1 P 0 ;0,1,2=351,3=90.000000
L 5.88121614 2.0869002 5.87811585 2.08536654 1 P 0 ;0,1,2=351,3=90.000000
L 5.87811585 2.08536654 5.87553307 2.08306634 1 P 0 ;0,1,2=351,3=90.000000
L 5.87553307 2.08306634 5.8745 2.08038356 1 P 0 ;0,1,2=351,3=90.000000
L 5.8745 2.08038356 5.87553307 2.07731683 1 P 0 ;0,1,2=351,3=90.000000
L 5.87553307 2.07731683 5.87863238 2.07463337 1 P 0 ;0,1,2=351,3=90.000000
L 5.87863238 2.07463337 5.88328327 2.0730997 1 P 0 ;0,1,2=351,3=90.000000
L 5.88328327 2.0730997 5.8884498 2.07271644 1 P 0 ;0,1,2=351,3=90.000000
L 5.8884498 2.07271644 5.89516594 2.07348287 1 P 0 ;0,1,2=351,3=90.000000
L 5.89516594 2.07348287 5.89878376 2.07463337 1 P 0 ;0,1,2=351,3=90.000000
L 5.89878376 2.07463337 5.9023997 2.07654961 1 P 0 ;0,1,2=351,3=90.000000
L 5.9023997 2.07654961 5.90498337 2.07923307 1 P 0 ;0,1,2=351,3=90.000000
L 5.90498337 2.07923307 5.9055 2.08191654 1 P 0 ;0,1,2=351,3=90.000000
L 5.9055 2.08191654 5.90446683 2.0846 1 P 0 ;0,1,2=351,3=90.000000
L 5.90446683 2.0846 5.90188307 2.08651703 1 P 0 ;0,1,2=351,3=90.000000
L 5.8745 2.1156 5.9055 2.1156 1 P 0 ;0,1,2=351,3=90.000000
L 5.9055 2.1156 5.88328327 2.10141624 1 P 0 ;0,1,2=351,3=90.000000
L 5.88328327 2.10141624 5.88328327 2.12058366 1 P 0 ;0,1,2=351,3=90.000000
L 4.015 2.576 4.059 2.576 1 P 0 
L 4.059 2.576 4.059 2.486 1 P 0 
L 4.059 2.486 4.015 2.486 1 P 0 
L 4.015 2.486 4.015 2.576 1 P 0 
L 4.0195 2.61583317 4.0505 2.61583317 1 P 0 ;0,1,2=352,3=90.000000
L 4.0505 2.61583317 4.0505 2.62541654 1 P 0 ;0,1,2=352,3=90.000000
L 4.0505 2.62541654 4.04894931 2.62848327 1 P 0 ;0,1,2=352,3=90.000000
L 4.04894931 2.62848327 4.04688307 2.6304002 1 P 0 ;0,1,2=352,3=90.000000
L 4.04688307 2.6304002 4.0427497 2.63116673 1 P 0 ;0,1,2=352,3=90.000000
L 4.0427497 2.63116673 4.03861634 2.6304002 1 P 0 ;0,1,2=352,3=90.000000
L 4.03861634 2.6304002 4.03603356 2.6281 1 P 0 ;0,1,2=352,3=90.000000
L 4.03603356 2.6281 4.03448287 2.62541654 1 P 0 ;0,1,2=352,3=90.000000
L 4.03448287 2.62541654 4.03448287 2.61583317 1 P 0 ;0,1,2=352,3=90.000000
L 4.03448287 2.62541654 4.0195 2.63116673 1 P 0 ;0,1,2=352,3=90.000000
L 4.04533346 2.64721644 4.04843278 2.64951663 1 P 0 ;0,1,2=352,3=90.000000
L 4.04843278 2.64951663 4.04998337 2.6522001 1 P 0 ;0,1,2=352,3=90.000000
L 4.04998337 2.6522001 4.0505 2.65526683 1 P 0 ;0,1,2=352,3=90.000000
L 4.0505 2.65526683 4.04946683 2.6591 1 P 0 ;0,1,2=352,3=90.000000
L 4.04946683 2.6591 4.04688307 2.66178346 1 P 0 ;0,1,2=352,3=90.000000
L 4.04688307 2.66178346 4.04378376 2.66255 1 P 0 ;0,1,2=352,3=90.000000
L 4.04378376 2.66255 4.04068258 2.66216673 1 P 0 ;0,1,2=352,3=90.000000
L 4.04068258 2.66216673 4.0380998 2.66063307 1 P 0 ;0,1,2=352,3=90.000000
L 4.0380998 2.66063307 4.03293327 2.65296663 1 P 0 ;0,1,2=352,3=90.000000
L 4.03293327 2.65296663 4.02931644 2.64951663 1 P 0 ;0,1,2=352,3=90.000000
L 4.02931644 2.64951663 4.02414892 2.64721644 1 P 0 ;0,1,2=352,3=90.000000
L 4.02414892 2.64721644 4.0195 2.6464499 1 P 0 ;0,1,2=352,3=90.000000
L 4.0195 2.6464499 4.0195 2.66255 1 P 0 ;0,1,2=352,3=90.000000
L 4.02311585 2.67898287 4.02053307 2.68166634 1 P 0 ;0,1,2=352,3=90.000000
L 4.02053307 2.68166634 4.0195 2.68473307 1 P 0 ;0,1,2=352,3=90.000000
L 4.0195 2.68473307 4.02053307 2.6877998 1 P 0 ;0,1,2=352,3=90.000000
L 4.02053307 2.6877998 4.02363238 2.69048327 1 P 0 ;0,1,2=352,3=90.000000
L 4.02363238 2.69048327 4.02828327 2.6924002 1 P 0 ;0,1,2=352,3=90.000000
L 4.02828327 2.6924002 4.03293327 2.69316673 1 P 0 ;0,1,2=352,3=90.000000
L 4.03293327 2.69316673 4.03861634 2.69316673 1 P 0 ;0,1,2=352,3=90.000000
L 4.03861634 2.69316673 4.04326624 2.6924002 1 P 0 ;0,1,2=352,3=90.000000
L 4.04326624 2.6924002 4.0473997 2.69048327 1 P 0 ;0,1,2=352,3=90.000000
L 4.0473997 2.69048327 4.04946683 2.68818307 1 P 0 ;0,1,2=352,3=90.000000
L 4.04946683 2.68818307 4.0505 2.68549961 1 P 0 ;0,1,2=352,3=90.000000
L 4.0505 2.68549961 4.04946683 2.68243287 1 P 0 ;0,1,2=352,3=90.000000
L 4.04946683 2.68243287 4.0473997 2.68013337 1 P 0 ;0,1,2=352,3=90.000000
L 4.0473997 2.68013337 4.0443003 2.6785997 1 P 0 ;0,1,2=352,3=90.000000
L 4.0443003 2.6785997 4.04016594 2.67783317 1 P 0 ;0,1,2=352,3=90.000000
L 4.04016594 2.67783317 4.0365501 2.6785997 1 P 0 ;0,1,2=352,3=90.000000
L 4.0365501 2.6785997 4.03293327 2.68051663 1 P 0 ;0,1,2=352,3=90.000000
L 4.03293327 2.68051663 4.03086604 2.68281683 1 P 0 ;0,1,2=352,3=90.000000
L 4.03086604 2.68281683 4.03034951 2.68549961 1 P 0 ;0,1,2=352,3=90.000000
L 4.03034951 2.68549961 4.03138268 2.68856634 1 P 0 ;0,1,2=352,3=90.000000
L 4.03138268 2.68856634 4.03396634 2.69086654 1 P 0 ;0,1,2=352,3=90.000000
L 4.03396634 2.69086654 4.03861634 2.69316673 1 P 0 ;0,1,2=352,3=90.000000
L 4.02569961 2.70806663 4.02208278 2.71036614 1 P 0 ;0,1,2=352,3=90.000000
L 4.02208278 2.71036614 4.02001654 2.71343287 1 P 0 ;0,1,2=352,3=90.000000
L 4.02001654 2.71343287 4.0195 2.71688356 1 P 0 ;0,1,2=352,3=90.000000
L 4.0195 2.71688356 4.02001654 2.7199503 1 P 0 ;0,1,2=352,3=90.000000
L 4.02001654 2.7199503 4.02259931 2.72301703 1 P 0 ;0,1,2=352,3=90.000000
L 4.02259931 2.72301703 4.02569961 2.72493327 1 P 0 ;0,1,2=352,3=90.000000
L 4.02569961 2.72493327 4.0287999 2.72531654 1 P 0 ;0,1,2=352,3=90.000000
L 4.0287999 2.72531654 4.03241575 2.72455 1 P 0 ;0,1,2=352,3=90.000000
L 4.03241575 2.72455 4.03499951 2.72186654 1 P 0 ;0,1,2=352,3=90.000000
L 4.03499951 2.72186654 4.03603356 2.71918307 1 P 0 ;0,1,2=352,3=90.000000
L 4.03603356 2.71918307 4.03603356 2.71573307 1 P 0 ;0,1,2=352,3=90.000000
L 4.03603356 2.71918307 4.03758317 2.72148327 1 P 0 ;0,1,2=352,3=90.000000
L 4.03758317 2.72148327 4.04016594 2.7234002 1 P 0 ;0,1,2=352,3=90.000000
L 4.04016594 2.7234002 4.04326624 2.72416673 1 P 0 ;0,1,2=352,3=90.000000
L 4.04326624 2.72416673 4.04636654 2.7234002 1 P 0 ;0,1,2=352,3=90.000000
L 4.04636654 2.7234002 4.04894931 2.72148327 1 P 0 ;0,1,2=352,3=90.000000
L 4.04894931 2.72148327 4.0505 2.71803327 1 P 0 ;0,1,2=352,3=90.000000
L 4.0505 2.71803327 4.04998337 2.71458337 1 P 0 ;0,1,2=352,3=90.000000
L 4.04998337 2.71458337 4.04791624 2.71113337 1 P 0 ;0,1,2=352,3=90.000000
L 1.302 3.16 1.302 3.07 1 P 0 
L 1.302 3.07 1.258 3.07 1 P 0 
L 1.258 3.07 1.258 3.16 1 P 0 
L 1.258 3.16 1.302 3.16 1 P 0 
L 1.3095 3.07083317 1.3405 3.07083317 1 P 0 ;0,1,2=353,3=90.000000
L 1.3405 3.07083317 1.3405 3.08041654 1 P 0 ;0,1,2=353,3=90.000000
L 1.3405 3.08041654 1.33894931 3.08348327 1 P 0 ;0,1,2=353,3=90.000000
L 1.33894931 3.08348327 1.33688307 3.0854002 1 P 0 ;0,1,2=353,3=90.000000
L 1.33688307 3.0854002 1.3327497 3.08616673 1 P 0 ;0,1,2=353,3=90.000000
L 1.3327497 3.08616673 1.32861634 3.0854002 1 P 0 ;0,1,2=353,3=90.000000
L 1.32861634 3.0854002 1.32603356 3.0831 1 P 0 ;0,1,2=353,3=90.000000
L 1.32603356 3.0831 1.32448287 3.08041654 1 P 0 ;0,1,2=353,3=90.000000
L 1.32448287 3.08041654 1.32448287 3.07083317 1 P 0 ;0,1,2=353,3=90.000000
L 1.32448287 3.08041654 1.3095 3.08616673 1 P 0 ;0,1,2=353,3=90.000000
L 1.3095 3.10949961 1.3405 3.10949961 1 P 0 ;0,1,2=353,3=90.000000
L 1.3405 3.10949961 1.3343003 3.1048999 1 P 0 ;0,1,2=353,3=90.000000
L 1.3095 3.1048999 1.3095 3.11409931 1 P 0 ;0,1,2=353,3=90.000000
L 1.31569961 3.13206663 1.31208278 3.13436614 1 P 0 ;0,1,2=353,3=90.000000
L 1.31208278 3.13436614 1.31001654 3.13743287 1 P 0 ;0,1,2=353,3=90.000000
L 1.31001654 3.13743287 1.3095 3.14088356 1 P 0 ;0,1,2=353,3=90.000000
L 1.3095 3.14088356 1.31001654 3.1439503 1 P 0 ;0,1,2=353,3=90.000000
L 1.31001654 3.1439503 1.31259931 3.14701703 1 P 0 ;0,1,2=353,3=90.000000
L 1.31259931 3.14701703 1.31569961 3.14893327 1 P 0 ;0,1,2=353,3=90.000000
L 1.31569961 3.14893327 1.3187999 3.14931654 1 P 0 ;0,1,2=353,3=90.000000
L 1.3187999 3.14931654 1.32241575 3.14855 1 P 0 ;0,1,2=353,3=90.000000
L 1.32241575 3.14855 1.32499951 3.14586654 1 P 0 ;0,1,2=353,3=90.000000
L 1.32499951 3.14586654 1.32603356 3.14318307 1 P 0 ;0,1,2=353,3=90.000000
L 1.32603356 3.14318307 1.32603356 3.13973307 1 P 0 ;0,1,2=353,3=90.000000
L 1.32603356 3.14318307 1.32758317 3.14548327 1 P 0 ;0,1,2=353,3=90.000000
L 1.32758317 3.14548327 1.33016594 3.1474002 1 P 0 ;0,1,2=353,3=90.000000
L 1.33016594 3.1474002 1.33326624 3.14816673 1 P 0 ;0,1,2=353,3=90.000000
L 1.33326624 3.14816673 1.33636654 3.1474002 1 P 0 ;0,1,2=353,3=90.000000
L 1.33636654 3.1474002 1.33894931 3.14548327 1 P 0 ;0,1,2=353,3=90.000000
L 1.33894931 3.14548327 1.3405 3.14203327 1 P 0 ;0,1,2=353,3=90.000000
L 1.3405 3.14203327 1.33998337 3.13858337 1 P 0 ;0,1,2=353,3=90.000000
L 1.33998337 3.13858337 1.33791624 3.13513337 1 P 0 ;0,1,2=353,3=90.000000
L 1.3095 3.17149961 1.3405 3.17149961 1 P 0 ;0,1,2=353,3=90.000000
L 1.3405 3.17149961 1.3343003 3.1668999 1 P 0 ;0,1,2=353,3=90.000000
L 1.3095 3.1668999 1.3095 3.17609931 1 P 0 ;0,1,2=353,3=90.000000
L 1.405 3.257 1.405 3.213 1 P 0 
L 1.315 3.257 1.405 3.257 1 P 0 
L 1.405 3.213 1.315 3.213 1 P 0 
L 1.315 3.213 1.315 3.257 1 P 0 
L 1.39916683 3.3145 1.39916683 3.3455 1 P 0 ;0,1,2=354,3=0.000000
L 1.39916683 3.3455 1.38958346 3.3455 1 P 0 ;0,1,2=354,3=0.000000
L 1.38958346 3.3455 1.38651673 3.34394931 1 P 0 ;0,1,2=354,3=0.000000
L 1.38651673 3.34394931 1.3845998 3.34188307 1 P 0 ;0,1,2=354,3=0.000000
L 1.3845998 3.34188307 1.38383327 3.3377497 1 P 0 ;0,1,2=354,3=0.000000
L 1.38383327 3.3377497 1.3845998 3.33361634 1 P 0 ;0,1,2=354,3=0.000000
L 1.3845998 3.33361634 1.3869 3.33103356 1 P 0 ;0,1,2=354,3=0.000000
L 1.3869 3.33103356 1.38958346 3.32948287 1 P 0 ;0,1,2=354,3=0.000000
L 1.38958346 3.32948287 1.39916683 3.32948287 1 P 0 ;0,1,2=354,3=0.000000
L 1.38958346 3.32948287 1.38383327 3.3145 1 P 0 ;0,1,2=354,3=0.000000
L 1.36893337 3.32069961 1.36663386 3.31708278 1 P 0 ;0,1,2=354,3=0.000000
L 1.36663386 3.31708278 1.36356713 3.31501654 1 P 0 ;0,1,2=354,3=0.000000
L 1.36356713 3.31501654 1.36011644 3.3145 1 P 0 ;0,1,2=354,3=0.000000
L 1.36011644 3.3145 1.3570497 3.31501654 1 P 0 ;0,1,2=354,3=0.000000
L 1.3570497 3.31501654 1.35398297 3.31759931 1 P 0 ;0,1,2=354,3=0.000000
L 1.35398297 3.31759931 1.35206673 3.32069961 1 P 0 ;0,1,2=354,3=0.000000
L 1.35206673 3.32069961 1.35168346 3.3237999 1 P 0 ;0,1,2=354,3=0.000000
L 1.35168346 3.3237999 1.35245 3.32741575 1 P 0 ;0,1,2=354,3=0.000000
L 1.35245 3.32741575 1.35513346 3.32999951 1 P 0 ;0,1,2=354,3=0.000000
L 1.35513346 3.32999951 1.35781693 3.33103356 1 P 0 ;0,1,2=354,3=0.000000
L 1.35781693 3.33103356 1.36126693 3.33103356 1 P 0 ;0,1,2=354,3=0.000000
L 1.35781693 3.33103356 1.35551673 3.33258317 1 P 0 ;0,1,2=354,3=0.000000
L 1.35551673 3.33258317 1.3535998 3.33516594 1 P 0 ;0,1,2=354,3=0.000000
L 1.3535998 3.33516594 1.35283327 3.33826624 1 P 0 ;0,1,2=354,3=0.000000
L 1.35283327 3.33826624 1.3535998 3.34136654 1 P 0 ;0,1,2=354,3=0.000000
L 1.3535998 3.34136654 1.35551673 3.34394931 1 P 0 ;0,1,2=354,3=0.000000
L 1.35551673 3.34394931 1.35896673 3.3455 1 P 0 ;0,1,2=354,3=0.000000
L 1.35896673 3.3455 1.36241663 3.34498337 1 P 0 ;0,1,2=354,3=0.000000
L 1.36241663 3.34498337 1.36586663 3.34291624 1 P 0 ;0,1,2=354,3=0.000000
L 1.3249 3.3145 1.3249 3.3455 1 P 0 ;0,1,2=354,3=0.000000
L 1.3249 3.3455 1.33908376 3.32328327 1 P 0 ;0,1,2=354,3=0.000000
L 1.33908376 3.32328327 1.31991634 3.32328327 1 P 0 ;0,1,2=354,3=0.000000
L 1.30501713 3.31811585 1.30233366 3.31553307 1 P 0 ;0,1,2=354,3=0.000000
L 1.30233366 3.31553307 1.29926693 3.3145 1 P 0 ;0,1,2=354,3=0.000000
L 1.29926693 3.3145 1.2962002 3.31553307 1 P 0 ;0,1,2=354,3=0.000000
L 1.2962002 3.31553307 1.29351673 3.31863238 1 P 0 ;0,1,2=354,3=0.000000
L 1.29351673 3.31863238 1.2915998 3.32328327 1 P 0 ;0,1,2=354,3=0.000000
L 1.2915998 3.32328327 1.29083327 3.32793327 1 P 0 ;0,1,2=354,3=0.000000
L 1.29083327 3.32793327 1.29083327 3.33361634 1 P 0 ;0,1,2=354,3=0.000000
L 1.29083327 3.33361634 1.2915998 3.33826624 1 P 0 ;0,1,2=354,3=0.000000
L 1.2915998 3.33826624 1.29351673 3.3423997 1 P 0 ;0,1,2=354,3=0.000000
L 1.29351673 3.3423997 1.29581693 3.34446683 1 P 0 ;0,1,2=354,3=0.000000
L 1.29581693 3.34446683 1.29850039 3.3455 1 P 0 ;0,1,2=354,3=0.000000
L 1.29850039 3.3455 1.30156713 3.34446683 1 P 0 ;0,1,2=354,3=0.000000
L 1.30156713 3.34446683 1.30386663 3.3423997 1 P 0 ;0,1,2=354,3=0.000000
L 1.30386663 3.3423997 1.3054003 3.3393003 1 P 0 ;0,1,2=354,3=0.000000
L 1.3054003 3.3393003 1.30616683 3.33516594 1 P 0 ;0,1,2=354,3=0.000000
L 1.30616683 3.33516594 1.3054003 3.3315501 1 P 0 ;0,1,2=354,3=0.000000
L 1.3054003 3.3315501 1.30348337 3.32793327 1 P 0 ;0,1,2=354,3=0.000000
L 1.30348337 3.32793327 1.30118317 3.32586604 1 P 0 ;0,1,2=354,3=0.000000
L 1.30118317 3.32586604 1.29850039 3.32534951 1 P 0 ;0,1,2=354,3=0.000000
L 1.29850039 3.32534951 1.29543366 3.32638268 1 P 0 ;0,1,2=354,3=0.000000
L 1.29543366 3.32638268 1.29313346 3.32896634 1 P 0 ;0,1,2=354,3=0.000000
L 1.29313346 3.32896634 1.29083327 3.33361634 1 P 0 ;0,1,2=354,3=0.000000
L 1.405 3.302 1.405 3.258 1 P 0 
L 1.315 3.302 1.405 3.302 1 P 0 
L 1.405 3.258 1.315 3.258 1 P 0 
L 1.315 3.258 1.315 3.302 1 P 0 
L 1.39916683 3.3595 1.39916683 3.3905 1 P 0 ;0,1,2=355,3=0.000000
L 1.39916683 3.3905 1.38958346 3.3905 1 P 0 ;0,1,2=355,3=0.000000
L 1.38958346 3.3905 1.38651673 3.38894931 1 P 0 ;0,1,2=355,3=0.000000
L 1.38651673 3.38894931 1.3845998 3.38688307 1 P 0 ;0,1,2=355,3=0.000000
L 1.3845998 3.38688307 1.38383327 3.3827497 1 P 0 ;0,1,2=355,3=0.000000
L 1.38383327 3.3827497 1.3845998 3.37861634 1 P 0 ;0,1,2=355,3=0.000000
L 1.3845998 3.37861634 1.3869 3.37603356 1 P 0 ;0,1,2=355,3=0.000000
L 1.3869 3.37603356 1.38958346 3.37448287 1 P 0 ;0,1,2=355,3=0.000000
L 1.38958346 3.37448287 1.39916683 3.37448287 1 P 0 ;0,1,2=355,3=0.000000
L 1.38958346 3.37448287 1.38383327 3.3595 1 P 0 ;0,1,2=355,3=0.000000
L 1.36050039 3.3595 1.36050039 3.3905 1 P 0 ;0,1,2=355,3=0.000000
L 1.36050039 3.3905 1.3651001 3.3843003 1 P 0 ;0,1,2=355,3=0.000000
L 1.3651001 3.3595 1.35590069 3.3595 1 P 0 ;0,1,2=355,3=0.000000
L 1.33793337 3.36569961 1.33563386 3.36208278 1 P 0 ;0,1,2=355,3=0.000000
L 1.33563386 3.36208278 1.33256713 3.36001654 1 P 0 ;0,1,2=355,3=0.000000
L 1.33256713 3.36001654 1.32911644 3.3595 1 P 0 ;0,1,2=355,3=0.000000
L 1.32911644 3.3595 1.3260497 3.36001654 1 P 0 ;0,1,2=355,3=0.000000
L 1.3260497 3.36001654 1.32298297 3.36259931 1 P 0 ;0,1,2=355,3=0.000000
L 1.32298297 3.36259931 1.32106673 3.36569961 1 P 0 ;0,1,2=355,3=0.000000
L 1.32106673 3.36569961 1.32068346 3.3687999 1 P 0 ;0,1,2=355,3=0.000000
L 1.32068346 3.3687999 1.32145 3.37241575 1 P 0 ;0,1,2=355,3=0.000000
L 1.32145 3.37241575 1.32413346 3.37499951 1 P 0 ;0,1,2=355,3=0.000000
L 1.32413346 3.37499951 1.32681693 3.37603356 1 P 0 ;0,1,2=355,3=0.000000
L 1.32681693 3.37603356 1.33026693 3.37603356 1 P 0 ;0,1,2=355,3=0.000000
L 1.32681693 3.37603356 1.32451673 3.37758317 1 P 0 ;0,1,2=355,3=0.000000
L 1.32451673 3.37758317 1.3225998 3.38016594 1 P 0 ;0,1,2=355,3=0.000000
L 1.3225998 3.38016594 1.32183327 3.38326624 1 P 0 ;0,1,2=355,3=0.000000
L 1.32183327 3.38326624 1.3225998 3.38636654 1 P 0 ;0,1,2=355,3=0.000000
L 1.3225998 3.38636654 1.32451673 3.38894931 1 P 0 ;0,1,2=355,3=0.000000
L 1.32451673 3.38894931 1.32796673 3.3905 1 P 0 ;0,1,2=355,3=0.000000
L 1.32796673 3.3905 1.33141663 3.38998337 1 P 0 ;0,1,2=355,3=0.000000
L 1.33141663 3.38998337 1.33486663 3.38791624 1 P 0 ;0,1,2=355,3=0.000000
L 1.30578356 3.38533346 1.30348337 3.38843278 1 P 0 ;0,1,2=355,3=0.000000
L 1.30348337 3.38843278 1.3007999 3.38998337 1 P 0 ;0,1,2=355,3=0.000000
L 1.3007999 3.38998337 1.29773317 3.3905 1 P 0 ;0,1,2=355,3=0.000000
L 1.29773317 3.3905 1.2939 3.38946683 1 P 0 ;0,1,2=355,3=0.000000
L 1.2939 3.38946683 1.29121654 3.38688307 1 P 0 ;0,1,2=355,3=0.000000
L 1.29121654 3.38688307 1.29045 3.38378376 1 P 0 ;0,1,2=355,3=0.000000
L 1.29045 3.38378376 1.29083327 3.38068258 1 P 0 ;0,1,2=355,3=0.000000
L 1.29083327 3.38068258 1.29236693 3.3780998 1 P 0 ;0,1,2=355,3=0.000000
L 1.29236693 3.3780998 1.30003337 3.37293327 1 P 0 ;0,1,2=355,3=0.000000
L 1.30003337 3.37293327 1.30348337 3.36931644 1 P 0 ;0,1,2=355,3=0.000000
L 1.30348337 3.36931644 1.30578356 3.36414892 1 P 0 ;0,1,2=355,3=0.000000
L 1.30578356 3.36414892 1.3065501 3.3595 1 P 0 ;0,1,2=355,3=0.000000
L 1.3065501 3.3595 1.29045 3.3595 1 P 0 ;0,1,2=355,3=0.000000
L 3.313 2.577 3.357 2.577 1 P 0 
L 3.357 2.577 3.357 2.487 1 P 0 
L 3.357 2.487 3.313 2.487 1 P 0 
L 3.313 2.487 3.313 2.577 1 P 0 
L 3.3645 2.48133317 3.3955 2.48133317 1 P 0 ;0,1,2=356,3=90.000000
L 3.3955 2.48133317 3.3955 2.49091654 1 P 0 ;0,1,2=356,3=90.000000
L 3.3955 2.49091654 3.39394931 2.49398327 1 P 0 ;0,1,2=356,3=90.000000
L 3.39394931 2.49398327 3.39188307 2.4959002 1 P 0 ;0,1,2=356,3=90.000000
L 3.39188307 2.4959002 3.3877497 2.49666673 1 P 0 ;0,1,2=356,3=90.000000
L 3.3877497 2.49666673 3.38361634 2.4959002 1 P 0 ;0,1,2=356,3=90.000000
L 3.38361634 2.4959002 3.38103356 2.4936 1 P 0 ;0,1,2=356,3=90.000000
L 3.38103356 2.4936 3.37948287 2.49091654 1 P 0 ;0,1,2=356,3=90.000000
L 3.37948287 2.49091654 3.37948287 2.48133317 1 P 0 ;0,1,2=356,3=90.000000
L 3.37948287 2.49091654 3.3645 2.49666673 1 P 0 ;0,1,2=356,3=90.000000
L 3.3645 2.51999961 3.36501654 2.52268307 1 P 0 ;0,1,2=356,3=90.000000
L 3.36501654 2.52268307 3.36656614 2.5257498 1 P 0 ;0,1,2=356,3=90.000000
L 3.36656614 2.5257498 3.36914892 2.52766673 1 P 0 ;0,1,2=356,3=90.000000
L 3.36914892 2.52766673 3.37276673 2.52843327 1 P 0 ;0,1,2=356,3=90.000000
L 3.37276673 2.52843327 3.37638268 2.52766673 1 P 0 ;0,1,2=356,3=90.000000
L 3.37638268 2.52766673 3.37948287 2.52536654 1 P 0 ;0,1,2=356,3=90.000000
L 3.37948287 2.52536654 3.38103356 2.52191654 1 P 0 ;0,1,2=356,3=90.000000
L 3.38103356 2.52191654 3.38103356 2.51808337 1 P 0 ;0,1,2=356,3=90.000000
L 3.38103356 2.51808337 3.38206663 2.51578317 1 P 0 ;0,1,2=356,3=90.000000
L 3.38206663 2.51578317 3.38464941 2.51386614 1 P 0 ;0,1,2=356,3=90.000000
L 3.38464941 2.51386614 3.38826624 2.5130997 1 P 0 ;0,1,2=356,3=90.000000
L 3.38826624 2.5130997 3.39188307 2.5142501 1 P 0 ;0,1,2=356,3=90.000000
L 3.39188307 2.5142501 3.39446683 2.51693287 1 P 0 ;0,1,2=356,3=90.000000
L 3.39446683 2.51693287 3.3955 2.51999961 1 P 0 ;0,1,2=356,3=90.000000
L 3.3955 2.51999961 3.39446683 2.52306634 1 P 0 ;0,1,2=356,3=90.000000
L 3.39446683 2.52306634 3.39188307 2.5257498 1 P 0 ;0,1,2=356,3=90.000000
L 3.39188307 2.5257498 3.38826624 2.5269002 1 P 0 ;0,1,2=356,3=90.000000
L 3.38826624 2.5269002 3.38464941 2.52613307 1 P 0 ;0,1,2=356,3=90.000000
L 3.38464941 2.52613307 3.38206663 2.52421673 1 P 0 ;0,1,2=356,3=90.000000
L 3.38206663 2.52421673 3.38103356 2.52191654 1 P 0 ;0,1,2=356,3=90.000000
L 3.38103356 2.52191654 3.38103356 2.51808337 1 P 0 ;0,1,2=356,3=90.000000
L 3.38103356 2.51808337 3.37948287 2.51463337 1 P 0 ;0,1,2=356,3=90.000000
L 3.37948287 2.51463337 3.37638268 2.51233317 1 P 0 ;0,1,2=356,3=90.000000
L 3.37638268 2.51233317 3.37276673 2.51156663 1 P 0 ;0,1,2=356,3=90.000000
L 3.37276673 2.51156663 3.36914892 2.51233317 1 P 0 ;0,1,2=356,3=90.000000
L 3.36914892 2.51233317 3.36656614 2.5142501 1 P 0 ;0,1,2=356,3=90.000000
L 3.36656614 2.5142501 3.36501654 2.51731683 1 P 0 ;0,1,2=356,3=90.000000
L 3.36501654 2.51731683 3.3645 2.51999961 1 P 0 ;0,1,2=356,3=90.000000
L 3.3955 2.55099961 3.39446683 2.54793287 1 P 0 ;0,1,2=356,3=90.000000
L 3.39446683 2.54793287 3.39188307 2.54563337 1 P 0 ;0,1,2=356,3=90.000000
L 3.39188307 2.54563337 3.38878376 2.5440997 1 P 0 ;0,1,2=356,3=90.000000
L 3.38878376 2.5440997 3.38464941 2.5429499 1 P 0 ;0,1,2=356,3=90.000000
L 3.38464941 2.5429499 3.37999951 2.54256663 1 P 0 ;0,1,2=356,3=90.000000
L 3.37999951 2.54256663 3.37534951 2.5429499 1 P 0 ;0,1,2=356,3=90.000000
L 3.37534951 2.5429499 3.37121614 2.5440997 1 P 0 ;0,1,2=356,3=90.000000
L 3.37121614 2.5440997 3.36811585 2.54563337 1 P 0 ;0,1,2=356,3=90.000000
L 3.36811585 2.54563337 3.36553307 2.54793287 1 P 0 ;0,1,2=356,3=90.000000
L 3.36553307 2.54793287 3.3645 2.55099961 1 P 0 ;0,1,2=356,3=90.000000
L 3.3645 2.55099961 3.36553307 2.55406634 1 P 0 ;0,1,2=356,3=90.000000
L 3.36553307 2.55406634 3.36811585 2.55636654 1 P 0 ;0,1,2=356,3=90.000000
L 3.36811585 2.55636654 3.37121614 2.5579002 1 P 0 ;0,1,2=356,3=90.000000
L 3.37121614 2.5579002 3.37534951 2.55905 1 P 0 ;0,1,2=356,3=90.000000
L 3.37534951 2.55905 3.37999951 2.55943327 1 P 0 ;0,1,2=356,3=90.000000
L 3.37999951 2.55943327 3.38464941 2.55905 1 P 0 ;0,1,2=356,3=90.000000
L 3.38464941 2.55905 3.38878376 2.5579002 1 P 0 ;0,1,2=356,3=90.000000
L 3.38878376 2.5579002 3.39188307 2.55636654 1 P 0 ;0,1,2=356,3=90.000000
L 3.39188307 2.55636654 3.39446683 2.55406634 1 P 0 ;0,1,2=356,3=90.000000
L 3.39446683 2.55406634 3.3955 2.55099961 1 P 0 ;0,1,2=356,3=90.000000
L 2.127 3.475 2.127 3.385 1 P 0 
L 2.127 3.385 2.083 3.385 1 P 0 
L 2.083 3.385 2.083 3.475 1 P 0 
L 2.083 3.475 2.127 3.475 1 P 0 
L 2.18416683 3.6195 2.18416683 3.6505 1 P 0 ;0,1,2=357,3=0.000000
L 2.18416683 3.6505 2.17458346 3.6505 1 P 0 ;0,1,2=357,3=0.000000
L 2.17458346 3.6505 2.17151673 3.64894931 1 P 0 ;0,1,2=357,3=0.000000
L 2.17151673 3.64894931 2.1695998 3.64688307 1 P 0 ;0,1,2=357,3=0.000000
L 2.1695998 3.64688307 2.16883327 3.6427497 1 P 0 ;0,1,2=357,3=0.000000
L 2.16883327 3.6427497 2.1695998 3.63861634 1 P 0 ;0,1,2=357,3=0.000000
L 2.1695998 3.63861634 2.1719 3.63603356 1 P 0 ;0,1,2=357,3=0.000000
L 2.1719 3.63603356 2.17458346 3.63448287 1 P 0 ;0,1,2=357,3=0.000000
L 2.17458346 3.63448287 2.18416683 3.63448287 1 P 0 ;0,1,2=357,3=0.000000
L 2.17458346 3.63448287 2.16883327 3.6195 1 P 0 ;0,1,2=357,3=0.000000
L 2.1409 3.6195 2.1409 3.6505 1 P 0 ;0,1,2=357,3=0.000000
L 2.1409 3.6505 2.15508376 3.62828327 1 P 0 ;0,1,2=357,3=0.000000
L 2.15508376 3.62828327 2.13591634 3.62828327 1 P 0 ;0,1,2=357,3=0.000000
L 2.12293337 3.62414892 2.12063386 3.62156614 1 P 0 ;0,1,2=357,3=0.000000
L 2.12063386 3.62156614 2.11795039 3.62001654 1 P 0 ;0,1,2=357,3=0.000000
L 2.11795039 3.62001654 2.11450039 3.6195 1 P 0 ;0,1,2=357,3=0.000000
L 2.11450039 3.6195 2.1110497 3.62053307 1 P 0 ;0,1,2=357,3=0.000000
L 2.1110497 3.62053307 2.10836693 3.62259931 1 P 0 ;0,1,2=357,3=0.000000
L 2.10836693 3.62259931 2.10645 3.62621614 1 P 0 ;0,1,2=357,3=0.000000
L 2.10645 3.62621614 2.10606673 3.63034951 1 P 0 ;0,1,2=357,3=0.000000
L 2.10606673 3.63034951 2.10683327 3.63448287 1 P 0 ;0,1,2=357,3=0.000000
L 2.10683327 3.63448287 2.1087502 3.63706663 1 P 0 ;0,1,2=357,3=0.000000
L 2.1087502 3.63706663 2.11143366 3.63913287 1 P 0 ;0,1,2=357,3=0.000000
L 2.11143366 3.63913287 2.11411644 3.63964941 1 P 0 ;0,1,2=357,3=0.000000
L 2.11411644 3.63964941 2.1167999 3.63913287 1 P 0 ;0,1,2=357,3=0.000000
L 2.1167999 3.63913287 2.1202499 3.63706663 1 P 0 ;0,1,2=357,3=0.000000
L 2.1202499 3.63706663 2.1191001 3.6505 1 P 0 ;0,1,2=357,3=0.000000
L 2.1191001 3.6505 2.1087502 3.6505 1 P 0 ;0,1,2=357,3=0.000000
L 2.0789 3.6195 2.0789 3.6505 1 P 0 ;0,1,2=357,3=0.000000
L 2.0789 3.6505 2.09308376 3.62828327 1 P 0 ;0,1,2=357,3=0.000000
L 2.09308376 3.62828327 2.07391634 3.62828327 1 P 0 ;0,1,2=357,3=0.000000
L 1.153 3.63 1.197 3.63 1 P 0 
L 1.153 3.54 1.153 3.63 1 P 0 
L 1.197 3.63 1.197 3.54 1 P 0 
L 1.197 3.54 1.153 3.54 1 P 0 
L 1.1595 3.65583317 1.1905 3.65583317 1 P 0 ;0,1,2=358,3=90.000000
L 1.1905 3.65583317 1.1905 3.66541654 1 P 0 ;0,1,2=358,3=90.000000
L 1.1905 3.66541654 1.18894931 3.66848327 1 P 0 ;0,1,2=358,3=90.000000
L 1.18894931 3.66848327 1.18688307 3.6704002 1 P 0 ;0,1,2=358,3=90.000000
L 1.18688307 3.6704002 1.1827497 3.67116673 1 P 0 ;0,1,2=358,3=90.000000
L 1.1827497 3.67116673 1.17861634 3.6704002 1 P 0 ;0,1,2=358,3=90.000000
L 1.17861634 3.6704002 1.17603356 3.6681 1 P 0 ;0,1,2=358,3=90.000000
L 1.17603356 3.6681 1.17448287 3.66541654 1 P 0 ;0,1,2=358,3=90.000000
L 1.17448287 3.66541654 1.17448287 3.65583317 1 P 0 ;0,1,2=358,3=90.000000
L 1.17448287 3.66541654 1.1595 3.67116673 1 P 0 ;0,1,2=358,3=90.000000
L 1.1595 3.6991 1.1905 3.6991 1 P 0 ;0,1,2=358,3=90.000000
L 1.1905 3.6991 1.16828327 3.68491624 1 P 0 ;0,1,2=358,3=90.000000
L 1.16828327 3.68491624 1.16828327 3.70408366 1 P 0 ;0,1,2=358,3=90.000000
L 1.17241575 3.71821644 1.17603356 3.7208999 1 P 0 ;0,1,2=358,3=90.000000
L 1.17603356 3.7208999 1.1780998 3.7232001 1 P 0 ;0,1,2=358,3=90.000000
L 1.1780998 3.7232001 1.17913287 3.72626683 1 P 0 ;0,1,2=358,3=90.000000
L 1.17913287 3.72626683 1.1780998 3.7289503 1 P 0 ;0,1,2=358,3=90.000000
L 1.1780998 3.7289503 1.17603356 3.73086654 1 P 0 ;0,1,2=358,3=90.000000
L 1.17603356 3.73086654 1.17293327 3.7324002 1 P 0 ;0,1,2=358,3=90.000000
L 1.17293327 3.7324002 1.16931644 3.73278346 1 P 0 ;0,1,2=358,3=90.000000
L 1.16931644 3.73278346 1.16621614 3.7324002 1 P 0 ;0,1,2=358,3=90.000000
L 1.16621614 3.7324002 1.16311585 3.73086654 1 P 0 ;0,1,2=358,3=90.000000
L 1.16311585 3.73086654 1.16053307 3.72856634 1 P 0 ;0,1,2=358,3=90.000000
L 1.16053307 3.72856634 1.1595 3.72588356 1 P 0 ;0,1,2=358,3=90.000000
L 1.1595 3.72588356 1.16053307 3.72281683 1 P 0 ;0,1,2=358,3=90.000000
L 1.16053307 3.72281683 1.16363238 3.72013337 1 P 0 ;0,1,2=358,3=90.000000
L 1.16363238 3.72013337 1.16828327 3.7185997 1 P 0 ;0,1,2=358,3=90.000000
L 1.16828327 3.7185997 1.1734498 3.71821644 1 P 0 ;0,1,2=358,3=90.000000
L 1.1734498 3.71821644 1.18016594 3.71898287 1 P 0 ;0,1,2=358,3=90.000000
L 1.18016594 3.71898287 1.18378376 3.72013337 1 P 0 ;0,1,2=358,3=90.000000
L 1.18378376 3.72013337 1.1873997 3.72204961 1 P 0 ;0,1,2=358,3=90.000000
L 1.1873997 3.72204961 1.18998337 3.72473307 1 P 0 ;0,1,2=358,3=90.000000
L 1.18998337 3.72473307 1.1905 3.72741654 1 P 0 ;0,1,2=358,3=90.000000
L 1.1905 3.72741654 1.18946683 3.7301 1 P 0 ;0,1,2=358,3=90.000000
L 1.18946683 3.7301 1.18688307 3.73201703 1 P 0 ;0,1,2=358,3=90.000000
L 1.16569961 3.74806663 1.16208278 3.75036614 1 P 0 ;0,1,2=358,3=90.000000
L 1.16208278 3.75036614 1.16001654 3.75343287 1 P 0 ;0,1,2=358,3=90.000000
L 1.16001654 3.75343287 1.1595 3.75688356 1 P 0 ;0,1,2=358,3=90.000000
L 1.1595 3.75688356 1.16001654 3.7599503 1 P 0 ;0,1,2=358,3=90.000000
L 1.16001654 3.7599503 1.16259931 3.76301703 1 P 0 ;0,1,2=358,3=90.000000
L 1.16259931 3.76301703 1.16569961 3.76493327 1 P 0 ;0,1,2=358,3=90.000000
L 1.16569961 3.76493327 1.1687999 3.76531654 1 P 0 ;0,1,2=358,3=90.000000
L 1.1687999 3.76531654 1.17241575 3.76455 1 P 0 ;0,1,2=358,3=90.000000
L 1.17241575 3.76455 1.17499951 3.76186654 1 P 0 ;0,1,2=358,3=90.000000
L 1.17499951 3.76186654 1.17603356 3.75918307 1 P 0 ;0,1,2=358,3=90.000000
L 1.17603356 3.75918307 1.17603356 3.75573307 1 P 0 ;0,1,2=358,3=90.000000
L 1.17603356 3.75918307 1.17758317 3.76148327 1 P 0 ;0,1,2=358,3=90.000000
L 1.17758317 3.76148327 1.18016594 3.7634002 1 P 0 ;0,1,2=358,3=90.000000
L 1.18016594 3.7634002 1.18326624 3.76416673 1 P 0 ;0,1,2=358,3=90.000000
L 1.18326624 3.76416673 1.18636654 3.7634002 1 P 0 ;0,1,2=358,3=90.000000
L 1.18636654 3.7634002 1.18894931 3.76148327 1 P 0 ;0,1,2=358,3=90.000000
L 1.18894931 3.76148327 1.1905 3.75803327 1 P 0 ;0,1,2=358,3=90.000000
L 1.1905 3.75803327 1.18998337 3.75458337 1 P 0 ;0,1,2=358,3=90.000000
L 1.18998337 3.75458337 1.18791624 3.75113337 1 P 0 ;0,1,2=358,3=90.000000
L 5.786 3.929 5.786 3.885 1 P 0 
L 5.696 3.929 5.786 3.929 1 P 0 
L 5.786 3.885 5.696 3.885 1 P 0 
L 5.696 3.885 5.696 3.929 1 P 0 
L 5.90366683 3.8895 5.90366683 3.9205 1 P 0 ;0,1,2=359,3=0.000000
L 5.90366683 3.9205 5.89408346 3.9205 1 P 0 ;0,1,2=359,3=0.000000
L 5.89408346 3.9205 5.89101673 3.91894931 1 P 0 ;0,1,2=359,3=0.000000
L 5.89101673 3.91894931 5.8890998 3.91688307 1 P 0 ;0,1,2=359,3=0.000000
L 5.8890998 3.91688307 5.88833327 3.9127497 1 P 0 ;0,1,2=359,3=0.000000
L 5.88833327 3.9127497 5.8890998 3.90861634 1 P 0 ;0,1,2=359,3=0.000000
L 5.8890998 3.90861634 5.8914 3.90603356 1 P 0 ;0,1,2=359,3=0.000000
L 5.8914 3.90603356 5.89408346 3.90448287 1 P 0 ;0,1,2=359,3=0.000000
L 5.89408346 3.90448287 5.90366683 3.90448287 1 P 0 ;0,1,2=359,3=0.000000
L 5.89408346 3.90448287 5.88833327 3.8895 1 P 0 ;0,1,2=359,3=0.000000
L 5.86500039 3.8895 5.86500039 3.9205 1 P 0 ;0,1,2=359,3=0.000000
L 5.86500039 3.9205 5.8696001 3.9143003 1 P 0 ;0,1,2=359,3=0.000000
L 5.8696001 3.8895 5.86040069 3.8895 1 P 0 ;0,1,2=359,3=0.000000
L 5.84128356 3.90241575 5.8386001 3.90603356 1 P 0 ;0,1,2=359,3=0.000000
L 5.8386001 3.90603356 5.8362999 3.9080998 1 P 0 ;0,1,2=359,3=0.000000
L 5.8362999 3.9080998 5.83323317 3.90913287 1 P 0 ;0,1,2=359,3=0.000000
L 5.83323317 3.90913287 5.8305497 3.9080998 1 P 0 ;0,1,2=359,3=0.000000
L 5.8305497 3.9080998 5.82863346 3.90603356 1 P 0 ;0,1,2=359,3=0.000000
L 5.82863346 3.90603356 5.8270998 3.90293327 1 P 0 ;0,1,2=359,3=0.000000
L 5.8270998 3.90293327 5.82671654 3.89931644 1 P 0 ;0,1,2=359,3=0.000000
L 5.82671654 3.89931644 5.8270998 3.89621614 1 P 0 ;0,1,2=359,3=0.000000
L 5.8270998 3.89621614 5.82863346 3.89311585 1 P 0 ;0,1,2=359,3=0.000000
L 5.82863346 3.89311585 5.83093366 3.89053307 1 P 0 ;0,1,2=359,3=0.000000
L 5.83093366 3.89053307 5.83361644 3.8895 1 P 0 ;0,1,2=359,3=0.000000
L 5.83361644 3.8895 5.83668317 3.89053307 1 P 0 ;0,1,2=359,3=0.000000
L 5.83668317 3.89053307 5.83936663 3.89363238 1 P 0 ;0,1,2=359,3=0.000000
L 5.83936663 3.89363238 5.8409003 3.89828327 1 P 0 ;0,1,2=359,3=0.000000
L 5.8409003 3.89828327 5.84128356 3.9034498 1 P 0 ;0,1,2=359,3=0.000000
L 5.84128356 3.9034498 5.84051713 3.91016594 1 P 0 ;0,1,2=359,3=0.000000
L 5.84051713 3.91016594 5.83936663 3.91378376 1 P 0 ;0,1,2=359,3=0.000000
L 5.83936663 3.91378376 5.83745039 3.9173997 1 P 0 ;0,1,2=359,3=0.000000
L 5.83745039 3.9173997 5.83476693 3.91998337 1 P 0 ;0,1,2=359,3=0.000000
L 5.83476693 3.91998337 5.83208346 3.9205 1 P 0 ;0,1,2=359,3=0.000000
L 5.83208346 3.9205 5.8294 3.91946683 1 P 0 ;0,1,2=359,3=0.000000
L 5.8294 3.91946683 5.82748297 3.91688307 1 P 0 ;0,1,2=359,3=0.000000
L 5.47 0.712 5.47 0.668 1 P 0 
L 5.38 0.712 5.47 0.712 1 P 0 
L 5.47 0.668 5.38 0.668 1 P 0 
L 5.38 0.668 5.38 0.712 1 P 0 
L 5.42916683 0.7195 5.42916683 0.7505 1 P 0 ;0,1,2=360,3=0.000000
L 5.42916683 0.7505 5.41958346 0.7505 1 P 0 ;0,1,2=360,3=0.000000
L 5.41958346 0.7505 5.41651673 0.74894931 1 P 0 ;0,1,2=360,3=0.000000
L 5.41651673 0.74894931 5.4145998 0.74688307 1 P 0 ;0,1,2=360,3=0.000000
L 5.4145998 0.74688307 5.41383327 0.7427497 1 P 0 ;0,1,2=360,3=0.000000
L 5.41383327 0.7427497 5.4145998 0.73861634 1 P 0 ;0,1,2=360,3=0.000000
L 5.4145998 0.73861634 5.4169 0.73603356 1 P 0 ;0,1,2=360,3=0.000000
L 5.4169 0.73603356 5.41958346 0.73448287 1 P 0 ;0,1,2=360,3=0.000000
L 5.41958346 0.73448287 5.42916683 0.73448287 1 P 0 ;0,1,2=360,3=0.000000
L 5.41958346 0.73448287 5.41383327 0.7195 1 P 0 ;0,1,2=360,3=0.000000
L 5.39778356 0.74533346 5.39548337 0.74843278 1 P 0 ;0,1,2=360,3=0.000000
L 5.39548337 0.74843278 5.3927999 0.74998337 1 P 0 ;0,1,2=360,3=0.000000
L 5.3927999 0.74998337 5.38973317 0.7505 1 P 0 ;0,1,2=360,3=0.000000
L 5.38973317 0.7505 5.3859 0.74946683 1 P 0 ;0,1,2=360,3=0.000000
L 5.3859 0.74946683 5.38321654 0.74688307 1 P 0 ;0,1,2=360,3=0.000000
L 5.38321654 0.74688307 5.38245 0.74378376 1 P 0 ;0,1,2=360,3=0.000000
L 5.38245 0.74378376 5.38283327 0.74068258 1 P 0 ;0,1,2=360,3=0.000000
L 5.38283327 0.74068258 5.38436693 0.7380998 1 P 0 ;0,1,2=360,3=0.000000
L 5.38436693 0.7380998 5.39203337 0.73293327 1 P 0 ;0,1,2=360,3=0.000000
L 5.39203337 0.73293327 5.39548337 0.72931644 1 P 0 ;0,1,2=360,3=0.000000
L 5.39548337 0.72931644 5.39778356 0.72414892 1 P 0 ;0,1,2=360,3=0.000000
L 5.39778356 0.72414892 5.3985501 0.7195 1 P 0 ;0,1,2=360,3=0.000000
L 5.3985501 0.7195 5.38245 0.7195 1 P 0 ;0,1,2=360,3=0.000000
L 5.36793337 0.72569961 5.36563386 0.72208278 1 P 0 ;0,1,2=360,3=0.000000
L 5.36563386 0.72208278 5.36256713 0.72001654 1 P 0 ;0,1,2=360,3=0.000000
L 5.36256713 0.72001654 5.35911644 0.7195 1 P 0 ;0,1,2=360,3=0.000000
L 5.35911644 0.7195 5.3560497 0.72001654 1 P 0 ;0,1,2=360,3=0.000000
L 5.3560497 0.72001654 5.35298297 0.72259931 1 P 0 ;0,1,2=360,3=0.000000
L 5.35298297 0.72259931 5.35106673 0.72569961 1 P 0 ;0,1,2=360,3=0.000000
L 5.35106673 0.72569961 5.35068346 0.7287999 1 P 0 ;0,1,2=360,3=0.000000
L 5.35068346 0.7287999 5.35145 0.73241575 1 P 0 ;0,1,2=360,3=0.000000
L 5.35145 0.73241575 5.35413346 0.73499951 1 P 0 ;0,1,2=360,3=0.000000
L 5.35413346 0.73499951 5.35681693 0.73603356 1 P 0 ;0,1,2=360,3=0.000000
L 5.35681693 0.73603356 5.36026693 0.73603356 1 P 0 ;0,1,2=360,3=0.000000
L 5.35681693 0.73603356 5.35451673 0.73758317 1 P 0 ;0,1,2=360,3=0.000000
L 5.35451673 0.73758317 5.3525998 0.74016594 1 P 0 ;0,1,2=360,3=0.000000
L 5.3525998 0.74016594 5.35183327 0.74326624 1 P 0 ;0,1,2=360,3=0.000000
L 5.35183327 0.74326624 5.3525998 0.74636654 1 P 0 ;0,1,2=360,3=0.000000
L 5.3525998 0.74636654 5.35451673 0.74894931 1 P 0 ;0,1,2=360,3=0.000000
L 5.35451673 0.74894931 5.35796673 0.7505 1 P 0 ;0,1,2=360,3=0.000000
L 5.35796673 0.7505 5.36141663 0.74998337 1 P 0 ;0,1,2=360,3=0.000000
L 5.36141663 0.74998337 5.36486663 0.74791624 1 P 0 ;0,1,2=360,3=0.000000
L 5.33693337 0.72569961 5.33463386 0.72208278 1 P 0 ;0,1,2=360,3=0.000000
L 5.33463386 0.72208278 5.33156713 0.72001654 1 P 0 ;0,1,2=360,3=0.000000
L 5.33156713 0.72001654 5.32811644 0.7195 1 P 0 ;0,1,2=360,3=0.000000
L 5.32811644 0.7195 5.3250497 0.72001654 1 P 0 ;0,1,2=360,3=0.000000
L 5.3250497 0.72001654 5.32198297 0.72259931 1 P 0 ;0,1,2=360,3=0.000000
L 5.32198297 0.72259931 5.32006673 0.72569961 1 P 0 ;0,1,2=360,3=0.000000
L 5.32006673 0.72569961 5.31968346 0.7287999 1 P 0 ;0,1,2=360,3=0.000000
L 5.31968346 0.7287999 5.32045 0.73241575 1 P 0 ;0,1,2=360,3=0.000000
L 5.32045 0.73241575 5.32313346 0.73499951 1 P 0 ;0,1,2=360,3=0.000000
L 5.32313346 0.73499951 5.32581693 0.73603356 1 P 0 ;0,1,2=360,3=0.000000
L 5.32581693 0.73603356 5.32926693 0.73603356 1 P 0 ;0,1,2=360,3=0.000000
L 5.32581693 0.73603356 5.32351673 0.73758317 1 P 0 ;0,1,2=360,3=0.000000
L 5.32351673 0.73758317 5.3215998 0.74016594 1 P 0 ;0,1,2=360,3=0.000000
L 5.3215998 0.74016594 5.32083327 0.74326624 1 P 0 ;0,1,2=360,3=0.000000
L 5.32083327 0.74326624 5.3215998 0.74636654 1 P 0 ;0,1,2=360,3=0.000000
L 5.3215998 0.74636654 5.32351673 0.74894931 1 P 0 ;0,1,2=360,3=0.000000
L 5.32351673 0.74894931 5.32696673 0.7505 1 P 0 ;0,1,2=360,3=0.000000
L 5.32696673 0.7505 5.33041663 0.74998337 1 P 0 ;0,1,2=360,3=0.000000
L 5.33041663 0.74998337 5.33386663 0.74791624 1 P 0 ;0,1,2=360,3=0.000000
L 5.535 0.771 5.579 0.771 1 P 0 
L 5.579 0.771 5.579 0.681 1 P 0 
L 5.579 0.681 5.535 0.681 1 P 0 
L 5.535 0.681 5.535 0.771 1 P 0 
L 5.5345 0.92583317 5.5655 0.92583317 1 P 0 ;0,1,2=361,3=90.000000
L 5.5655 0.92583317 5.5655 0.93541654 1 P 0 ;0,1,2=361,3=90.000000
L 5.5655 0.93541654 5.56394931 0.93848327 1 P 0 ;0,1,2=361,3=90.000000
L 5.56394931 0.93848327 5.56188307 0.9404002 1 P 0 ;0,1,2=361,3=90.000000
L 5.56188307 0.9404002 5.5577497 0.94116673 1 P 0 ;0,1,2=361,3=90.000000
L 5.5577497 0.94116673 5.55361634 0.9404002 1 P 0 ;0,1,2=361,3=90.000000
L 5.55361634 0.9404002 5.55103356 0.9381 1 P 0 ;0,1,2=361,3=90.000000
L 5.55103356 0.9381 5.54948287 0.93541654 1 P 0 ;0,1,2=361,3=90.000000
L 5.54948287 0.93541654 5.54948287 0.92583317 1 P 0 ;0,1,2=361,3=90.000000
L 5.54948287 0.93541654 5.5345 0.94116673 1 P 0 ;0,1,2=361,3=90.000000
L 5.56033346 0.95721644 5.56343278 0.95951663 1 P 0 ;0,1,2=361,3=90.000000
L 5.56343278 0.95951663 5.56498337 0.9622001 1 P 0 ;0,1,2=361,3=90.000000
L 5.56498337 0.9622001 5.5655 0.96526683 1 P 0 ;0,1,2=361,3=90.000000
L 5.5655 0.96526683 5.56446683 0.9691 1 P 0 ;0,1,2=361,3=90.000000
L 5.56446683 0.9691 5.56188307 0.97178346 1 P 0 ;0,1,2=361,3=90.000000
L 5.56188307 0.97178346 5.55878376 0.97255 1 P 0 ;0,1,2=361,3=90.000000
L 5.55878376 0.97255 5.55568258 0.97216673 1 P 0 ;0,1,2=361,3=90.000000
L 5.55568258 0.97216673 5.5530998 0.97063307 1 P 0 ;0,1,2=361,3=90.000000
L 5.5530998 0.97063307 5.54793327 0.96296663 1 P 0 ;0,1,2=361,3=90.000000
L 5.54793327 0.96296663 5.54431644 0.95951663 1 P 0 ;0,1,2=361,3=90.000000
L 5.54431644 0.95951663 5.53914892 0.95721644 1 P 0 ;0,1,2=361,3=90.000000
L 5.53914892 0.95721644 5.5345 0.9564499 1 P 0 ;0,1,2=361,3=90.000000
L 5.5345 0.9564499 5.5345 0.97255 1 P 0 ;0,1,2=361,3=90.000000
L 5.54069961 0.98706663 5.53708278 0.98936614 1 P 0 ;0,1,2=361,3=90.000000
L 5.53708278 0.98936614 5.53501654 0.99243287 1 P 0 ;0,1,2=361,3=90.000000
L 5.53501654 0.99243287 5.5345 0.99588356 1 P 0 ;0,1,2=361,3=90.000000
L 5.5345 0.99588356 5.53501654 0.9989503 1 P 0 ;0,1,2=361,3=90.000000
L 5.53501654 0.9989503 5.53759931 1.00201703 1 P 0 ;0,1,2=361,3=90.000000
L 5.53759931 1.00201703 5.54069961 1.00393327 1 P 0 ;0,1,2=361,3=90.000000
L 5.54069961 1.00393327 5.5437999 1.00431654 1 P 0 ;0,1,2=361,3=90.000000
L 5.5437999 1.00431654 5.54741575 1.00355 1 P 0 ;0,1,2=361,3=90.000000
L 5.54741575 1.00355 5.54999951 1.00086654 1 P 0 ;0,1,2=361,3=90.000000
L 5.54999951 1.00086654 5.55103356 0.99818307 1 P 0 ;0,1,2=361,3=90.000000
L 5.55103356 0.99818307 5.55103356 0.99473307 1 P 0 ;0,1,2=361,3=90.000000
L 5.55103356 0.99818307 5.55258317 1.00048327 1 P 0 ;0,1,2=361,3=90.000000
L 5.55258317 1.00048327 5.55516594 1.0024002 1 P 0 ;0,1,2=361,3=90.000000
L 5.55516594 1.0024002 5.55826624 1.00316673 1 P 0 ;0,1,2=361,3=90.000000
L 5.55826624 1.00316673 5.56136654 1.0024002 1 P 0 ;0,1,2=361,3=90.000000
L 5.56136654 1.0024002 5.56394931 1.00048327 1 P 0 ;0,1,2=361,3=90.000000
L 5.56394931 1.00048327 5.5655 0.99703327 1 P 0 ;0,1,2=361,3=90.000000
L 5.5655 0.99703327 5.56498337 0.99358337 1 P 0 ;0,1,2=361,3=90.000000
L 5.56498337 0.99358337 5.56291624 0.99013337 1 P 0 ;0,1,2=361,3=90.000000
L 5.56033346 1.01921644 5.56343278 1.02151663 1 P 0 ;0,1,2=361,3=90.000000
L 5.56343278 1.02151663 5.56498337 1.0242001 1 P 0 ;0,1,2=361,3=90.000000
L 5.56498337 1.0242001 5.5655 1.02726683 1 P 0 ;0,1,2=361,3=90.000000
L 5.5655 1.02726683 5.56446683 1.0311 1 P 0 ;0,1,2=361,3=90.000000
L 5.56446683 1.0311 5.56188307 1.03378346 1 P 0 ;0,1,2=361,3=90.000000
L 5.56188307 1.03378346 5.55878376 1.03455 1 P 0 ;0,1,2=361,3=90.000000
L 5.55878376 1.03455 5.55568258 1.03416673 1 P 0 ;0,1,2=361,3=90.000000
L 5.55568258 1.03416673 5.5530998 1.03263307 1 P 0 ;0,1,2=361,3=90.000000
L 5.5530998 1.03263307 5.54793327 1.02496663 1 P 0 ;0,1,2=361,3=90.000000
L 5.54793327 1.02496663 5.54431644 1.02151663 1 P 0 ;0,1,2=361,3=90.000000
L 5.54431644 1.02151663 5.53914892 1.01921644 1 P 0 ;0,1,2=361,3=90.000000
L 5.53914892 1.01921644 5.5345 1.0184499 1 P 0 ;0,1,2=361,3=90.000000
L 5.5345 1.0184499 5.5345 1.03455 1 P 0 ;0,1,2=361,3=90.000000
L 3.859 3.114 3.859 3.07 1 P 0 
L 3.769 3.114 3.859 3.114 1 P 0 
L 3.859 3.07 3.769 3.07 1 P 0 
L 3.769 3.07 3.769 3.114 1 P 0 
L 3.85416683 3.1295 3.85416683 3.1605 1 P 0 ;0,1,2=362,3=0.000000
L 3.85416683 3.1605 3.84458346 3.1605 1 P 0 ;0,1,2=362,3=0.000000
L 3.84458346 3.1605 3.84151673 3.15894931 1 P 0 ;0,1,2=362,3=0.000000
L 3.84151673 3.15894931 3.8395998 3.15688307 1 P 0 ;0,1,2=362,3=0.000000
L 3.8395998 3.15688307 3.83883327 3.1527497 1 P 0 ;0,1,2=362,3=0.000000
L 3.83883327 3.1527497 3.8395998 3.14861634 1 P 0 ;0,1,2=362,3=0.000000
L 3.8395998 3.14861634 3.8419 3.14603356 1 P 0 ;0,1,2=362,3=0.000000
L 3.8419 3.14603356 3.84458346 3.14448287 1 P 0 ;0,1,2=362,3=0.000000
L 3.84458346 3.14448287 3.85416683 3.14448287 1 P 0 ;0,1,2=362,3=0.000000
L 3.84458346 3.14448287 3.83883327 3.1295 1 P 0 ;0,1,2=362,3=0.000000
L 3.81550039 3.1295 3.81550039 3.1605 1 P 0 ;0,1,2=362,3=0.000000
L 3.81550039 3.1605 3.8201001 3.1543003 1 P 0 ;0,1,2=362,3=0.000000
L 3.8201001 3.1295 3.81090069 3.1295 1 P 0 ;0,1,2=362,3=0.000000
L 3.78526693 3.1295 3.78450039 3.13621614 1 P 0 ;0,1,2=362,3=0.000000
L 3.78450039 3.13621614 3.7833499 3.14189921 1 P 0 ;0,1,2=362,3=0.000000
L 3.7833499 3.14189921 3.78181693 3.14706663 1 P 0 ;0,1,2=362,3=0.000000
L 3.78181693 3.14706663 3.7799 3.1527497 1 P 0 ;0,1,2=362,3=0.000000
L 3.7799 3.1527497 3.77683327 3.1605 1 P 0 ;0,1,2=362,3=0.000000
L 3.77683327 3.1605 3.79216683 3.1605 1 P 0 ;0,1,2=362,3=0.000000
L 3.75426693 3.1295 3.75350039 3.13621614 1 P 0 ;0,1,2=362,3=0.000000
L 3.75350039 3.13621614 3.7523499 3.14189921 1 P 0 ;0,1,2=362,3=0.000000
L 3.7523499 3.14189921 3.75081693 3.14706663 1 P 0 ;0,1,2=362,3=0.000000
L 3.75081693 3.14706663 3.7489 3.1527497 1 P 0 ;0,1,2=362,3=0.000000
L 3.7489 3.1527497 3.74583327 3.1605 1 P 0 ;0,1,2=362,3=0.000000
L 3.74583327 3.1605 3.76116683 3.1605 1 P 0 ;0,1,2=362,3=0.000000
L 5.6625 2.37143002 5.6275 2.37143002 1 P 0 
L 5.6275 2.37143002 5.6275 2.31856998 1 P 0 
L 5.6275 2.31856998 5.6625 2.31856998 1 P 0 
L 5.6625 2.31856998 5.6625 2.37143002 1 P 0 
L 5.66291624 2.44193327 5.66446683 2.43963307 1 P 0 ;0,1,2=363,3=90.000000
L 5.66446683 2.43963307 5.6655 2.4369503 1 P 0 ;0,1,2=363,3=90.000000
L 5.6655 2.4369503 5.6655 2.43388356 1 P 0 ;0,1,2=363,3=90.000000
L 5.6655 2.43388356 5.66394931 2.43043287 1 P 0 ;0,1,2=363,3=90.000000
L 5.66394931 2.43043287 5.66136654 2.4277501 1 P 0 ;0,1,2=363,3=90.000000
L 5.66136654 2.4277501 5.65826624 2.42583317 1 P 0 ;0,1,2=363,3=90.000000
L 5.65826624 2.42583317 5.6530998 2.42429951 1 P 0 ;0,1,2=363,3=90.000000
L 5.6530998 2.42429951 5.6484498 2.42391624 1 P 0 ;0,1,2=363,3=90.000000
L 5.6484498 2.42391624 5.6437999 2.42468337 1 P 0 ;0,1,2=363,3=90.000000
L 5.6437999 2.42468337 5.64069961 2.42583317 1 P 0 ;0,1,2=363,3=90.000000
L 5.64069961 2.42583317 5.63759931 2.42813337 1 P 0 ;0,1,2=363,3=90.000000
L 5.63759931 2.42813337 5.63553307 2.43081683 1 P 0 ;0,1,2=363,3=90.000000
L 5.63553307 2.43081683 5.6345 2.43349961 1 P 0 ;0,1,2=363,3=90.000000
L 5.6345 2.43349961 5.6345 2.43618307 1 P 0 ;0,1,2=363,3=90.000000
L 5.6345 2.43618307 5.63553307 2.43886654 1 P 0 ;0,1,2=363,3=90.000000
L 5.63553307 2.43886654 5.63708278 2.44116673 1 P 0 ;0,1,2=363,3=90.000000
L 5.63708278 2.44116673 5.63914892 2.44308366 1 P 0 ;0,1,2=363,3=90.000000
L 5.66033346 2.45721644 5.66343278 2.45951663 1 P 0 ;0,1,2=363,3=90.000000
L 5.66343278 2.45951663 5.66498337 2.4622001 1 P 0 ;0,1,2=363,3=90.000000
L 5.66498337 2.4622001 5.6655 2.46526683 1 P 0 ;0,1,2=363,3=90.000000
L 5.6655 2.46526683 5.66446683 2.4691 1 P 0 ;0,1,2=363,3=90.000000
L 5.66446683 2.4691 5.66188307 2.47178346 1 P 0 ;0,1,2=363,3=90.000000
L 5.66188307 2.47178346 5.65878376 2.47255 1 P 0 ;0,1,2=363,3=90.000000
L 5.65878376 2.47255 5.65568258 2.47216673 1 P 0 ;0,1,2=363,3=90.000000
L 5.65568258 2.47216673 5.6530998 2.47063307 1 P 0 ;0,1,2=363,3=90.000000
L 5.6530998 2.47063307 5.64793327 2.46296663 1 P 0 ;0,1,2=363,3=90.000000
L 5.64793327 2.46296663 5.64431644 2.45951663 1 P 0 ;0,1,2=363,3=90.000000
L 5.64431644 2.45951663 5.63914892 2.45721644 1 P 0 ;0,1,2=363,3=90.000000
L 5.63914892 2.45721644 5.6345 2.4564499 1 P 0 ;0,1,2=363,3=90.000000
L 5.6345 2.4564499 5.6345 2.47255 1 P 0 ;0,1,2=363,3=90.000000
L 5.64741575 2.48821644 5.65103356 2.4908999 1 P 0 ;0,1,2=363,3=90.000000
L 5.65103356 2.4908999 5.6530998 2.4932001 1 P 0 ;0,1,2=363,3=90.000000
L 5.6530998 2.4932001 5.65413287 2.49626683 1 P 0 ;0,1,2=363,3=90.000000
L 5.65413287 2.49626683 5.6530998 2.4989503 1 P 0 ;0,1,2=363,3=90.000000
L 5.6530998 2.4989503 5.65103356 2.50086654 1 P 0 ;0,1,2=363,3=90.000000
L 5.65103356 2.50086654 5.64793327 2.5024002 1 P 0 ;0,1,2=363,3=90.000000
L 5.64793327 2.5024002 5.64431644 2.50278346 1 P 0 ;0,1,2=363,3=90.000000
L 5.64431644 2.50278346 5.64121614 2.5024002 1 P 0 ;0,1,2=363,3=90.000000
L 5.64121614 2.5024002 5.63811585 2.50086654 1 P 0 ;0,1,2=363,3=90.000000
L 5.63811585 2.50086654 5.63553307 2.49856634 1 P 0 ;0,1,2=363,3=90.000000
L 5.63553307 2.49856634 5.6345 2.49588356 1 P 0 ;0,1,2=363,3=90.000000
L 5.6345 2.49588356 5.63553307 2.49281683 1 P 0 ;0,1,2=363,3=90.000000
L 5.63553307 2.49281683 5.63863238 2.49013337 1 P 0 ;0,1,2=363,3=90.000000
L 5.63863238 2.49013337 5.64328327 2.4885997 1 P 0 ;0,1,2=363,3=90.000000
L 5.64328327 2.4885997 5.6484498 2.48821644 1 P 0 ;0,1,2=363,3=90.000000
L 5.6484498 2.48821644 5.65516594 2.48898287 1 P 0 ;0,1,2=363,3=90.000000
L 5.65516594 2.48898287 5.65878376 2.49013337 1 P 0 ;0,1,2=363,3=90.000000
L 5.65878376 2.49013337 5.6623997 2.49204961 1 P 0 ;0,1,2=363,3=90.000000
L 5.6623997 2.49204961 5.66498337 2.49473307 1 P 0 ;0,1,2=363,3=90.000000
L 5.66498337 2.49473307 5.6655 2.49741654 1 P 0 ;0,1,2=363,3=90.000000
L 5.6655 2.49741654 5.66446683 2.5001 1 P 0 ;0,1,2=363,3=90.000000
L 5.66446683 2.5001 5.66188307 2.50201703 1 P 0 ;0,1,2=363,3=90.000000
L 5.64069961 2.51806663 5.63708278 2.52036614 1 P 0 ;0,1,2=363,3=90.000000
L 5.63708278 2.52036614 5.63501654 2.52343287 1 P 0 ;0,1,2=363,3=90.000000
L 5.63501654 2.52343287 5.6345 2.52688356 1 P 0 ;0,1,2=363,3=90.000000
L 5.6345 2.52688356 5.63501654 2.5299503 1 P 0 ;0,1,2=363,3=90.000000
L 5.63501654 2.5299503 5.63759931 2.53301703 1 P 0 ;0,1,2=363,3=90.000000
L 5.63759931 2.53301703 5.64069961 2.53493327 1 P 0 ;0,1,2=363,3=90.000000
L 5.64069961 2.53493327 5.6437999 2.53531654 1 P 0 ;0,1,2=363,3=90.000000
L 5.6437999 2.53531654 5.64741575 2.53455 1 P 0 ;0,1,2=363,3=90.000000
L 5.64741575 2.53455 5.64999951 2.53186654 1 P 0 ;0,1,2=363,3=90.000000
L 5.64999951 2.53186654 5.65103356 2.52918307 1 P 0 ;0,1,2=363,3=90.000000
L 5.65103356 2.52918307 5.65103356 2.52573307 1 P 0 ;0,1,2=363,3=90.000000
L 5.65103356 2.52918307 5.65258317 2.53148327 1 P 0 ;0,1,2=363,3=90.000000
L 5.65258317 2.53148327 5.65516594 2.5334002 1 P 0 ;0,1,2=363,3=90.000000
L 5.65516594 2.5334002 5.65826624 2.53416673 1 P 0 ;0,1,2=363,3=90.000000
L 5.65826624 2.53416673 5.66136654 2.5334002 1 P 0 ;0,1,2=363,3=90.000000
L 5.66136654 2.5334002 5.66394931 2.53148327 1 P 0 ;0,1,2=363,3=90.000000
L 5.66394931 2.53148327 5.6655 2.52803327 1 P 0 ;0,1,2=363,3=90.000000
L 5.6655 2.52803327 5.66498337 2.52458337 1 P 0 ;0,1,2=363,3=90.000000
L 5.66498337 2.52458337 5.66291624 2.52113337 1 P 0 ;0,1,2=363,3=90.000000
L 3.703 1.023 3.703 1.097 1 P 0 
L 3.827 1.023 3.703 1.023 1 P 0 
L 3.827 1.097 3.827 1.023 1 P 0 
L 3.703 1.097 3.827 1.097 1 P 0 
L 3.80306673 1.14291624 3.80536693 1.14446683 1 P 0 ;0,1,2=364,3=0.000000
L 3.80536693 1.14446683 3.8080497 1.1455 1 P 0 ;0,1,2=364,3=0.000000
L 3.8080497 1.1455 3.81111644 1.1455 1 P 0 ;0,1,2=364,3=0.000000
L 3.81111644 1.1455 3.81456713 1.14394931 1 P 0 ;0,1,2=364,3=0.000000
L 3.81456713 1.14394931 3.8172499 1.14136654 1 P 0 ;0,1,2=364,3=0.000000
L 3.8172499 1.14136654 3.81916683 1.13826624 1 P 0 ;0,1,2=364,3=0.000000
L 3.81916683 1.13826624 3.82070049 1.1330998 1 P 0 ;0,1,2=364,3=0.000000
L 3.82070049 1.1330998 3.82108376 1.1284498 1 P 0 ;0,1,2=364,3=0.000000
L 3.82108376 1.1284498 3.82031663 1.1237999 1 P 0 ;0,1,2=364,3=0.000000
L 3.82031663 1.1237999 3.81916683 1.12069961 1 P 0 ;0,1,2=364,3=0.000000
L 3.81916683 1.12069961 3.81686663 1.11759931 1 P 0 ;0,1,2=364,3=0.000000
L 3.81686663 1.11759931 3.81418317 1.11553307 1 P 0 ;0,1,2=364,3=0.000000
L 3.81418317 1.11553307 3.81150039 1.1145 1 P 0 ;0,1,2=364,3=0.000000
L 3.81150039 1.1145 3.80881693 1.1145 1 P 0 ;0,1,2=364,3=0.000000
L 3.80881693 1.1145 3.80613346 1.11553307 1 P 0 ;0,1,2=364,3=0.000000
L 3.80613346 1.11553307 3.80383327 1.11708278 1 P 0 ;0,1,2=364,3=0.000000
L 3.80383327 1.11708278 3.80191634 1.11914892 1 P 0 ;0,1,2=364,3=0.000000
L 3.78050039 1.1145 3.78050039 1.1455 1 P 0 ;0,1,2=364,3=0.000000
L 3.78050039 1.1455 3.7851001 1.1393003 1 P 0 ;0,1,2=364,3=0.000000
L 3.7851001 1.1145 3.77590069 1.1145 1 P 0 ;0,1,2=364,3=0.000000
L 3.75678356 1.12741575 3.7541001 1.13103356 1 P 0 ;0,1,2=364,3=0.000000
L 3.7541001 1.13103356 3.7517999 1.1330998 1 P 0 ;0,1,2=364,3=0.000000
L 3.7517999 1.1330998 3.74873317 1.13413287 1 P 0 ;0,1,2=364,3=0.000000
L 3.74873317 1.13413287 3.7460497 1.1330998 1 P 0 ;0,1,2=364,3=0.000000
L 3.7460497 1.1330998 3.74413346 1.13103356 1 P 0 ;0,1,2=364,3=0.000000
L 3.74413346 1.13103356 3.7425998 1.12793327 1 P 0 ;0,1,2=364,3=0.000000
L 3.7425998 1.12793327 3.74221654 1.12431644 1 P 0 ;0,1,2=364,3=0.000000
L 3.74221654 1.12431644 3.7425998 1.12121614 1 P 0 ;0,1,2=364,3=0.000000
L 3.7425998 1.12121614 3.74413346 1.11811585 1 P 0 ;0,1,2=364,3=0.000000
L 3.74413346 1.11811585 3.74643366 1.11553307 1 P 0 ;0,1,2=364,3=0.000000
L 3.74643366 1.11553307 3.74911644 1.1145 1 P 0 ;0,1,2=364,3=0.000000
L 3.74911644 1.1145 3.75218317 1.11553307 1 P 0 ;0,1,2=364,3=0.000000
L 3.75218317 1.11553307 3.75486663 1.11863238 1 P 0 ;0,1,2=364,3=0.000000
L 3.75486663 1.11863238 3.7564003 1.12328327 1 P 0 ;0,1,2=364,3=0.000000
L 3.7564003 1.12328327 3.75678356 1.1284498 1 P 0 ;0,1,2=364,3=0.000000
L 3.75678356 1.1284498 3.75601713 1.13516594 1 P 0 ;0,1,2=364,3=0.000000
L 3.75601713 1.13516594 3.75486663 1.13878376 1 P 0 ;0,1,2=364,3=0.000000
L 3.75486663 1.13878376 3.75295039 1.1423997 1 P 0 ;0,1,2=364,3=0.000000
L 3.75295039 1.1423997 3.75026693 1.14498337 1 P 0 ;0,1,2=364,3=0.000000
L 3.75026693 1.14498337 3.74758346 1.1455 1 P 0 ;0,1,2=364,3=0.000000
L 3.74758346 1.1455 3.7449 1.14446683 1 P 0 ;0,1,2=364,3=0.000000
L 3.7449 1.14446683 3.74298297 1.14188307 1 P 0 ;0,1,2=364,3=0.000000
L 3.7139 1.1145 3.7139 1.1455 1 P 0 ;0,1,2=364,3=0.000000
L 3.7139 1.1455 3.72808376 1.12328327 1 P 0 ;0,1,2=364,3=0.000000
L 3.72808376 1.12328327 3.70891634 1.12328327 1 P 0 ;0,1,2=364,3=0.000000
L 3.423 1.407 3.497 1.407 1 P 0 
L 3.423 1.283 3.423 1.407 1 P 0 
L 3.497 1.283 3.423 1.283 1 P 0 
L 3.497 1.407 3.497 1.283 1 P 0 
L 3.47291624 1.17193327 3.47446683 1.16963307 1 P 0 ;0,1,2=365,3=90.000000
L 3.47446683 1.16963307 3.4755 1.1669503 1 P 0 ;0,1,2=365,3=90.000000
L 3.4755 1.1669503 3.4755 1.16388356 1 P 0 ;0,1,2=365,3=90.000000
L 3.4755 1.16388356 3.47394931 1.16043287 1 P 0 ;0,1,2=365,3=90.000000
L 3.47394931 1.16043287 3.47136654 1.1577501 1 P 0 ;0,1,2=365,3=90.000000
L 3.47136654 1.1577501 3.46826624 1.15583317 1 P 0 ;0,1,2=365,3=90.000000
L 3.46826624 1.15583317 3.4630998 1.15429951 1 P 0 ;0,1,2=365,3=90.000000
L 3.4630998 1.15429951 3.4584498 1.15391624 1 P 0 ;0,1,2=365,3=90.000000
L 3.4584498 1.15391624 3.4537999 1.15468337 1 P 0 ;0,1,2=365,3=90.000000
L 3.4537999 1.15468337 3.45069961 1.15583317 1 P 0 ;0,1,2=365,3=90.000000
L 3.45069961 1.15583317 3.44759931 1.15813337 1 P 0 ;0,1,2=365,3=90.000000
L 3.44759931 1.15813337 3.44553307 1.16081683 1 P 0 ;0,1,2=365,3=90.000000
L 3.44553307 1.16081683 3.4445 1.16349961 1 P 0 ;0,1,2=365,3=90.000000
L 3.4445 1.16349961 3.4445 1.16618307 1 P 0 ;0,1,2=365,3=90.000000
L 3.4445 1.16618307 3.44553307 1.16886654 1 P 0 ;0,1,2=365,3=90.000000
L 3.44553307 1.16886654 3.44708278 1.17116673 1 P 0 ;0,1,2=365,3=90.000000
L 3.44708278 1.17116673 3.44914892 1.17308366 1 P 0 ;0,1,2=365,3=90.000000
L 3.4445 1.19449961 3.4755 1.19449961 1 P 0 ;0,1,2=365,3=90.000000
L 3.4755 1.19449961 3.4693003 1.1898999 1 P 0 ;0,1,2=365,3=90.000000
L 3.4445 1.1898999 3.4445 1.19909931 1 P 0 ;0,1,2=365,3=90.000000
L 3.4445 1.2301 3.4755 1.2301 1 P 0 ;0,1,2=365,3=90.000000
L 3.4755 1.2301 3.45328327 1.21591624 1 P 0 ;0,1,2=365,3=90.000000
L 3.45328327 1.21591624 3.45328327 1.23508366 1 P 0 ;0,1,2=365,3=90.000000
L 3.45069961 1.24806663 3.44708278 1.25036614 1 P 0 ;0,1,2=365,3=90.000000
L 3.44708278 1.25036614 3.44501654 1.25343287 1 P 0 ;0,1,2=365,3=90.000000
L 3.44501654 1.25343287 3.4445 1.25688356 1 P 0 ;0,1,2=365,3=90.000000
L 3.4445 1.25688356 3.44501654 1.2599503 1 P 0 ;0,1,2=365,3=90.000000
L 3.44501654 1.2599503 3.44759931 1.26301703 1 P 0 ;0,1,2=365,3=90.000000
L 3.44759931 1.26301703 3.45069961 1.26493327 1 P 0 ;0,1,2=365,3=90.000000
L 3.45069961 1.26493327 3.4537999 1.26531654 1 P 0 ;0,1,2=365,3=90.000000
L 3.4537999 1.26531654 3.45741575 1.26455 1 P 0 ;0,1,2=365,3=90.000000
L 3.45741575 1.26455 3.45999951 1.26186654 1 P 0 ;0,1,2=365,3=90.000000
L 3.45999951 1.26186654 3.46103356 1.25918307 1 P 0 ;0,1,2=365,3=90.000000
L 3.46103356 1.25918307 3.46103356 1.25573307 1 P 0 ;0,1,2=365,3=90.000000
L 3.46103356 1.25918307 3.46258317 1.26148327 1 P 0 ;0,1,2=365,3=90.000000
L 3.46258317 1.26148327 3.46516594 1.2634002 1 P 0 ;0,1,2=365,3=90.000000
L 3.46516594 1.2634002 3.46826624 1.26416673 1 P 0 ;0,1,2=365,3=90.000000
L 3.46826624 1.26416673 3.47136654 1.2634002 1 P 0 ;0,1,2=365,3=90.000000
L 3.47136654 1.2634002 3.47394931 1.26148327 1 P 0 ;0,1,2=365,3=90.000000
L 3.47394931 1.26148327 3.4755 1.25803327 1 P 0 ;0,1,2=365,3=90.000000
L 3.4755 1.25803327 3.47498337 1.25458337 1 P 0 ;0,1,2=365,3=90.000000
L 3.47498337 1.25458337 3.47291624 1.25113337 1 P 0 ;0,1,2=365,3=90.000000
L 3.748 1.273 3.748 1.397 1 P 0 
L 3.822 1.273 3.748 1.273 1 P 0 
L 3.822 1.397 3.822 1.273 1 P 0 
L 3.748 1.397 3.822 1.397 1 P 0 
L 3.78806673 1.26291624 3.79036693 1.26446683 1 P 0 ;0,1,2=366,3=0.000000
L 3.79036693 1.26446683 3.7930497 1.2655 1 P 0 ;0,1,2=366,3=0.000000
L 3.7930497 1.2655 3.79611644 1.2655 1 P 0 ;0,1,2=366,3=0.000000
L 3.79611644 1.2655 3.79956713 1.26394931 1 P 0 ;0,1,2=366,3=0.000000
L 3.79956713 1.26394931 3.8022499 1.26136654 1 P 0 ;0,1,2=366,3=0.000000
L 3.8022499 1.26136654 3.80416683 1.25826624 1 P 0 ;0,1,2=366,3=0.000000
L 3.80416683 1.25826624 3.80570049 1.2530998 1 P 0 ;0,1,2=366,3=0.000000
L 3.80570049 1.2530998 3.80608376 1.2484498 1 P 0 ;0,1,2=366,3=0.000000
L 3.80608376 1.2484498 3.80531663 1.2437999 1 P 0 ;0,1,2=366,3=0.000000
L 3.80531663 1.2437999 3.80416683 1.24069961 1 P 0 ;0,1,2=366,3=0.000000
L 3.80416683 1.24069961 3.80186663 1.23759931 1 P 0 ;0,1,2=366,3=0.000000
L 3.80186663 1.23759931 3.79918317 1.23553307 1 P 0 ;0,1,2=366,3=0.000000
L 3.79918317 1.23553307 3.79650039 1.2345 1 P 0 ;0,1,2=366,3=0.000000
L 3.79650039 1.2345 3.79381693 1.2345 1 P 0 ;0,1,2=366,3=0.000000
L 3.79381693 1.2345 3.79113346 1.23553307 1 P 0 ;0,1,2=366,3=0.000000
L 3.79113346 1.23553307 3.78883327 1.23708278 1 P 0 ;0,1,2=366,3=0.000000
L 3.78883327 1.23708278 3.78691634 1.23914892 1 P 0 ;0,1,2=366,3=0.000000
L 3.76550039 1.2345 3.76550039 1.2655 1 P 0 ;0,1,2=366,3=0.000000
L 3.76550039 1.2655 3.7701001 1.2593003 1 P 0 ;0,1,2=366,3=0.000000
L 3.7701001 1.2345 3.76090069 1.2345 1 P 0 ;0,1,2=366,3=0.000000
L 3.74178356 1.26033346 3.73948337 1.26343278 1 P 0 ;0,1,2=366,3=0.000000
L 3.73948337 1.26343278 3.7367999 1.26498337 1 P 0 ;0,1,2=366,3=0.000000
L 3.7367999 1.26498337 3.73373317 1.2655 1 P 0 ;0,1,2=366,3=0.000000
L 3.73373317 1.2655 3.7299 1.26446683 1 P 0 ;0,1,2=366,3=0.000000
L 3.7299 1.26446683 3.72721654 1.26188307 1 P 0 ;0,1,2=366,3=0.000000
L 3.72721654 1.26188307 3.72645 1.25878376 1 P 0 ;0,1,2=366,3=0.000000
L 3.72645 1.25878376 3.72683327 1.25568258 1 P 0 ;0,1,2=366,3=0.000000
L 3.72683327 1.25568258 3.72836693 1.2530998 1 P 0 ;0,1,2=366,3=0.000000
L 3.72836693 1.2530998 3.73603337 1.24793327 1 P 0 ;0,1,2=366,3=0.000000
L 3.73603337 1.24793327 3.73948337 1.24431644 1 P 0 ;0,1,2=366,3=0.000000
L 3.73948337 1.24431644 3.74178356 1.23914892 1 P 0 ;0,1,2=366,3=0.000000
L 3.74178356 1.23914892 3.7425501 1.2345 1 P 0 ;0,1,2=366,3=0.000000
L 3.7425501 1.2345 3.72645 1.2345 1 P 0 ;0,1,2=366,3=0.000000
L 3.71193337 1.23914892 3.70963386 1.23656614 1 P 0 ;0,1,2=366,3=0.000000
L 3.70963386 1.23656614 3.70695039 1.23501654 1 P 0 ;0,1,2=366,3=0.000000
L 3.70695039 1.23501654 3.70350039 1.2345 1 P 0 ;0,1,2=366,3=0.000000
L 3.70350039 1.2345 3.7000497 1.23553307 1 P 0 ;0,1,2=366,3=0.000000
L 3.7000497 1.23553307 3.69736693 1.23759931 1 P 0 ;0,1,2=366,3=0.000000
L 3.69736693 1.23759931 3.69545 1.24121614 1 P 0 ;0,1,2=366,3=0.000000
L 3.69545 1.24121614 3.69506673 1.24534951 1 P 0 ;0,1,2=366,3=0.000000
L 3.69506673 1.24534951 3.69583327 1.24948287 1 P 0 ;0,1,2=366,3=0.000000
L 3.69583327 1.24948287 3.6977502 1.25206663 1 P 0 ;0,1,2=366,3=0.000000
L 3.6977502 1.25206663 3.70043366 1.25413287 1 P 0 ;0,1,2=366,3=0.000000
L 3.70043366 1.25413287 3.70311644 1.25464941 1 P 0 ;0,1,2=366,3=0.000000
L 3.70311644 1.25464941 3.7057999 1.25413287 1 P 0 ;0,1,2=366,3=0.000000
L 3.7057999 1.25413287 3.7092499 1.25206663 1 P 0 ;0,1,2=366,3=0.000000
L 3.7092499 1.25206663 3.7081001 1.2655 1 P 0 ;0,1,2=366,3=0.000000
L 3.7081001 1.2655 3.6977502 1.2655 1 P 0 ;0,1,2=366,3=0.000000
L 5.432 3.243 5.556 3.243 1 P 0 
L 5.556 3.169 5.432 3.169 1 P 0 
L 5.432 3.169 5.432 3.243 1 P 0 
L 5.556 3.243 5.556 3.169 1 P 0 
L 5.55806673 3.52291624 5.56036693 3.52446683 1 P 0 ;0,1,2=367,3=0.000000
L 5.56036693 3.52446683 5.5630497 3.5255 1 P 0 ;0,1,2=367,3=0.000000
L 5.5630497 3.5255 5.56611644 3.5255 1 P 0 ;0,1,2=367,3=0.000000
L 5.56611644 3.5255 5.56956713 3.52394931 1 P 0 ;0,1,2=367,3=0.000000
L 5.56956713 3.52394931 5.5722499 3.52136654 1 P 0 ;0,1,2=367,3=0.000000
L 5.5722499 3.52136654 5.57416683 3.51826624 1 P 0 ;0,1,2=367,3=0.000000
L 5.57416683 3.51826624 5.57570049 3.5130998 1 P 0 ;0,1,2=367,3=0.000000
L 5.57570049 3.5130998 5.57608376 3.5084498 1 P 0 ;0,1,2=367,3=0.000000
L 5.57608376 3.5084498 5.57531663 3.5037999 1 P 0 ;0,1,2=367,3=0.000000
L 5.57531663 3.5037999 5.57416683 3.50069961 1 P 0 ;0,1,2=367,3=0.000000
L 5.57416683 3.50069961 5.57186663 3.49759931 1 P 0 ;0,1,2=367,3=0.000000
L 5.57186663 3.49759931 5.56918317 3.49553307 1 P 0 ;0,1,2=367,3=0.000000
L 5.56918317 3.49553307 5.56650039 3.4945 1 P 0 ;0,1,2=367,3=0.000000
L 5.56650039 3.4945 5.56381693 3.4945 1 P 0 ;0,1,2=367,3=0.000000
L 5.56381693 3.4945 5.56113346 3.49553307 1 P 0 ;0,1,2=367,3=0.000000
L 5.56113346 3.49553307 5.55883327 3.49708278 1 P 0 ;0,1,2=367,3=0.000000
L 5.55883327 3.49708278 5.55691634 3.49914892 1 P 0 ;0,1,2=367,3=0.000000
L 5.54393337 3.50069961 5.54163386 3.49708278 1 P 0 ;0,1,2=367,3=0.000000
L 5.54163386 3.49708278 5.53856713 3.49501654 1 P 0 ;0,1,2=367,3=0.000000
L 5.53856713 3.49501654 5.53511644 3.4945 1 P 0 ;0,1,2=367,3=0.000000
L 5.53511644 3.4945 5.5320497 3.49501654 1 P 0 ;0,1,2=367,3=0.000000
L 5.5320497 3.49501654 5.52898297 3.49759931 1 P 0 ;0,1,2=367,3=0.000000
L 5.52898297 3.49759931 5.52706673 3.50069961 1 P 0 ;0,1,2=367,3=0.000000
L 5.52706673 3.50069961 5.52668346 3.5037999 1 P 0 ;0,1,2=367,3=0.000000
L 5.52668346 3.5037999 5.52745 3.50741575 1 P 0 ;0,1,2=367,3=0.000000
L 5.52745 3.50741575 5.53013346 3.50999951 1 P 0 ;0,1,2=367,3=0.000000
L 5.53013346 3.50999951 5.53281693 3.51103356 1 P 0 ;0,1,2=367,3=0.000000
L 5.53281693 3.51103356 5.53626693 3.51103356 1 P 0 ;0,1,2=367,3=0.000000
L 5.53281693 3.51103356 5.53051673 3.51258317 1 P 0 ;0,1,2=367,3=0.000000
L 5.53051673 3.51258317 5.5285998 3.51516594 1 P 0 ;0,1,2=367,3=0.000000
L 5.5285998 3.51516594 5.52783327 3.51826624 1 P 0 ;0,1,2=367,3=0.000000
L 5.52783327 3.51826624 5.5285998 3.52136654 1 P 0 ;0,1,2=367,3=0.000000
L 5.5285998 3.52136654 5.53051673 3.52394931 1 P 0 ;0,1,2=367,3=0.000000
L 5.53051673 3.52394931 5.53396673 3.5255 1 P 0 ;0,1,2=367,3=0.000000
L 5.53396673 3.5255 5.53741663 3.52498337 1 P 0 ;0,1,2=367,3=0.000000
L 5.53741663 3.52498337 5.54086663 3.52291624 1 P 0 ;0,1,2=367,3=0.000000
L 5.50450039 3.5255 5.50756713 3.52446683 1 P 0 ;0,1,2=367,3=0.000000
L 5.50756713 3.52446683 5.50986663 3.52188307 1 P 0 ;0,1,2=367,3=0.000000
L 5.50986663 3.52188307 5.5114003 3.51878376 1 P 0 ;0,1,2=367,3=0.000000
L 5.5114003 3.51878376 5.5125501 3.51464941 1 P 0 ;0,1,2=367,3=0.000000
L 5.5125501 3.51464941 5.51293337 3.50999951 1 P 0 ;0,1,2=367,3=0.000000
L 5.51293337 3.50999951 5.5125501 3.50534951 1 P 0 ;0,1,2=367,3=0.000000
L 5.5125501 3.50534951 5.5114003 3.50121614 1 P 0 ;0,1,2=367,3=0.000000
L 5.5114003 3.50121614 5.50986663 3.49811585 1 P 0 ;0,1,2=367,3=0.000000
L 5.50986663 3.49811585 5.50756713 3.49553307 1 P 0 ;0,1,2=367,3=0.000000
L 5.50756713 3.49553307 5.50450039 3.4945 1 P 0 ;0,1,2=367,3=0.000000
L 5.50450039 3.4945 5.50143366 3.49553307 1 P 0 ;0,1,2=367,3=0.000000
L 5.50143366 3.49553307 5.49913346 3.49811585 1 P 0 ;0,1,2=367,3=0.000000
L 5.49913346 3.49811585 5.4975998 3.50121614 1 P 0 ;0,1,2=367,3=0.000000
L 5.4975998 3.50121614 5.49645 3.50534951 1 P 0 ;0,1,2=367,3=0.000000
L 5.49645 3.50534951 5.49606673 3.50999951 1 P 0 ;0,1,2=367,3=0.000000
L 5.49606673 3.50999951 5.49645 3.51464941 1 P 0 ;0,1,2=367,3=0.000000
L 5.49645 3.51464941 5.4975998 3.51878376 1 P 0 ;0,1,2=367,3=0.000000
L 5.4975998 3.51878376 5.49913346 3.52188307 1 P 0 ;0,1,2=367,3=0.000000
L 5.49913346 3.52188307 5.50143366 3.52446683 1 P 0 ;0,1,2=367,3=0.000000
L 5.50143366 3.52446683 5.50450039 3.5255 1 P 0 ;0,1,2=367,3=0.000000
L 5.48193337 3.50069961 5.47963386 3.49708278 1 P 0 ;0,1,2=367,3=0.000000
L 5.47963386 3.49708278 5.47656713 3.49501654 1 P 0 ;0,1,2=367,3=0.000000
L 5.47656713 3.49501654 5.47311644 3.4945 1 P 0 ;0,1,2=367,3=0.000000
L 5.47311644 3.4945 5.4700497 3.49501654 1 P 0 ;0,1,2=367,3=0.000000
L 5.4700497 3.49501654 5.46698297 3.49759931 1 P 0 ;0,1,2=367,3=0.000000
L 5.46698297 3.49759931 5.46506673 3.50069961 1 P 0 ;0,1,2=367,3=0.000000
L 5.46506673 3.50069961 5.46468346 3.5037999 1 P 0 ;0,1,2=367,3=0.000000
L 5.46468346 3.5037999 5.46545 3.50741575 1 P 0 ;0,1,2=367,3=0.000000
L 5.46545 3.50741575 5.46813346 3.50999951 1 P 0 ;0,1,2=367,3=0.000000
L 5.46813346 3.50999951 5.47081693 3.51103356 1 P 0 ;0,1,2=367,3=0.000000
L 5.47081693 3.51103356 5.47426693 3.51103356 1 P 0 ;0,1,2=367,3=0.000000
L 5.47081693 3.51103356 5.46851673 3.51258317 1 P 0 ;0,1,2=367,3=0.000000
L 5.46851673 3.51258317 5.4665998 3.51516594 1 P 0 ;0,1,2=367,3=0.000000
L 5.4665998 3.51516594 5.46583327 3.51826624 1 P 0 ;0,1,2=367,3=0.000000
L 5.46583327 3.51826624 5.4665998 3.52136654 1 P 0 ;0,1,2=367,3=0.000000
L 5.4665998 3.52136654 5.46851673 3.52394931 1 P 0 ;0,1,2=367,3=0.000000
L 5.46851673 3.52394931 5.47196673 3.5255 1 P 0 ;0,1,2=367,3=0.000000
L 5.47196673 3.5255 5.47541663 3.52498337 1 P 0 ;0,1,2=367,3=0.000000
L 5.47541663 3.52498337 5.47886663 3.52291624 1 P 0 ;0,1,2=367,3=0.000000
L 5.56 3.251 5.436 3.251 1 P 0 
L 5.436 3.251 5.436 3.325 1 P 0 
L 5.436 3.325 5.56 3.325 1 P 0 
L 5.56 3.325 5.56 3.251 1 P 0 
L 5.55306673 3.56291624 5.55536693 3.56446683 1 P 0 ;0,1,2=368,3=0.000000
L 5.55536693 3.56446683 5.5580497 3.5655 1 P 0 ;0,1,2=368,3=0.000000
L 5.5580497 3.5655 5.56111644 3.5655 1 P 0 ;0,1,2=368,3=0.000000
L 5.56111644 3.5655 5.56456713 3.56394931 1 P 0 ;0,1,2=368,3=0.000000
L 5.56456713 3.56394931 5.5672499 3.56136654 1 P 0 ;0,1,2=368,3=0.000000
L 5.5672499 3.56136654 5.56916683 3.55826624 1 P 0 ;0,1,2=368,3=0.000000
L 5.56916683 3.55826624 5.57070049 3.5530998 1 P 0 ;0,1,2=368,3=0.000000
L 5.57070049 3.5530998 5.57108376 3.5484498 1 P 0 ;0,1,2=368,3=0.000000
L 5.57108376 3.5484498 5.57031663 3.5437999 1 P 0 ;0,1,2=368,3=0.000000
L 5.57031663 3.5437999 5.56916683 3.54069961 1 P 0 ;0,1,2=368,3=0.000000
L 5.56916683 3.54069961 5.56686663 3.53759931 1 P 0 ;0,1,2=368,3=0.000000
L 5.56686663 3.53759931 5.56418317 3.53553307 1 P 0 ;0,1,2=368,3=0.000000
L 5.56418317 3.53553307 5.56150039 3.5345 1 P 0 ;0,1,2=368,3=0.000000
L 5.56150039 3.5345 5.55881693 3.5345 1 P 0 ;0,1,2=368,3=0.000000
L 5.55881693 3.5345 5.55613346 3.53553307 1 P 0 ;0,1,2=368,3=0.000000
L 5.55613346 3.53553307 5.55383327 3.53708278 1 P 0 ;0,1,2=368,3=0.000000
L 5.55383327 3.53708278 5.55191634 3.53914892 1 P 0 ;0,1,2=368,3=0.000000
L 5.53778356 3.56033346 5.53548337 3.56343278 1 P 0 ;0,1,2=368,3=0.000000
L 5.53548337 3.56343278 5.5327999 3.56498337 1 P 0 ;0,1,2=368,3=0.000000
L 5.5327999 3.56498337 5.52973317 3.5655 1 P 0 ;0,1,2=368,3=0.000000
L 5.52973317 3.5655 5.5259 3.56446683 1 P 0 ;0,1,2=368,3=0.000000
L 5.5259 3.56446683 5.52321654 3.56188307 1 P 0 ;0,1,2=368,3=0.000000
L 5.52321654 3.56188307 5.52245 3.55878376 1 P 0 ;0,1,2=368,3=0.000000
L 5.52245 3.55878376 5.52283327 3.55568258 1 P 0 ;0,1,2=368,3=0.000000
L 5.52283327 3.55568258 5.52436693 3.5530998 1 P 0 ;0,1,2=368,3=0.000000
L 5.52436693 3.5530998 5.53203337 3.54793327 1 P 0 ;0,1,2=368,3=0.000000
L 5.53203337 3.54793327 5.53548337 3.54431644 1 P 0 ;0,1,2=368,3=0.000000
L 5.53548337 3.54431644 5.53778356 3.53914892 1 P 0 ;0,1,2=368,3=0.000000
L 5.53778356 3.53914892 5.5385501 3.5345 1 P 0 ;0,1,2=368,3=0.000000
L 5.5385501 3.5345 5.52245 3.5345 1 P 0 ;0,1,2=368,3=0.000000
L 5.50601713 3.53811585 5.50333366 3.53553307 1 P 0 ;0,1,2=368,3=0.000000
L 5.50333366 3.53553307 5.50026693 3.5345 1 P 0 ;0,1,2=368,3=0.000000
L 5.50026693 3.5345 5.4972002 3.53553307 1 P 0 ;0,1,2=368,3=0.000000
L 5.4972002 3.53553307 5.49451673 3.53863238 1 P 0 ;0,1,2=368,3=0.000000
L 5.49451673 3.53863238 5.4925998 3.54328327 1 P 0 ;0,1,2=368,3=0.000000
L 5.4925998 3.54328327 5.49183327 3.54793327 1 P 0 ;0,1,2=368,3=0.000000
L 5.49183327 3.54793327 5.49183327 3.55361634 1 P 0 ;0,1,2=368,3=0.000000
L 5.49183327 3.55361634 5.4925998 3.55826624 1 P 0 ;0,1,2=368,3=0.000000
L 5.4925998 3.55826624 5.49451673 3.5623997 1 P 0 ;0,1,2=368,3=0.000000
L 5.49451673 3.5623997 5.49681693 3.56446683 1 P 0 ;0,1,2=368,3=0.000000
L 5.49681693 3.56446683 5.49950039 3.5655 1 P 0 ;0,1,2=368,3=0.000000
L 5.49950039 3.5655 5.50256713 3.56446683 1 P 0 ;0,1,2=368,3=0.000000
L 5.50256713 3.56446683 5.50486663 3.5623997 1 P 0 ;0,1,2=368,3=0.000000
L 5.50486663 3.5623997 5.5064003 3.5593003 1 P 0 ;0,1,2=368,3=0.000000
L 5.5064003 3.5593003 5.50716683 3.55516594 1 P 0 ;0,1,2=368,3=0.000000
L 5.50716683 3.55516594 5.5064003 3.5515501 1 P 0 ;0,1,2=368,3=0.000000
L 5.5064003 3.5515501 5.50448337 3.54793327 1 P 0 ;0,1,2=368,3=0.000000
L 5.50448337 3.54793327 5.50218317 3.54586604 1 P 0 ;0,1,2=368,3=0.000000
L 5.50218317 3.54586604 5.49950039 3.54534951 1 P 0 ;0,1,2=368,3=0.000000
L 5.49950039 3.54534951 5.49643366 3.54638268 1 P 0 ;0,1,2=368,3=0.000000
L 5.49643366 3.54638268 5.49413346 3.54896634 1 P 0 ;0,1,2=368,3=0.000000
L 5.49413346 3.54896634 5.49183327 3.55361634 1 P 0 ;0,1,2=368,3=0.000000
L 5.47501713 3.53811585 5.47233366 3.53553307 1 P 0 ;0,1,2=368,3=0.000000
L 5.47233366 3.53553307 5.46926693 3.5345 1 P 0 ;0,1,2=368,3=0.000000
L 5.46926693 3.5345 5.4662002 3.53553307 1 P 0 ;0,1,2=368,3=0.000000
L 5.4662002 3.53553307 5.46351673 3.53863238 1 P 0 ;0,1,2=368,3=0.000000
L 5.46351673 3.53863238 5.4615998 3.54328327 1 P 0 ;0,1,2=368,3=0.000000
L 5.4615998 3.54328327 5.46083327 3.54793327 1 P 0 ;0,1,2=368,3=0.000000
L 5.46083327 3.54793327 5.46083327 3.55361634 1 P 0 ;0,1,2=368,3=0.000000
L 5.46083327 3.55361634 5.4615998 3.55826624 1 P 0 ;0,1,2=368,3=0.000000
L 5.4615998 3.55826624 5.46351673 3.5623997 1 P 0 ;0,1,2=368,3=0.000000
L 5.46351673 3.5623997 5.46581693 3.56446683 1 P 0 ;0,1,2=368,3=0.000000
L 5.46581693 3.56446683 5.46850039 3.5655 1 P 0 ;0,1,2=368,3=0.000000
L 5.46850039 3.5655 5.47156713 3.56446683 1 P 0 ;0,1,2=368,3=0.000000
L 5.47156713 3.56446683 5.47386663 3.5623997 1 P 0 ;0,1,2=368,3=0.000000
L 5.47386663 3.5623997 5.4754003 3.5593003 1 P 0 ;0,1,2=368,3=0.000000
L 5.4754003 3.5593003 5.47616683 3.55516594 1 P 0 ;0,1,2=368,3=0.000000
L 5.47616683 3.55516594 5.4754003 3.5515501 1 P 0 ;0,1,2=368,3=0.000000
L 5.4754003 3.5515501 5.47348337 3.54793327 1 P 0 ;0,1,2=368,3=0.000000
L 5.47348337 3.54793327 5.47118317 3.54586604 1 P 0 ;0,1,2=368,3=0.000000
L 5.47118317 3.54586604 5.46850039 3.54534951 1 P 0 ;0,1,2=368,3=0.000000
L 5.46850039 3.54534951 5.46543366 3.54638268 1 P 0 ;0,1,2=368,3=0.000000
L 5.46543366 3.54638268 5.46313346 3.54896634 1 P 0 ;0,1,2=368,3=0.000000
L 5.46313346 3.54896634 5.46083327 3.55361634 1 P 0 ;0,1,2=368,3=0.000000
L 5.436 3.401 5.56 3.401 1 P 0 
L 5.56 3.327 5.436 3.327 1 P 0 
L 5.436 3.327 5.436 3.401 1 P 0 
L 5.56 3.401 5.56 3.327 1 P 0 
L 5.55306673 3.60791624 5.55536693 3.60946683 1 P 0 ;0,1,2=369,3=0.000000
L 5.55536693 3.60946683 5.5580497 3.6105 1 P 0 ;0,1,2=369,3=0.000000
L 5.5580497 3.6105 5.56111644 3.6105 1 P 0 ;0,1,2=369,3=0.000000
L 5.56111644 3.6105 5.56456713 3.60894931 1 P 0 ;0,1,2=369,3=0.000000
L 5.56456713 3.60894931 5.5672499 3.60636654 1 P 0 ;0,1,2=369,3=0.000000
L 5.5672499 3.60636654 5.56916683 3.60326624 1 P 0 ;0,1,2=369,3=0.000000
L 5.56916683 3.60326624 5.57070049 3.5980998 1 P 0 ;0,1,2=369,3=0.000000
L 5.57070049 3.5980998 5.57108376 3.5934498 1 P 0 ;0,1,2=369,3=0.000000
L 5.57108376 3.5934498 5.57031663 3.5887999 1 P 0 ;0,1,2=369,3=0.000000
L 5.57031663 3.5887999 5.56916683 3.58569961 1 P 0 ;0,1,2=369,3=0.000000
L 5.56916683 3.58569961 5.56686663 3.58259931 1 P 0 ;0,1,2=369,3=0.000000
L 5.56686663 3.58259931 5.56418317 3.58053307 1 P 0 ;0,1,2=369,3=0.000000
L 5.56418317 3.58053307 5.56150039 3.5795 1 P 0 ;0,1,2=369,3=0.000000
L 5.56150039 3.5795 5.55881693 3.5795 1 P 0 ;0,1,2=369,3=0.000000
L 5.55881693 3.5795 5.55613346 3.58053307 1 P 0 ;0,1,2=369,3=0.000000
L 5.55613346 3.58053307 5.55383327 3.58208278 1 P 0 ;0,1,2=369,3=0.000000
L 5.55383327 3.58208278 5.55191634 3.58414892 1 P 0 ;0,1,2=369,3=0.000000
L 5.53778356 3.60533346 5.53548337 3.60843278 1 P 0 ;0,1,2=369,3=0.000000
L 5.53548337 3.60843278 5.5327999 3.60998337 1 P 0 ;0,1,2=369,3=0.000000
L 5.5327999 3.60998337 5.52973317 3.6105 1 P 0 ;0,1,2=369,3=0.000000
L 5.52973317 3.6105 5.5259 3.60946683 1 P 0 ;0,1,2=369,3=0.000000
L 5.5259 3.60946683 5.52321654 3.60688307 1 P 0 ;0,1,2=369,3=0.000000
L 5.52321654 3.60688307 5.52245 3.60378376 1 P 0 ;0,1,2=369,3=0.000000
L 5.52245 3.60378376 5.52283327 3.60068258 1 P 0 ;0,1,2=369,3=0.000000
L 5.52283327 3.60068258 5.52436693 3.5980998 1 P 0 ;0,1,2=369,3=0.000000
L 5.52436693 3.5980998 5.53203337 3.59293327 1 P 0 ;0,1,2=369,3=0.000000
L 5.53203337 3.59293327 5.53548337 3.58931644 1 P 0 ;0,1,2=369,3=0.000000
L 5.53548337 3.58931644 5.53778356 3.58414892 1 P 0 ;0,1,2=369,3=0.000000
L 5.53778356 3.58414892 5.5385501 3.5795 1 P 0 ;0,1,2=369,3=0.000000
L 5.5385501 3.5795 5.52245 3.5795 1 P 0 ;0,1,2=369,3=0.000000
L 5.50601713 3.58311585 5.50333366 3.58053307 1 P 0 ;0,1,2=369,3=0.000000
L 5.50333366 3.58053307 5.50026693 3.5795 1 P 0 ;0,1,2=369,3=0.000000
L 5.50026693 3.5795 5.4972002 3.58053307 1 P 0 ;0,1,2=369,3=0.000000
L 5.4972002 3.58053307 5.49451673 3.58363238 1 P 0 ;0,1,2=369,3=0.000000
L 5.49451673 3.58363238 5.4925998 3.58828327 1 P 0 ;0,1,2=369,3=0.000000
L 5.4925998 3.58828327 5.49183327 3.59293327 1 P 0 ;0,1,2=369,3=0.000000
L 5.49183327 3.59293327 5.49183327 3.59861634 1 P 0 ;0,1,2=369,3=0.000000
L 5.49183327 3.59861634 5.4925998 3.60326624 1 P 0 ;0,1,2=369,3=0.000000
L 5.4925998 3.60326624 5.49451673 3.6073997 1 P 0 ;0,1,2=369,3=0.000000
L 5.49451673 3.6073997 5.49681693 3.60946683 1 P 0 ;0,1,2=369,3=0.000000
L 5.49681693 3.60946683 5.49950039 3.6105 1 P 0 ;0,1,2=369,3=0.000000
L 5.49950039 3.6105 5.50256713 3.60946683 1 P 0 ;0,1,2=369,3=0.000000
L 5.50256713 3.60946683 5.50486663 3.6073997 1 P 0 ;0,1,2=369,3=0.000000
L 5.50486663 3.6073997 5.5064003 3.6043003 1 P 0 ;0,1,2=369,3=0.000000
L 5.5064003 3.6043003 5.50716683 3.60016594 1 P 0 ;0,1,2=369,3=0.000000
L 5.50716683 3.60016594 5.5064003 3.5965501 1 P 0 ;0,1,2=369,3=0.000000
L 5.5064003 3.5965501 5.50448337 3.59293327 1 P 0 ;0,1,2=369,3=0.000000
L 5.50448337 3.59293327 5.50218317 3.59086604 1 P 0 ;0,1,2=369,3=0.000000
L 5.50218317 3.59086604 5.49950039 3.59034951 1 P 0 ;0,1,2=369,3=0.000000
L 5.49950039 3.59034951 5.49643366 3.59138268 1 P 0 ;0,1,2=369,3=0.000000
L 5.49643366 3.59138268 5.49413346 3.59396634 1 P 0 ;0,1,2=369,3=0.000000
L 5.49413346 3.59396634 5.49183327 3.59861634 1 P 0 ;0,1,2=369,3=0.000000
L 5.46926693 3.5795 5.46850039 3.58621614 1 P 0 ;0,1,2=369,3=0.000000
L 5.46850039 3.58621614 5.4673499 3.59189921 1 P 0 ;0,1,2=369,3=0.000000
L 5.4673499 3.59189921 5.46581693 3.59706663 1 P 0 ;0,1,2=369,3=0.000000
L 5.46581693 3.59706663 5.4639 3.6027497 1 P 0 ;0,1,2=369,3=0.000000
L 5.4639 3.6027497 5.46083327 3.6105 1 P 0 ;0,1,2=369,3=0.000000
L 5.46083327 3.6105 5.47616683 3.6105 1 P 0 ;0,1,2=369,3=0.000000
L 5.56 3.404 5.436 3.404 1 P 0 
L 5.436 3.404 5.436 3.478 1 P 0 
L 5.436 3.478 5.56 3.478 1 P 0 
L 5.56 3.478 5.56 3.404 1 P 0 
L 5.54806673 3.65291624 5.55036693 3.65446683 1 P 0 ;0,1,2=370,3=0.000000
L 5.55036693 3.65446683 5.5530497 3.6555 1 P 0 ;0,1,2=370,3=0.000000
L 5.5530497 3.6555 5.55611644 3.6555 1 P 0 ;0,1,2=370,3=0.000000
L 5.55611644 3.6555 5.55956713 3.65394931 1 P 0 ;0,1,2=370,3=0.000000
L 5.55956713 3.65394931 5.5622499 3.65136654 1 P 0 ;0,1,2=370,3=0.000000
L 5.5622499 3.65136654 5.56416683 3.64826624 1 P 0 ;0,1,2=370,3=0.000000
L 5.56416683 3.64826624 5.56570049 3.6430998 1 P 0 ;0,1,2=370,3=0.000000
L 5.56570049 3.6430998 5.56608376 3.6384498 1 P 0 ;0,1,2=370,3=0.000000
L 5.56608376 3.6384498 5.56531663 3.6337999 1 P 0 ;0,1,2=370,3=0.000000
L 5.56531663 3.6337999 5.56416683 3.63069961 1 P 0 ;0,1,2=370,3=0.000000
L 5.56416683 3.63069961 5.56186663 3.62759931 1 P 0 ;0,1,2=370,3=0.000000
L 5.56186663 3.62759931 5.55918317 3.62553307 1 P 0 ;0,1,2=370,3=0.000000
L 5.55918317 3.62553307 5.55650039 3.6245 1 P 0 ;0,1,2=370,3=0.000000
L 5.55650039 3.6245 5.55381693 3.6245 1 P 0 ;0,1,2=370,3=0.000000
L 5.55381693 3.6245 5.55113346 3.62553307 1 P 0 ;0,1,2=370,3=0.000000
L 5.55113346 3.62553307 5.54883327 3.62708278 1 P 0 ;0,1,2=370,3=0.000000
L 5.54883327 3.62708278 5.54691634 3.62914892 1 P 0 ;0,1,2=370,3=0.000000
L 5.53393337 3.63069961 5.53163386 3.62708278 1 P 0 ;0,1,2=370,3=0.000000
L 5.53163386 3.62708278 5.52856713 3.62501654 1 P 0 ;0,1,2=370,3=0.000000
L 5.52856713 3.62501654 5.52511644 3.6245 1 P 0 ;0,1,2=370,3=0.000000
L 5.52511644 3.6245 5.5220497 3.62501654 1 P 0 ;0,1,2=370,3=0.000000
L 5.5220497 3.62501654 5.51898297 3.62759931 1 P 0 ;0,1,2=370,3=0.000000
L 5.51898297 3.62759931 5.51706673 3.63069961 1 P 0 ;0,1,2=370,3=0.000000
L 5.51706673 3.63069961 5.51668346 3.6337999 1 P 0 ;0,1,2=370,3=0.000000
L 5.51668346 3.6337999 5.51745 3.63741575 1 P 0 ;0,1,2=370,3=0.000000
L 5.51745 3.63741575 5.52013346 3.63999951 1 P 0 ;0,1,2=370,3=0.000000
L 5.52013346 3.63999951 5.52281693 3.64103356 1 P 0 ;0,1,2=370,3=0.000000
L 5.52281693 3.64103356 5.52626693 3.64103356 1 P 0 ;0,1,2=370,3=0.000000
L 5.52281693 3.64103356 5.52051673 3.64258317 1 P 0 ;0,1,2=370,3=0.000000
L 5.52051673 3.64258317 5.5185998 3.64516594 1 P 0 ;0,1,2=370,3=0.000000
L 5.5185998 3.64516594 5.51783327 3.64826624 1 P 0 ;0,1,2=370,3=0.000000
L 5.51783327 3.64826624 5.5185998 3.65136654 1 P 0 ;0,1,2=370,3=0.000000
L 5.5185998 3.65136654 5.52051673 3.65394931 1 P 0 ;0,1,2=370,3=0.000000
L 5.52051673 3.65394931 5.52396673 3.6555 1 P 0 ;0,1,2=370,3=0.000000
L 5.52396673 3.6555 5.52741663 3.65498337 1 P 0 ;0,1,2=370,3=0.000000
L 5.52741663 3.65498337 5.53086663 3.65291624 1 P 0 ;0,1,2=370,3=0.000000
L 5.49450039 3.6555 5.49756713 3.65446683 1 P 0 ;0,1,2=370,3=0.000000
L 5.49756713 3.65446683 5.49986663 3.65188307 1 P 0 ;0,1,2=370,3=0.000000
L 5.49986663 3.65188307 5.5014003 3.64878376 1 P 0 ;0,1,2=370,3=0.000000
L 5.5014003 3.64878376 5.5025501 3.64464941 1 P 0 ;0,1,2=370,3=0.000000
L 5.5025501 3.64464941 5.50293337 3.63999951 1 P 0 ;0,1,2=370,3=0.000000
L 5.50293337 3.63999951 5.5025501 3.63534951 1 P 0 ;0,1,2=370,3=0.000000
L 5.5025501 3.63534951 5.5014003 3.63121614 1 P 0 ;0,1,2=370,3=0.000000
L 5.5014003 3.63121614 5.49986663 3.62811585 1 P 0 ;0,1,2=370,3=0.000000
L 5.49986663 3.62811585 5.49756713 3.62553307 1 P 0 ;0,1,2=370,3=0.000000
L 5.49756713 3.62553307 5.49450039 3.6245 1 P 0 ;0,1,2=370,3=0.000000
L 5.49450039 3.6245 5.49143366 3.62553307 1 P 0 ;0,1,2=370,3=0.000000
L 5.49143366 3.62553307 5.48913346 3.62811585 1 P 0 ;0,1,2=370,3=0.000000
L 5.48913346 3.62811585 5.4875998 3.63121614 1 P 0 ;0,1,2=370,3=0.000000
L 5.4875998 3.63121614 5.48645 3.63534951 1 P 0 ;0,1,2=370,3=0.000000
L 5.48645 3.63534951 5.48606673 3.63999951 1 P 0 ;0,1,2=370,3=0.000000
L 5.48606673 3.63999951 5.48645 3.64464941 1 P 0 ;0,1,2=370,3=0.000000
L 5.48645 3.64464941 5.4875998 3.64878376 1 P 0 ;0,1,2=370,3=0.000000
L 5.4875998 3.64878376 5.48913346 3.65188307 1 P 0 ;0,1,2=370,3=0.000000
L 5.48913346 3.65188307 5.49143366 3.65446683 1 P 0 ;0,1,2=370,3=0.000000
L 5.49143366 3.65446683 5.49450039 3.6555 1 P 0 ;0,1,2=370,3=0.000000
L 5.46350039 3.6245 5.46350039 3.6555 1 P 0 ;0,1,2=370,3=0.000000
L 5.46350039 3.6555 5.4681001 3.6493003 1 P 0 ;0,1,2=370,3=0.000000
L 5.4681001 3.6245 5.45890069 3.6245 1 P 0 ;0,1,2=370,3=0.000000
L 5.437 1.882 5.437 1.758 1 P 0 
L 5.363 1.882 5.437 1.882 1 P 0 
L 5.363 1.758 5.363 1.882 1 P 0 
L 5.437 1.758 5.363 1.758 1 P 0 
L 5.48841624 1.78193327 5.48996683 1.77963307 1 P 0 ;0,1,2=371,3=90.000000
L 5.48996683 1.77963307 5.491 1.7769503 1 P 0 ;0,1,2=371,3=90.000000
L 5.491 1.7769503 5.491 1.77388356 1 P 0 ;0,1,2=371,3=90.000000
L 5.491 1.77388356 5.48944931 1.77043287 1 P 0 ;0,1,2=371,3=90.000000
L 5.48944931 1.77043287 5.48686654 1.7677501 1 P 0 ;0,1,2=371,3=90.000000
L 5.48686654 1.7677501 5.48376624 1.76583317 1 P 0 ;0,1,2=371,3=90.000000
L 5.48376624 1.76583317 5.4785998 1.76429951 1 P 0 ;0,1,2=371,3=90.000000
L 5.4785998 1.76429951 5.4739498 1.76391624 1 P 0 ;0,1,2=371,3=90.000000
L 5.4739498 1.76391624 5.4692999 1.76468337 1 P 0 ;0,1,2=371,3=90.000000
L 5.4692999 1.76468337 5.46619961 1.76583317 1 P 0 ;0,1,2=371,3=90.000000
L 5.46619961 1.76583317 5.46309931 1.76813337 1 P 0 ;0,1,2=371,3=90.000000
L 5.46309931 1.76813337 5.46103307 1.77081683 1 P 0 ;0,1,2=371,3=90.000000
L 5.46103307 1.77081683 5.46 1.77349961 1 P 0 ;0,1,2=371,3=90.000000
L 5.46 1.77349961 5.46 1.77618307 1 P 0 ;0,1,2=371,3=90.000000
L 5.46 1.77618307 5.46103307 1.77886654 1 P 0 ;0,1,2=371,3=90.000000
L 5.46103307 1.77886654 5.46258278 1.78116673 1 P 0 ;0,1,2=371,3=90.000000
L 5.46258278 1.78116673 5.46464892 1.78308366 1 P 0 ;0,1,2=371,3=90.000000
L 5.46 1.80449961 5.491 1.80449961 1 P 0 ;0,1,2=371,3=90.000000
L 5.491 1.80449961 5.4848003 1.7998999 1 P 0 ;0,1,2=371,3=90.000000
L 5.46 1.7998999 5.46 1.80909931 1 P 0 ;0,1,2=371,3=90.000000
L 5.46 1.83473307 5.46671614 1.83549961 1 P 0 ;0,1,2=371,3=90.000000
L 5.46671614 1.83549961 5.47239921 1.8366501 1 P 0 ;0,1,2=371,3=90.000000
L 5.47239921 1.8366501 5.47756663 1.83818307 1 P 0 ;0,1,2=371,3=90.000000
L 5.47756663 1.83818307 5.4832497 1.8401 1 P 0 ;0,1,2=371,3=90.000000
L 5.4832497 1.8401 5.491 1.84316673 1 P 0 ;0,1,2=371,3=90.000000
L 5.491 1.84316673 5.491 1.82783317 1 P 0 ;0,1,2=371,3=90.000000
L 5.46361585 1.85998287 5.46103307 1.86266634 1 P 0 ;0,1,2=371,3=90.000000
L 5.46103307 1.86266634 5.46 1.86573307 1 P 0 ;0,1,2=371,3=90.000000
L 5.46 1.86573307 5.46103307 1.8687998 1 P 0 ;0,1,2=371,3=90.000000
L 5.46103307 1.8687998 5.46413238 1.87148327 1 P 0 ;0,1,2=371,3=90.000000
L 5.46413238 1.87148327 5.46878327 1.8734002 1 P 0 ;0,1,2=371,3=90.000000
L 5.46878327 1.8734002 5.47343327 1.87416673 1 P 0 ;0,1,2=371,3=90.000000
L 5.47343327 1.87416673 5.47911634 1.87416673 1 P 0 ;0,1,2=371,3=90.000000
L 5.47911634 1.87416673 5.48376624 1.8734002 1 P 0 ;0,1,2=371,3=90.000000
L 5.48376624 1.8734002 5.4878997 1.87148327 1 P 0 ;0,1,2=371,3=90.000000
L 5.4878997 1.87148327 5.48996683 1.86918307 1 P 0 ;0,1,2=371,3=90.000000
L 5.48996683 1.86918307 5.491 1.86649961 1 P 0 ;0,1,2=371,3=90.000000
L 5.491 1.86649961 5.48996683 1.86343287 1 P 0 ;0,1,2=371,3=90.000000
L 5.48996683 1.86343287 5.4878997 1.86113337 1 P 0 ;0,1,2=371,3=90.000000
L 5.4878997 1.86113337 5.4848003 1.8595997 1 P 0 ;0,1,2=371,3=90.000000
L 5.4848003 1.8595997 5.48066594 1.85883317 1 P 0 ;0,1,2=371,3=90.000000
L 5.48066594 1.85883317 5.4770501 1.8595997 1 P 0 ;0,1,2=371,3=90.000000
L 5.4770501 1.8595997 5.47343327 1.86151663 1 P 0 ;0,1,2=371,3=90.000000
L 5.47343327 1.86151663 5.47136604 1.86381683 1 P 0 ;0,1,2=371,3=90.000000
L 5.47136604 1.86381683 5.47084951 1.86649961 1 P 0 ;0,1,2=371,3=90.000000
L 5.47084951 1.86649961 5.47188268 1.86956634 1 P 0 ;0,1,2=371,3=90.000000
L 5.47188268 1.86956634 5.47446634 1.87186654 1 P 0 ;0,1,2=371,3=90.000000
L 5.47446634 1.87186654 5.47911634 1.87416673 1 P 0 ;0,1,2=371,3=90.000000
L 3.707 2.267 3.707 2.193 1 P 0 
L 3.583 2.267 3.707 2.267 1 P 0 
L 3.707 2.193 3.583 2.193 1 P 0 
L 3.583 2.193 3.583 2.267 1 P 0 
L 3.62806673 2.30291624 3.63036693 2.30446683 1 P 0 ;0,1,2=372,3=0.000000
L 3.63036693 2.30446683 3.6330497 2.3055 1 P 0 ;0,1,2=372,3=0.000000
L 3.6330497 2.3055 3.63611644 2.3055 1 P 0 ;0,1,2=372,3=0.000000
L 3.63611644 2.3055 3.63956713 2.30394931 1 P 0 ;0,1,2=372,3=0.000000
L 3.63956713 2.30394931 3.6422499 2.30136654 1 P 0 ;0,1,2=372,3=0.000000
L 3.6422499 2.30136654 3.64416683 2.29826624 1 P 0 ;0,1,2=372,3=0.000000
L 3.64416683 2.29826624 3.64570049 2.2930998 1 P 0 ;0,1,2=372,3=0.000000
L 3.64570049 2.2930998 3.64608376 2.2884498 1 P 0 ;0,1,2=372,3=0.000000
L 3.64608376 2.2884498 3.64531663 2.2837999 1 P 0 ;0,1,2=372,3=0.000000
L 3.64531663 2.2837999 3.64416683 2.28069961 1 P 0 ;0,1,2=372,3=0.000000
L 3.64416683 2.28069961 3.64186663 2.27759931 1 P 0 ;0,1,2=372,3=0.000000
L 3.64186663 2.27759931 3.63918317 2.27553307 1 P 0 ;0,1,2=372,3=0.000000
L 3.63918317 2.27553307 3.63650039 2.2745 1 P 0 ;0,1,2=372,3=0.000000
L 3.63650039 2.2745 3.63381693 2.2745 1 P 0 ;0,1,2=372,3=0.000000
L 3.63381693 2.2745 3.63113346 2.27553307 1 P 0 ;0,1,2=372,3=0.000000
L 3.63113346 2.27553307 3.62883327 2.27708278 1 P 0 ;0,1,2=372,3=0.000000
L 3.62883327 2.27708278 3.62691634 2.27914892 1 P 0 ;0,1,2=372,3=0.000000
L 3.60550039 2.2745 3.60550039 2.3055 1 P 0 ;0,1,2=372,3=0.000000
L 3.60550039 2.3055 3.6101001 2.2993003 1 P 0 ;0,1,2=372,3=0.000000
L 3.6101001 2.2745 3.60090069 2.2745 1 P 0 ;0,1,2=372,3=0.000000
L 3.58293337 2.27914892 3.58063386 2.27656614 1 P 0 ;0,1,2=372,3=0.000000
L 3.58063386 2.27656614 3.57795039 2.27501654 1 P 0 ;0,1,2=372,3=0.000000
L 3.57795039 2.27501654 3.57450039 2.2745 1 P 0 ;0,1,2=372,3=0.000000
L 3.57450039 2.2745 3.5710497 2.27553307 1 P 0 ;0,1,2=372,3=0.000000
L 3.5710497 2.27553307 3.56836693 2.27759931 1 P 0 ;0,1,2=372,3=0.000000
L 3.56836693 2.27759931 3.56645 2.28121614 1 P 0 ;0,1,2=372,3=0.000000
L 3.56645 2.28121614 3.56606673 2.28534951 1 P 0 ;0,1,2=372,3=0.000000
L 3.56606673 2.28534951 3.56683327 2.28948287 1 P 0 ;0,1,2=372,3=0.000000
L 3.56683327 2.28948287 3.5687502 2.29206663 1 P 0 ;0,1,2=372,3=0.000000
L 3.5687502 2.29206663 3.57143366 2.29413287 1 P 0 ;0,1,2=372,3=0.000000
L 3.57143366 2.29413287 3.57411644 2.29464941 1 P 0 ;0,1,2=372,3=0.000000
L 3.57411644 2.29464941 3.5767999 2.29413287 1 P 0 ;0,1,2=372,3=0.000000
L 3.5767999 2.29413287 3.5802499 2.29206663 1 P 0 ;0,1,2=372,3=0.000000
L 3.5802499 2.29206663 3.5791001 2.3055 1 P 0 ;0,1,2=372,3=0.000000
L 3.5791001 2.3055 3.5687502 2.3055 1 P 0 ;0,1,2=372,3=0.000000
L 3.54350039 2.2745 3.54081693 2.27501654 1 P 0 ;0,1,2=372,3=0.000000
L 3.54081693 2.27501654 3.5377502 2.27656614 1 P 0 ;0,1,2=372,3=0.000000
L 3.5377502 2.27656614 3.53583327 2.27914892 1 P 0 ;0,1,2=372,3=0.000000
L 3.53583327 2.27914892 3.53506673 2.28276673 1 P 0 ;0,1,2=372,3=0.000000
L 3.53506673 2.28276673 3.53583327 2.28638268 1 P 0 ;0,1,2=372,3=0.000000
L 3.53583327 2.28638268 3.53813346 2.28948287 1 P 0 ;0,1,2=372,3=0.000000
L 3.53813346 2.28948287 3.54158346 2.29103356 1 P 0 ;0,1,2=372,3=0.000000
L 3.54158346 2.29103356 3.54541663 2.29103356 1 P 0 ;0,1,2=372,3=0.000000
L 3.54541663 2.29103356 3.54771683 2.29206663 1 P 0 ;0,1,2=372,3=0.000000
L 3.54771683 2.29206663 3.54963386 2.29464941 1 P 0 ;0,1,2=372,3=0.000000
L 3.54963386 2.29464941 3.5504003 2.29826624 1 P 0 ;0,1,2=372,3=0.000000
L 3.5504003 2.29826624 3.5492499 2.30188307 1 P 0 ;0,1,2=372,3=0.000000
L 3.5492499 2.30188307 3.54656713 2.30446683 1 P 0 ;0,1,2=372,3=0.000000
L 3.54656713 2.30446683 3.54350039 2.3055 1 P 0 ;0,1,2=372,3=0.000000
L 3.54350039 2.3055 3.54043366 2.30446683 1 P 0 ;0,1,2=372,3=0.000000
L 3.54043366 2.30446683 3.5377502 2.30188307 1 P 0 ;0,1,2=372,3=0.000000
L 3.5377502 2.30188307 3.5365998 2.29826624 1 P 0 ;0,1,2=372,3=0.000000
L 3.5365998 2.29826624 3.53736693 2.29464941 1 P 0 ;0,1,2=372,3=0.000000
L 3.53736693 2.29464941 3.53928327 2.29206663 1 P 0 ;0,1,2=372,3=0.000000
L 3.53928327 2.29206663 3.54158346 2.29103356 1 P 0 ;0,1,2=372,3=0.000000
L 3.54158346 2.29103356 3.54541663 2.29103356 1 P 0 ;0,1,2=372,3=0.000000
L 3.54541663 2.29103356 3.54886663 2.28948287 1 P 0 ;0,1,2=372,3=0.000000
L 3.54886663 2.28948287 3.55116683 2.28638268 1 P 0 ;0,1,2=372,3=0.000000
L 3.55116683 2.28638268 3.55193337 2.28276673 1 P 0 ;0,1,2=372,3=0.000000
L 3.55193337 2.28276673 3.55116683 2.27914892 1 P 0 ;0,1,2=372,3=0.000000
L 3.55116683 2.27914892 3.5492499 2.27656614 1 P 0 ;0,1,2=372,3=0.000000
L 3.5492499 2.27656614 3.54618317 2.27501654 1 P 0 ;0,1,2=372,3=0.000000
L 3.54618317 2.27501654 3.54350039 2.2745 1 P 0 ;0,1,2=372,3=0.000000
L 2.973 1.982 3.097 1.982 1 P 0 
L 3.097 1.982 3.097 1.908 1 P 0 
L 3.097 1.908 2.973 1.908 1 P 0 
L 2.973 1.908 2.973 1.982 1 P 0 
L 3.17756673 1.95791624 3.17986693 1.95946683 1 P 0 ;0,1,2=373,3=0.000000
L 3.17986693 1.95946683 3.1825497 1.9605 1 P 0 ;0,1,2=373,3=0.000000
L 3.1825497 1.9605 3.18561644 1.9605 1 P 0 ;0,1,2=373,3=0.000000
L 3.18561644 1.9605 3.18906713 1.95894931 1 P 0 ;0,1,2=373,3=0.000000
L 3.18906713 1.95894931 3.1917499 1.95636654 1 P 0 ;0,1,2=373,3=0.000000
L 3.1917499 1.95636654 3.19366683 1.95326624 1 P 0 ;0,1,2=373,3=0.000000
L 3.19366683 1.95326624 3.19520049 1.9480998 1 P 0 ;0,1,2=373,3=0.000000
L 3.19520049 1.9480998 3.19558376 1.9434498 1 P 0 ;0,1,2=373,3=0.000000
L 3.19558376 1.9434498 3.19481663 1.9387999 1 P 0 ;0,1,2=373,3=0.000000
L 3.19481663 1.9387999 3.19366683 1.93569961 1 P 0 ;0,1,2=373,3=0.000000
L 3.19366683 1.93569961 3.19136663 1.93259931 1 P 0 ;0,1,2=373,3=0.000000
L 3.19136663 1.93259931 3.18868317 1.93053307 1 P 0 ;0,1,2=373,3=0.000000
L 3.18868317 1.93053307 3.18600039 1.9295 1 P 0 ;0,1,2=373,3=0.000000
L 3.18600039 1.9295 3.18331693 1.9295 1 P 0 ;0,1,2=373,3=0.000000
L 3.18331693 1.9295 3.18063346 1.93053307 1 P 0 ;0,1,2=373,3=0.000000
L 3.18063346 1.93053307 3.17833327 1.93208278 1 P 0 ;0,1,2=373,3=0.000000
L 3.17833327 1.93208278 3.17641634 1.93414892 1 P 0 ;0,1,2=373,3=0.000000
L 3.16228356 1.94241575 3.1596001 1.94603356 1 P 0 ;0,1,2=373,3=0.000000
L 3.1596001 1.94603356 3.1572999 1.9480998 1 P 0 ;0,1,2=373,3=0.000000
L 3.1572999 1.9480998 3.15423317 1.94913287 1 P 0 ;0,1,2=373,3=0.000000
L 3.15423317 1.94913287 3.1515497 1.9480998 1 P 0 ;0,1,2=373,3=0.000000
L 3.1515497 1.9480998 3.14963346 1.94603356 1 P 0 ;0,1,2=373,3=0.000000
L 3.14963346 1.94603356 3.1480998 1.94293327 1 P 0 ;0,1,2=373,3=0.000000
L 3.1480998 1.94293327 3.14771654 1.93931644 1 P 0 ;0,1,2=373,3=0.000000
L 3.14771654 1.93931644 3.1480998 1.93621614 1 P 0 ;0,1,2=373,3=0.000000
L 3.1480998 1.93621614 3.14963346 1.93311585 1 P 0 ;0,1,2=373,3=0.000000
L 3.14963346 1.93311585 3.15193366 1.93053307 1 P 0 ;0,1,2=373,3=0.000000
L 3.15193366 1.93053307 3.15461644 1.9295 1 P 0 ;0,1,2=373,3=0.000000
L 3.15461644 1.9295 3.15768317 1.93053307 1 P 0 ;0,1,2=373,3=0.000000
L 3.15768317 1.93053307 3.16036663 1.93363238 1 P 0 ;0,1,2=373,3=0.000000
L 3.16036663 1.93363238 3.1619003 1.93828327 1 P 0 ;0,1,2=373,3=0.000000
L 3.1619003 1.93828327 3.16228356 1.9434498 1 P 0 ;0,1,2=373,3=0.000000
L 3.16228356 1.9434498 3.16151713 1.95016594 1 P 0 ;0,1,2=373,3=0.000000
L 3.16151713 1.95016594 3.16036663 1.95378376 1 P 0 ;0,1,2=373,3=0.000000
L 3.16036663 1.95378376 3.15845039 1.9573997 1 P 0 ;0,1,2=373,3=0.000000
L 3.15845039 1.9573997 3.15576693 1.95998337 1 P 0 ;0,1,2=373,3=0.000000
L 3.15576693 1.95998337 3.15308346 1.9605 1 P 0 ;0,1,2=373,3=0.000000
L 3.15308346 1.9605 3.1504 1.95946683 1 P 0 ;0,1,2=373,3=0.000000
L 3.1504 1.95946683 3.14848297 1.95688307 1 P 0 ;0,1,2=373,3=0.000000
L 3.1194 1.9295 3.1194 1.9605 1 P 0 ;0,1,2=373,3=0.000000
L 3.1194 1.9605 3.13358376 1.93828327 1 P 0 ;0,1,2=373,3=0.000000
L 3.13358376 1.93828327 3.11441634 1.93828327 1 P 0 ;0,1,2=373,3=0.000000
L 4.904 1.3 5.028 1.3 1 P 0 
L 5.028 1.226 4.904 1.226 1 P 0 
L 4.904 1.226 4.904 1.3 1 P 0 
L 5.028 1.3 5.028 1.226 1 P 0 
L 4.99906673 1.19591624 5.00136693 1.19746683 1 P 0 ;0,1,2=374,3=0.000000
L 5.00136693 1.19746683 5.0040497 1.1985 1 P 0 ;0,1,2=374,3=0.000000
L 5.0040497 1.1985 5.00711644 1.1985 1 P 0 ;0,1,2=374,3=0.000000
L 5.00711644 1.1985 5.01056713 1.19694931 1 P 0 ;0,1,2=374,3=0.000000
L 5.01056713 1.19694931 5.0132499 1.19436654 1 P 0 ;0,1,2=374,3=0.000000
L 5.0132499 1.19436654 5.01516683 1.19126624 1 P 0 ;0,1,2=374,3=0.000000
L 5.01516683 1.19126624 5.01670049 1.1860998 1 P 0 ;0,1,2=374,3=0.000000
L 5.01670049 1.1860998 5.01708376 1.1814498 1 P 0 ;0,1,2=374,3=0.000000
L 5.01708376 1.1814498 5.01631663 1.1767999 1 P 0 ;0,1,2=374,3=0.000000
L 5.01631663 1.1767999 5.01516683 1.17369961 1 P 0 ;0,1,2=374,3=0.000000
L 5.01516683 1.17369961 5.01286663 1.17059931 1 P 0 ;0,1,2=374,3=0.000000
L 5.01286663 1.17059931 5.01018317 1.16853307 1 P 0 ;0,1,2=374,3=0.000000
L 5.01018317 1.16853307 5.00750039 1.1675 1 P 0 ;0,1,2=374,3=0.000000
L 5.00750039 1.1675 5.00481693 1.1675 1 P 0 ;0,1,2=374,3=0.000000
L 5.00481693 1.1675 5.00213346 1.16853307 1 P 0 ;0,1,2=374,3=0.000000
L 5.00213346 1.16853307 4.99983327 1.17008278 1 P 0 ;0,1,2=374,3=0.000000
L 4.99983327 1.17008278 4.99791634 1.17214892 1 P 0 ;0,1,2=374,3=0.000000
L 4.97650039 1.1675 4.97650039 1.1985 1 P 0 ;0,1,2=374,3=0.000000
L 4.97650039 1.1985 4.9811001 1.1923003 1 P 0 ;0,1,2=374,3=0.000000
L 4.9811001 1.1675 4.97190069 1.1675 1 P 0 ;0,1,2=374,3=0.000000
L 4.95278356 1.18041575 4.9501001 1.18403356 1 P 0 ;0,1,2=374,3=0.000000
L 4.9501001 1.18403356 4.9477999 1.1860998 1 P 0 ;0,1,2=374,3=0.000000
L 4.9477999 1.1860998 4.94473317 1.18713287 1 P 0 ;0,1,2=374,3=0.000000
L 4.94473317 1.18713287 4.9420497 1.1860998 1 P 0 ;0,1,2=374,3=0.000000
L 4.9420497 1.1860998 4.94013346 1.18403356 1 P 0 ;0,1,2=374,3=0.000000
L 4.94013346 1.18403356 4.9385998 1.18093327 1 P 0 ;0,1,2=374,3=0.000000
L 4.9385998 1.18093327 4.93821654 1.17731644 1 P 0 ;0,1,2=374,3=0.000000
L 4.93821654 1.17731644 4.9385998 1.17421614 1 P 0 ;0,1,2=374,3=0.000000
L 4.9385998 1.17421614 4.94013346 1.17111585 1 P 0 ;0,1,2=374,3=0.000000
L 4.94013346 1.17111585 4.94243366 1.16853307 1 P 0 ;0,1,2=374,3=0.000000
L 4.94243366 1.16853307 4.94511644 1.1675 1 P 0 ;0,1,2=374,3=0.000000
L 4.94511644 1.1675 4.94818317 1.16853307 1 P 0 ;0,1,2=374,3=0.000000
L 4.94818317 1.16853307 4.95086663 1.17163238 1 P 0 ;0,1,2=374,3=0.000000
L 4.95086663 1.17163238 4.9524003 1.17628327 1 P 0 ;0,1,2=374,3=0.000000
L 4.9524003 1.17628327 4.95278356 1.1814498 1 P 0 ;0,1,2=374,3=0.000000
L 4.95278356 1.1814498 4.95201713 1.18816594 1 P 0 ;0,1,2=374,3=0.000000
L 4.95201713 1.18816594 4.95086663 1.19178376 1 P 0 ;0,1,2=374,3=0.000000
L 4.95086663 1.19178376 4.94895039 1.1953997 1 P 0 ;0,1,2=374,3=0.000000
L 4.94895039 1.1953997 4.94626693 1.19798337 1 P 0 ;0,1,2=374,3=0.000000
L 4.94626693 1.19798337 4.94358346 1.1985 1 P 0 ;0,1,2=374,3=0.000000
L 4.94358346 1.1985 4.9409 1.19746683 1 P 0 ;0,1,2=374,3=0.000000
L 4.9409 1.19746683 4.93898297 1.19488307 1 P 0 ;0,1,2=374,3=0.000000
L 4.91450039 1.1675 4.91181693 1.16801654 1 P 0 ;0,1,2=374,3=0.000000
L 4.91181693 1.16801654 4.9087502 1.16956614 1 P 0 ;0,1,2=374,3=0.000000
L 4.9087502 1.16956614 4.90683327 1.17214892 1 P 0 ;0,1,2=374,3=0.000000
L 4.90683327 1.17214892 4.90606673 1.17576673 1 P 0 ;0,1,2=374,3=0.000000
L 4.90606673 1.17576673 4.90683327 1.17938268 1 P 0 ;0,1,2=374,3=0.000000
L 4.90683327 1.17938268 4.90913346 1.18248287 1 P 0 ;0,1,2=374,3=0.000000
L 4.90913346 1.18248287 4.91258346 1.18403356 1 P 0 ;0,1,2=374,3=0.000000
L 4.91258346 1.18403356 4.91641663 1.18403356 1 P 0 ;0,1,2=374,3=0.000000
L 4.91641663 1.18403356 4.91871683 1.18506663 1 P 0 ;0,1,2=374,3=0.000000
L 4.91871683 1.18506663 4.92063386 1.18764941 1 P 0 ;0,1,2=374,3=0.000000
L 4.92063386 1.18764941 4.9214003 1.19126624 1 P 0 ;0,1,2=374,3=0.000000
L 4.9214003 1.19126624 4.9202499 1.19488307 1 P 0 ;0,1,2=374,3=0.000000
L 4.9202499 1.19488307 4.91756713 1.19746683 1 P 0 ;0,1,2=374,3=0.000000
L 4.91756713 1.19746683 4.91450039 1.1985 1 P 0 ;0,1,2=374,3=0.000000
L 4.91450039 1.1985 4.91143366 1.19746683 1 P 0 ;0,1,2=374,3=0.000000
L 4.91143366 1.19746683 4.9087502 1.19488307 1 P 0 ;0,1,2=374,3=0.000000
L 4.9087502 1.19488307 4.9075998 1.19126624 1 P 0 ;0,1,2=374,3=0.000000
L 4.9075998 1.19126624 4.90836693 1.18764941 1 P 0 ;0,1,2=374,3=0.000000
L 4.90836693 1.18764941 4.91028327 1.18506663 1 P 0 ;0,1,2=374,3=0.000000
L 4.91028327 1.18506663 4.91258346 1.18403356 1 P 0 ;0,1,2=374,3=0.000000
L 4.91258346 1.18403356 4.91641663 1.18403356 1 P 0 ;0,1,2=374,3=0.000000
L 4.91641663 1.18403356 4.91986663 1.18248287 1 P 0 ;0,1,2=374,3=0.000000
L 4.91986663 1.18248287 4.92216683 1.17938268 1 P 0 ;0,1,2=374,3=0.000000
L 4.92216683 1.17938268 4.92293337 1.17576673 1 P 0 ;0,1,2=374,3=0.000000
L 4.92293337 1.17576673 4.92216683 1.17214892 1 P 0 ;0,1,2=374,3=0.000000
L 4.92216683 1.17214892 4.9202499 1.16956614 1 P 0 ;0,1,2=374,3=0.000000
L 4.9202499 1.16956614 4.91718317 1.16801654 1 P 0 ;0,1,2=374,3=0.000000
L 4.91718317 1.16801654 4.91450039 1.1675 1 P 0 ;0,1,2=374,3=0.000000
L 2.998 2.942 3.072 2.942 1 P 0 
L 2.998 2.818 2.998 2.942 1 P 0 
L 3.072 2.942 3.072 2.818 1 P 0 
L 3.072 2.818 2.998 2.818 1 P 0 
L 3.04791624 2.98193327 3.04946683 2.97963307 1 P 0 ;0,1,2=375,3=90.000000
L 3.04946683 2.97963307 3.0505 2.9769503 1 P 0 ;0,1,2=375,3=90.000000
L 3.0505 2.9769503 3.0505 2.97388356 1 P 0 ;0,1,2=375,3=90.000000
L 3.0505 2.97388356 3.04894931 2.97043287 1 P 0 ;0,1,2=375,3=90.000000
L 3.04894931 2.97043287 3.04636654 2.9677501 1 P 0 ;0,1,2=375,3=90.000000
L 3.04636654 2.9677501 3.04326624 2.96583317 1 P 0 ;0,1,2=375,3=90.000000
L 3.04326624 2.96583317 3.0380998 2.96429951 1 P 0 ;0,1,2=375,3=90.000000
L 3.0380998 2.96429951 3.0334498 2.96391624 1 P 0 ;0,1,2=375,3=90.000000
L 3.0334498 2.96391624 3.0287999 2.96468337 1 P 0 ;0,1,2=375,3=90.000000
L 3.0287999 2.96468337 3.02569961 2.96583317 1 P 0 ;0,1,2=375,3=90.000000
L 3.02569961 2.96583317 3.02259931 2.96813337 1 P 0 ;0,1,2=375,3=90.000000
L 3.02259931 2.96813337 3.02053307 2.97081683 1 P 0 ;0,1,2=375,3=90.000000
L 3.02053307 2.97081683 3.0195 2.97349961 1 P 0 ;0,1,2=375,3=90.000000
L 3.0195 2.97349961 3.0195 2.97618307 1 P 0 ;0,1,2=375,3=90.000000
L 3.0195 2.97618307 3.02053307 2.97886654 1 P 0 ;0,1,2=375,3=90.000000
L 3.02053307 2.97886654 3.02208278 2.98116673 1 P 0 ;0,1,2=375,3=90.000000
L 3.02208278 2.98116673 3.02414892 2.98308366 1 P 0 ;0,1,2=375,3=90.000000
L 3.04533346 2.99721644 3.04843278 2.99951663 1 P 0 ;0,1,2=375,3=90.000000
L 3.04843278 2.99951663 3.04998337 3.0022001 1 P 0 ;0,1,2=375,3=90.000000
L 3.04998337 3.0022001 3.0505 3.00526683 1 P 0 ;0,1,2=375,3=90.000000
L 3.0505 3.00526683 3.04946683 3.0091 1 P 0 ;0,1,2=375,3=90.000000
L 3.04946683 3.0091 3.04688307 3.01178346 1 P 0 ;0,1,2=375,3=90.000000
L 3.04688307 3.01178346 3.04378376 3.01255 1 P 0 ;0,1,2=375,3=90.000000
L 3.04378376 3.01255 3.04068258 3.01216673 1 P 0 ;0,1,2=375,3=90.000000
L 3.04068258 3.01216673 3.0380998 3.01063307 1 P 0 ;0,1,2=375,3=90.000000
L 3.0380998 3.01063307 3.03293327 3.00296663 1 P 0 ;0,1,2=375,3=90.000000
L 3.03293327 3.00296663 3.02931644 2.99951663 1 P 0 ;0,1,2=375,3=90.000000
L 3.02931644 2.99951663 3.02414892 2.99721644 1 P 0 ;0,1,2=375,3=90.000000
L 3.02414892 2.99721644 3.0195 2.9964499 1 P 0 ;0,1,2=375,3=90.000000
L 3.0195 2.9964499 3.0195 3.01255 1 P 0 ;0,1,2=375,3=90.000000
L 3.0195 3.03549961 3.02001654 3.03818307 1 P 0 ;0,1,2=375,3=90.000000
L 3.02001654 3.03818307 3.02156614 3.0412498 1 P 0 ;0,1,2=375,3=90.000000
L 3.02156614 3.0412498 3.02414892 3.04316673 1 P 0 ;0,1,2=375,3=90.000000
L 3.02414892 3.04316673 3.02776673 3.04393327 1 P 0 ;0,1,2=375,3=90.000000
L 3.02776673 3.04393327 3.03138268 3.04316673 1 P 0 ;0,1,2=375,3=90.000000
L 3.03138268 3.04316673 3.03448287 3.04086654 1 P 0 ;0,1,2=375,3=90.000000
L 3.03448287 3.04086654 3.03603356 3.03741654 1 P 0 ;0,1,2=375,3=90.000000
L 3.03603356 3.03741654 3.03603356 3.03358337 1 P 0 ;0,1,2=375,3=90.000000
L 3.03603356 3.03358337 3.03706663 3.03128317 1 P 0 ;0,1,2=375,3=90.000000
L 3.03706663 3.03128317 3.03964941 3.02936614 1 P 0 ;0,1,2=375,3=90.000000
L 3.03964941 3.02936614 3.04326624 3.0285997 1 P 0 ;0,1,2=375,3=90.000000
L 3.04326624 3.0285997 3.04688307 3.0297501 1 P 0 ;0,1,2=375,3=90.000000
L 3.04688307 3.0297501 3.04946683 3.03243287 1 P 0 ;0,1,2=375,3=90.000000
L 3.04946683 3.03243287 3.0505 3.03549961 1 P 0 ;0,1,2=375,3=90.000000
L 3.0505 3.03549961 3.04946683 3.03856634 1 P 0 ;0,1,2=375,3=90.000000
L 3.04946683 3.03856634 3.04688307 3.0412498 1 P 0 ;0,1,2=375,3=90.000000
L 3.04688307 3.0412498 3.04326624 3.0424002 1 P 0 ;0,1,2=375,3=90.000000
L 3.04326624 3.0424002 3.03964941 3.04163307 1 P 0 ;0,1,2=375,3=90.000000
L 3.03964941 3.04163307 3.03706663 3.03971673 1 P 0 ;0,1,2=375,3=90.000000
L 3.03706663 3.03971673 3.03603356 3.03741654 1 P 0 ;0,1,2=375,3=90.000000
L 3.03603356 3.03741654 3.03603356 3.03358337 1 P 0 ;0,1,2=375,3=90.000000
L 3.03603356 3.03358337 3.03448287 3.03013337 1 P 0 ;0,1,2=375,3=90.000000
L 3.03448287 3.03013337 3.03138268 3.02783317 1 P 0 ;0,1,2=375,3=90.000000
L 3.03138268 3.02783317 3.02776673 3.02706663 1 P 0 ;0,1,2=375,3=90.000000
L 3.02776673 3.02706663 3.02414892 3.02783317 1 P 0 ;0,1,2=375,3=90.000000
L 3.02414892 3.02783317 3.02156614 3.0297501 1 P 0 ;0,1,2=375,3=90.000000
L 3.02156614 3.0297501 3.02001654 3.03281683 1 P 0 ;0,1,2=375,3=90.000000
L 3.02001654 3.03281683 3.0195 3.03549961 1 P 0 ;0,1,2=375,3=90.000000
L 3.04533346 3.05921644 3.04843278 3.06151663 1 P 0 ;0,1,2=375,3=90.000000
L 3.04843278 3.06151663 3.04998337 3.0642001 1 P 0 ;0,1,2=375,3=90.000000
L 3.04998337 3.0642001 3.0505 3.06726683 1 P 0 ;0,1,2=375,3=90.000000
L 3.0505 3.06726683 3.04946683 3.0711 1 P 0 ;0,1,2=375,3=90.000000
L 3.04946683 3.0711 3.04688307 3.07378346 1 P 0 ;0,1,2=375,3=90.000000
L 3.04688307 3.07378346 3.04378376 3.07455 1 P 0 ;0,1,2=375,3=90.000000
L 3.04378376 3.07455 3.04068258 3.07416673 1 P 0 ;0,1,2=375,3=90.000000
L 3.04068258 3.07416673 3.0380998 3.07263307 1 P 0 ;0,1,2=375,3=90.000000
L 3.0380998 3.07263307 3.03293327 3.06496663 1 P 0 ;0,1,2=375,3=90.000000
L 3.03293327 3.06496663 3.02931644 3.06151663 1 P 0 ;0,1,2=375,3=90.000000
L 3.02931644 3.06151663 3.02414892 3.05921644 1 P 0 ;0,1,2=375,3=90.000000
L 3.02414892 3.05921644 3.0195 3.0584499 1 P 0 ;0,1,2=375,3=90.000000
L 3.0195 3.0584499 3.0195 3.07455 1 P 0 ;0,1,2=375,3=90.000000
L 3.147 2.942 3.147 2.818 1 P 0 
L 3.073 2.942 3.147 2.942 1 P 0 
L 3.073 2.818 3.073 2.942 1 P 0 
L 3.147 2.818 3.073 2.818 1 P 0 
L 3.10791624 2.98693327 3.10946683 2.98463307 1 P 0 ;0,1,2=376,3=90.000000
L 3.10946683 2.98463307 3.1105 2.9819503 1 P 0 ;0,1,2=376,3=90.000000
L 3.1105 2.9819503 3.1105 2.97888356 1 P 0 ;0,1,2=376,3=90.000000
L 3.1105 2.97888356 3.10894931 2.97543287 1 P 0 ;0,1,2=376,3=90.000000
L 3.10894931 2.97543287 3.10636654 2.9727501 1 P 0 ;0,1,2=376,3=90.000000
L 3.10636654 2.9727501 3.10326624 2.97083317 1 P 0 ;0,1,2=376,3=90.000000
L 3.10326624 2.97083317 3.0980998 2.96929951 1 P 0 ;0,1,2=376,3=90.000000
L 3.0980998 2.96929951 3.0934498 2.96891624 1 P 0 ;0,1,2=376,3=90.000000
L 3.0934498 2.96891624 3.0887999 2.96968337 1 P 0 ;0,1,2=376,3=90.000000
L 3.0887999 2.96968337 3.08569961 2.97083317 1 P 0 ;0,1,2=376,3=90.000000
L 3.08569961 2.97083317 3.08259931 2.97313337 1 P 0 ;0,1,2=376,3=90.000000
L 3.08259931 2.97313337 3.08053307 2.97581683 1 P 0 ;0,1,2=376,3=90.000000
L 3.08053307 2.97581683 3.0795 2.97849961 1 P 0 ;0,1,2=376,3=90.000000
L 3.0795 2.97849961 3.0795 2.98118307 1 P 0 ;0,1,2=376,3=90.000000
L 3.0795 2.98118307 3.08053307 2.98386654 1 P 0 ;0,1,2=376,3=90.000000
L 3.08053307 2.98386654 3.08208278 2.98616673 1 P 0 ;0,1,2=376,3=90.000000
L 3.08208278 2.98616673 3.08414892 2.98808366 1 P 0 ;0,1,2=376,3=90.000000
L 3.10533346 3.00221644 3.10843278 3.00451663 1 P 0 ;0,1,2=376,3=90.000000
L 3.10843278 3.00451663 3.10998337 3.0072001 1 P 0 ;0,1,2=376,3=90.000000
L 3.10998337 3.0072001 3.1105 3.01026683 1 P 0 ;0,1,2=376,3=90.000000
L 3.1105 3.01026683 3.10946683 3.0141 1 P 0 ;0,1,2=376,3=90.000000
L 3.10946683 3.0141 3.10688307 3.01678346 1 P 0 ;0,1,2=376,3=90.000000
L 3.10688307 3.01678346 3.10378376 3.01755 1 P 0 ;0,1,2=376,3=90.000000
L 3.10378376 3.01755 3.10068258 3.01716673 1 P 0 ;0,1,2=376,3=90.000000
L 3.10068258 3.01716673 3.0980998 3.01563307 1 P 0 ;0,1,2=376,3=90.000000
L 3.0980998 3.01563307 3.09293327 3.00796663 1 P 0 ;0,1,2=376,3=90.000000
L 3.09293327 3.00796663 3.08931644 3.00451663 1 P 0 ;0,1,2=376,3=90.000000
L 3.08931644 3.00451663 3.08414892 3.00221644 1 P 0 ;0,1,2=376,3=90.000000
L 3.08414892 3.00221644 3.0795 3.0014499 1 P 0 ;0,1,2=376,3=90.000000
L 3.0795 3.0014499 3.0795 3.01755 1 P 0 ;0,1,2=376,3=90.000000
L 3.0795 3.04049961 3.08001654 3.04318307 1 P 0 ;0,1,2=376,3=90.000000
L 3.08001654 3.04318307 3.08156614 3.0462498 1 P 0 ;0,1,2=376,3=90.000000
L 3.08156614 3.0462498 3.08414892 3.04816673 1 P 0 ;0,1,2=376,3=90.000000
L 3.08414892 3.04816673 3.08776673 3.04893327 1 P 0 ;0,1,2=376,3=90.000000
L 3.08776673 3.04893327 3.09138268 3.04816673 1 P 0 ;0,1,2=376,3=90.000000
L 3.09138268 3.04816673 3.09448287 3.04586654 1 P 0 ;0,1,2=376,3=90.000000
L 3.09448287 3.04586654 3.09603356 3.04241654 1 P 0 ;0,1,2=376,3=90.000000
L 3.09603356 3.04241654 3.09603356 3.03858337 1 P 0 ;0,1,2=376,3=90.000000
L 3.09603356 3.03858337 3.09706663 3.03628317 1 P 0 ;0,1,2=376,3=90.000000
L 3.09706663 3.03628317 3.09964941 3.03436614 1 P 0 ;0,1,2=376,3=90.000000
L 3.09964941 3.03436614 3.10326624 3.0335997 1 P 0 ;0,1,2=376,3=90.000000
L 3.10326624 3.0335997 3.10688307 3.0347501 1 P 0 ;0,1,2=376,3=90.000000
L 3.10688307 3.0347501 3.10946683 3.03743287 1 P 0 ;0,1,2=376,3=90.000000
L 3.10946683 3.03743287 3.1105 3.04049961 1 P 0 ;0,1,2=376,3=90.000000
L 3.1105 3.04049961 3.10946683 3.04356634 1 P 0 ;0,1,2=376,3=90.000000
L 3.10946683 3.04356634 3.10688307 3.0462498 1 P 0 ;0,1,2=376,3=90.000000
L 3.10688307 3.0462498 3.10326624 3.0474002 1 P 0 ;0,1,2=376,3=90.000000
L 3.10326624 3.0474002 3.09964941 3.04663307 1 P 0 ;0,1,2=376,3=90.000000
L 3.09964941 3.04663307 3.09706663 3.04471673 1 P 0 ;0,1,2=376,3=90.000000
L 3.09706663 3.04471673 3.09603356 3.04241654 1 P 0 ;0,1,2=376,3=90.000000
L 3.09603356 3.04241654 3.09603356 3.03858337 1 P 0 ;0,1,2=376,3=90.000000
L 3.09603356 3.03858337 3.09448287 3.03513337 1 P 0 ;0,1,2=376,3=90.000000
L 3.09448287 3.03513337 3.09138268 3.03283317 1 P 0 ;0,1,2=376,3=90.000000
L 3.09138268 3.03283317 3.08776673 3.03206663 1 P 0 ;0,1,2=376,3=90.000000
L 3.08776673 3.03206663 3.08414892 3.03283317 1 P 0 ;0,1,2=376,3=90.000000
L 3.08414892 3.03283317 3.08156614 3.0347501 1 P 0 ;0,1,2=376,3=90.000000
L 3.08156614 3.0347501 3.08001654 3.03781683 1 P 0 ;0,1,2=376,3=90.000000
L 3.08001654 3.03781683 3.0795 3.04049961 1 P 0 ;0,1,2=376,3=90.000000
L 3.08569961 3.06306663 3.08208278 3.06536614 1 P 0 ;0,1,2=376,3=90.000000
L 3.08208278 3.06536614 3.08001654 3.06843287 1 P 0 ;0,1,2=376,3=90.000000
L 3.08001654 3.06843287 3.0795 3.07188356 1 P 0 ;0,1,2=376,3=90.000000
L 3.0795 3.07188356 3.08001654 3.0749503 1 P 0 ;0,1,2=376,3=90.000000
L 3.08001654 3.0749503 3.08259931 3.07801703 1 P 0 ;0,1,2=376,3=90.000000
L 3.08259931 3.07801703 3.08569961 3.07993327 1 P 0 ;0,1,2=376,3=90.000000
L 3.08569961 3.07993327 3.0887999 3.08031654 1 P 0 ;0,1,2=376,3=90.000000
L 3.0887999 3.08031654 3.09241575 3.07955 1 P 0 ;0,1,2=376,3=90.000000
L 3.09241575 3.07955 3.09499951 3.07686654 1 P 0 ;0,1,2=376,3=90.000000
L 3.09499951 3.07686654 3.09603356 3.07418307 1 P 0 ;0,1,2=376,3=90.000000
L 3.09603356 3.07418307 3.09603356 3.07073307 1 P 0 ;0,1,2=376,3=90.000000
L 3.09603356 3.07418307 3.09758317 3.07648327 1 P 0 ;0,1,2=376,3=90.000000
L 3.09758317 3.07648327 3.10016594 3.0784002 1 P 0 ;0,1,2=376,3=90.000000
L 3.10016594 3.0784002 3.10326624 3.07916673 1 P 0 ;0,1,2=376,3=90.000000
L 3.10326624 3.07916673 3.10636654 3.0784002 1 P 0 ;0,1,2=376,3=90.000000
L 3.10636654 3.0784002 3.10894931 3.07648327 1 P 0 ;0,1,2=376,3=90.000000
L 3.10894931 3.07648327 3.1105 3.07303327 1 P 0 ;0,1,2=376,3=90.000000
L 3.1105 3.07303327 3.10998337 3.06958337 1 P 0 ;0,1,2=376,3=90.000000
L 3.10998337 3.06958337 3.10791624 3.06613337 1 P 0 ;0,1,2=376,3=90.000000
L 2.997 2.942 2.997 2.818 1 P 0 
L 2.923 2.942 2.997 2.942 1 P 0 
L 2.923 2.818 2.923 2.942 1 P 0 
L 2.997 2.818 2.923 2.818 1 P 0 
L 2.98791624 2.99243327 2.98946683 2.99013307 1 P 0 ;0,1,2=377,3=90.000000
L 2.98946683 2.99013307 2.9905 2.9874503 1 P 0 ;0,1,2=377,3=90.000000
L 2.9905 2.9874503 2.9905 2.98438356 1 P 0 ;0,1,2=377,3=90.000000
L 2.9905 2.98438356 2.98894931 2.98093287 1 P 0 ;0,1,2=377,3=90.000000
L 2.98894931 2.98093287 2.98636654 2.9782501 1 P 0 ;0,1,2=377,3=90.000000
L 2.98636654 2.9782501 2.98326624 2.97633317 1 P 0 ;0,1,2=377,3=90.000000
L 2.98326624 2.97633317 2.9780998 2.97479951 1 P 0 ;0,1,2=377,3=90.000000
L 2.9780998 2.97479951 2.9734498 2.97441624 1 P 0 ;0,1,2=377,3=90.000000
L 2.9734498 2.97441624 2.9687999 2.97518337 1 P 0 ;0,1,2=377,3=90.000000
L 2.9687999 2.97518337 2.96569961 2.97633317 1 P 0 ;0,1,2=377,3=90.000000
L 2.96569961 2.97633317 2.96259931 2.97863337 1 P 0 ;0,1,2=377,3=90.000000
L 2.96259931 2.97863337 2.96053307 2.98131683 1 P 0 ;0,1,2=377,3=90.000000
L 2.96053307 2.98131683 2.9595 2.98399961 1 P 0 ;0,1,2=377,3=90.000000
L 2.9595 2.98399961 2.9595 2.98668307 1 P 0 ;0,1,2=377,3=90.000000
L 2.9595 2.98668307 2.96053307 2.98936654 1 P 0 ;0,1,2=377,3=90.000000
L 2.96053307 2.98936654 2.96208278 2.99166673 1 P 0 ;0,1,2=377,3=90.000000
L 2.96208278 2.99166673 2.96414892 2.99358366 1 P 0 ;0,1,2=377,3=90.000000
L 2.96414892 3.00656663 2.96156614 3.00886614 1 P 0 ;0,1,2=377,3=90.000000
L 2.96156614 3.00886614 2.96001654 3.01154961 1 P 0 ;0,1,2=377,3=90.000000
L 2.96001654 3.01154961 2.9595 3.01499961 1 P 0 ;0,1,2=377,3=90.000000
L 2.9595 3.01499961 2.96053307 3.0184503 1 P 0 ;0,1,2=377,3=90.000000
L 2.96053307 3.0184503 2.96259931 3.02113307 1 P 0 ;0,1,2=377,3=90.000000
L 2.96259931 3.02113307 2.96621614 3.02305 1 P 0 ;0,1,2=377,3=90.000000
L 2.96621614 3.02305 2.97034951 3.02343327 1 P 0 ;0,1,2=377,3=90.000000
L 2.97034951 3.02343327 2.97448287 3.02266673 1 P 0 ;0,1,2=377,3=90.000000
L 2.97448287 3.02266673 2.97706663 3.0207498 1 P 0 ;0,1,2=377,3=90.000000
L 2.97706663 3.0207498 2.97913287 3.01806634 1 P 0 ;0,1,2=377,3=90.000000
L 2.97913287 3.01806634 2.97964941 3.01538356 1 P 0 ;0,1,2=377,3=90.000000
L 2.97964941 3.01538356 2.97913287 3.0127001 1 P 0 ;0,1,2=377,3=90.000000
L 2.97913287 3.0127001 2.97706663 3.0092501 1 P 0 ;0,1,2=377,3=90.000000
L 2.97706663 3.0092501 2.9905 3.0103999 1 P 0 ;0,1,2=377,3=90.000000
L 2.9905 3.0103999 2.9905 3.0207498 1 P 0 ;0,1,2=377,3=90.000000
L 2.9595 3.04599961 2.96001654 3.04868307 1 P 0 ;0,1,2=377,3=90.000000
L 2.96001654 3.04868307 2.96156614 3.0517498 1 P 0 ;0,1,2=377,3=90.000000
L 2.96156614 3.0517498 2.96414892 3.05366673 1 P 0 ;0,1,2=377,3=90.000000
L 2.96414892 3.05366673 2.96776673 3.05443327 1 P 0 ;0,1,2=377,3=90.000000
L 2.96776673 3.05443327 2.97138268 3.05366673 1 P 0 ;0,1,2=377,3=90.000000
L 2.97138268 3.05366673 2.97448287 3.05136654 1 P 0 ;0,1,2=377,3=90.000000
L 2.97448287 3.05136654 2.97603356 3.04791654 1 P 0 ;0,1,2=377,3=90.000000
L 2.97603356 3.04791654 2.97603356 3.04408337 1 P 0 ;0,1,2=377,3=90.000000
L 2.97603356 3.04408337 2.97706663 3.04178317 1 P 0 ;0,1,2=377,3=90.000000
L 2.97706663 3.04178317 2.97964941 3.03986614 1 P 0 ;0,1,2=377,3=90.000000
L 2.97964941 3.03986614 2.98326624 3.0390997 1 P 0 ;0,1,2=377,3=90.000000
L 2.98326624 3.0390997 2.98688307 3.0402501 1 P 0 ;0,1,2=377,3=90.000000
L 2.98688307 3.0402501 2.98946683 3.04293287 1 P 0 ;0,1,2=377,3=90.000000
L 2.98946683 3.04293287 2.9905 3.04599961 1 P 0 ;0,1,2=377,3=90.000000
L 2.9905 3.04599961 2.98946683 3.04906634 1 P 0 ;0,1,2=377,3=90.000000
L 2.98946683 3.04906634 2.98688307 3.0517498 1 P 0 ;0,1,2=377,3=90.000000
L 2.98688307 3.0517498 2.98326624 3.0529002 1 P 0 ;0,1,2=377,3=90.000000
L 2.98326624 3.0529002 2.97964941 3.05213307 1 P 0 ;0,1,2=377,3=90.000000
L 2.97964941 3.05213307 2.97706663 3.05021673 1 P 0 ;0,1,2=377,3=90.000000
L 2.97706663 3.05021673 2.97603356 3.04791654 1 P 0 ;0,1,2=377,3=90.000000
L 2.97603356 3.04791654 2.97603356 3.04408337 1 P 0 ;0,1,2=377,3=90.000000
L 2.97603356 3.04408337 2.97448287 3.04063337 1 P 0 ;0,1,2=377,3=90.000000
L 2.97448287 3.04063337 2.97138268 3.03833317 1 P 0 ;0,1,2=377,3=90.000000
L 2.97138268 3.03833317 2.96776673 3.03756663 1 P 0 ;0,1,2=377,3=90.000000
L 2.96776673 3.03756663 2.96414892 3.03833317 1 P 0 ;0,1,2=377,3=90.000000
L 2.96414892 3.03833317 2.96156614 3.0402501 1 P 0 ;0,1,2=377,3=90.000000
L 2.96156614 3.0402501 2.96001654 3.04331683 1 P 0 ;0,1,2=377,3=90.000000
L 2.96001654 3.04331683 2.9595 3.04599961 1 P 0 ;0,1,2=377,3=90.000000
L 4.229 2.892 4.229 2.818 1 P 0 
L 4.105 2.892 4.229 2.892 1 P 0 
L 4.229 2.818 4.105 2.818 1 P 0 
L 4.105 2.818 4.105 2.892 1 P 0 
L 4.05506673 2.87291624 4.05736693 2.87446683 1 P 0 ;0,1,2=378,3=0.000000
L 4.05736693 2.87446683 4.0600497 2.8755 1 P 0 ;0,1,2=378,3=0.000000
L 4.0600497 2.8755 4.06311644 2.8755 1 P 0 ;0,1,2=378,3=0.000000
L 4.06311644 2.8755 4.06656713 2.87394931 1 P 0 ;0,1,2=378,3=0.000000
L 4.06656713 2.87394931 4.0692499 2.87136654 1 P 0 ;0,1,2=378,3=0.000000
L 4.0692499 2.87136654 4.07116683 2.86826624 1 P 0 ;0,1,2=378,3=0.000000
L 4.07116683 2.86826624 4.07270049 2.8630998 1 P 0 ;0,1,2=378,3=0.000000
L 4.07270049 2.8630998 4.07308376 2.8584498 1 P 0 ;0,1,2=378,3=0.000000
L 4.07308376 2.8584498 4.07231663 2.8537999 1 P 0 ;0,1,2=378,3=0.000000
L 4.07231663 2.8537999 4.07116683 2.85069961 1 P 0 ;0,1,2=378,3=0.000000
L 4.07116683 2.85069961 4.06886663 2.84759931 1 P 0 ;0,1,2=378,3=0.000000
L 4.06886663 2.84759931 4.06618317 2.84553307 1 P 0 ;0,1,2=378,3=0.000000
L 4.06618317 2.84553307 4.06350039 2.8445 1 P 0 ;0,1,2=378,3=0.000000
L 4.06350039 2.8445 4.06081693 2.8445 1 P 0 ;0,1,2=378,3=0.000000
L 4.06081693 2.8445 4.05813346 2.84553307 1 P 0 ;0,1,2=378,3=0.000000
L 4.05813346 2.84553307 4.05583327 2.84708278 1 P 0 ;0,1,2=378,3=0.000000
L 4.05583327 2.84708278 4.05391634 2.84914892 1 P 0 ;0,1,2=378,3=0.000000
L 4.03978356 2.87033346 4.03748337 2.87343278 1 P 0 ;0,1,2=378,3=0.000000
L 4.03748337 2.87343278 4.0347999 2.87498337 1 P 0 ;0,1,2=378,3=0.000000
L 4.0347999 2.87498337 4.03173317 2.8755 1 P 0 ;0,1,2=378,3=0.000000
L 4.03173317 2.8755 4.0279 2.87446683 1 P 0 ;0,1,2=378,3=0.000000
L 4.0279 2.87446683 4.02521654 2.87188307 1 P 0 ;0,1,2=378,3=0.000000
L 4.02521654 2.87188307 4.02445 2.86878376 1 P 0 ;0,1,2=378,3=0.000000
L 4.02445 2.86878376 4.02483327 2.86568258 1 P 0 ;0,1,2=378,3=0.000000
L 4.02483327 2.86568258 4.02636693 2.8630998 1 P 0 ;0,1,2=378,3=0.000000
L 4.02636693 2.8630998 4.03403337 2.85793327 1 P 0 ;0,1,2=378,3=0.000000
L 4.03403337 2.85793327 4.03748337 2.85431644 1 P 0 ;0,1,2=378,3=0.000000
L 4.03748337 2.85431644 4.03978356 2.84914892 1 P 0 ;0,1,2=378,3=0.000000
L 4.03978356 2.84914892 4.0405501 2.8445 1 P 0 ;0,1,2=378,3=0.000000
L 4.0405501 2.8445 4.02445 2.8445 1 P 0 ;0,1,2=378,3=0.000000
L 3.9969 2.8445 3.9969 2.8755 1 P 0 ;0,1,2=378,3=0.000000
L 3.9969 2.8755 4.01108376 2.85328327 1 P 0 ;0,1,2=378,3=0.000000
L 4.01108376 2.85328327 3.99191634 2.85328327 1 P 0 ;0,1,2=378,3=0.000000
L 3.97893337 2.85069961 3.97663386 2.84708278 1 P 0 ;0,1,2=378,3=0.000000
L 3.97663386 2.84708278 3.97356713 2.84501654 1 P 0 ;0,1,2=378,3=0.000000
L 3.97356713 2.84501654 3.97011644 2.8445 1 P 0 ;0,1,2=378,3=0.000000
L 3.97011644 2.8445 3.9670497 2.84501654 1 P 0 ;0,1,2=378,3=0.000000
L 3.9670497 2.84501654 3.96398297 2.84759931 1 P 0 ;0,1,2=378,3=0.000000
L 3.96398297 2.84759931 3.96206673 2.85069961 1 P 0 ;0,1,2=378,3=0.000000
L 3.96206673 2.85069961 3.96168346 2.8537999 1 P 0 ;0,1,2=378,3=0.000000
L 3.96168346 2.8537999 3.96245 2.85741575 1 P 0 ;0,1,2=378,3=0.000000
L 3.96245 2.85741575 3.96513346 2.85999951 1 P 0 ;0,1,2=378,3=0.000000
L 3.96513346 2.85999951 3.96781693 2.86103356 1 P 0 ;0,1,2=378,3=0.000000
L 3.96781693 2.86103356 3.97126693 2.86103356 1 P 0 ;0,1,2=378,3=0.000000
L 3.96781693 2.86103356 3.96551673 2.86258317 1 P 0 ;0,1,2=378,3=0.000000
L 3.96551673 2.86258317 3.9635998 2.86516594 1 P 0 ;0,1,2=378,3=0.000000
L 3.9635998 2.86516594 3.96283327 2.86826624 1 P 0 ;0,1,2=378,3=0.000000
L 3.96283327 2.86826624 3.9635998 2.87136654 1 P 0 ;0,1,2=378,3=0.000000
L 3.9635998 2.87136654 3.96551673 2.87394931 1 P 0 ;0,1,2=378,3=0.000000
L 3.96551673 2.87394931 3.96896673 2.8755 1 P 0 ;0,1,2=378,3=0.000000
L 3.96896673 2.8755 3.97241663 2.87498337 1 P 0 ;0,1,2=378,3=0.000000
L 3.97241663 2.87498337 3.97586663 2.87291624 1 P 0 ;0,1,2=378,3=0.000000
L 4.229 2.973 4.229 2.899 1 P 0 
L 4.229 2.899 4.105 2.899 1 P 0 
L 4.105 2.899 4.105 2.973 1 P 0 
L 4.105 2.973 4.229 2.973 1 P 0 
L 4.05506673 2.95391624 4.05736693 2.95546683 1 P 0 ;0,1,2=379,3=0.000000
L 4.05736693 2.95546683 4.0600497 2.9565 1 P 0 ;0,1,2=379,3=0.000000
L 4.0600497 2.9565 4.06311644 2.9565 1 P 0 ;0,1,2=379,3=0.000000
L 4.06311644 2.9565 4.06656713 2.95494931 1 P 0 ;0,1,2=379,3=0.000000
L 4.06656713 2.95494931 4.0692499 2.95236654 1 P 0 ;0,1,2=379,3=0.000000
L 4.0692499 2.95236654 4.07116683 2.94926624 1 P 0 ;0,1,2=379,3=0.000000
L 4.07116683 2.94926624 4.07270049 2.9440998 1 P 0 ;0,1,2=379,3=0.000000
L 4.07270049 2.9440998 4.07308376 2.9394498 1 P 0 ;0,1,2=379,3=0.000000
L 4.07308376 2.9394498 4.07231663 2.9347999 1 P 0 ;0,1,2=379,3=0.000000
L 4.07231663 2.9347999 4.07116683 2.93169961 1 P 0 ;0,1,2=379,3=0.000000
L 4.07116683 2.93169961 4.06886663 2.92859931 1 P 0 ;0,1,2=379,3=0.000000
L 4.06886663 2.92859931 4.06618317 2.92653307 1 P 0 ;0,1,2=379,3=0.000000
L 4.06618317 2.92653307 4.06350039 2.9255 1 P 0 ;0,1,2=379,3=0.000000
L 4.06350039 2.9255 4.06081693 2.9255 1 P 0 ;0,1,2=379,3=0.000000
L 4.06081693 2.9255 4.05813346 2.92653307 1 P 0 ;0,1,2=379,3=0.000000
L 4.05813346 2.92653307 4.05583327 2.92808278 1 P 0 ;0,1,2=379,3=0.000000
L 4.05583327 2.92808278 4.05391634 2.93014892 1 P 0 ;0,1,2=379,3=0.000000
L 4.03978356 2.95133346 4.03748337 2.95443278 1 P 0 ;0,1,2=379,3=0.000000
L 4.03748337 2.95443278 4.0347999 2.95598337 1 P 0 ;0,1,2=379,3=0.000000
L 4.0347999 2.95598337 4.03173317 2.9565 1 P 0 ;0,1,2=379,3=0.000000
L 4.03173317 2.9565 4.0279 2.95546683 1 P 0 ;0,1,2=379,3=0.000000
L 4.0279 2.95546683 4.02521654 2.95288307 1 P 0 ;0,1,2=379,3=0.000000
L 4.02521654 2.95288307 4.02445 2.94978376 1 P 0 ;0,1,2=379,3=0.000000
L 4.02445 2.94978376 4.02483327 2.94668258 1 P 0 ;0,1,2=379,3=0.000000
L 4.02483327 2.94668258 4.02636693 2.9440998 1 P 0 ;0,1,2=379,3=0.000000
L 4.02636693 2.9440998 4.03403337 2.93893327 1 P 0 ;0,1,2=379,3=0.000000
L 4.03403337 2.93893327 4.03748337 2.93531644 1 P 0 ;0,1,2=379,3=0.000000
L 4.03748337 2.93531644 4.03978356 2.93014892 1 P 0 ;0,1,2=379,3=0.000000
L 4.03978356 2.93014892 4.0405501 2.9255 1 P 0 ;0,1,2=379,3=0.000000
L 4.0405501 2.9255 4.02445 2.9255 1 P 0 ;0,1,2=379,3=0.000000
L 3.9969 2.9255 3.9969 2.9565 1 P 0 ;0,1,2=379,3=0.000000
L 3.9969 2.9565 4.01108376 2.93428327 1 P 0 ;0,1,2=379,3=0.000000
L 4.01108376 2.93428327 3.99191634 2.93428327 1 P 0 ;0,1,2=379,3=0.000000
L 3.97050039 2.9255 3.97050039 2.9565 1 P 0 ;0,1,2=379,3=0.000000
L 3.97050039 2.9565 3.9751001 2.9503003 1 P 0 ;0,1,2=379,3=0.000000
L 3.9751001 2.9255 3.96590069 2.9255 1 P 0 ;0,1,2=379,3=0.000000
L 3.699 3.047 3.699 2.923 1 P 0 
L 3.625 3.047 3.699 3.047 1 P 0 
L 3.699 2.923 3.625 2.923 1 P 0 
L 3.625 2.923 3.625 3.047 1 P 0 
L 3.73791624 2.96693327 3.73946683 2.96463307 1 P 0 ;0,1,2=380,3=90.000000
L 3.73946683 2.96463307 3.7405 2.9619503 1 P 0 ;0,1,2=380,3=90.000000
L 3.7405 2.9619503 3.7405 2.95888356 1 P 0 ;0,1,2=380,3=90.000000
L 3.7405 2.95888356 3.73894931 2.95543287 1 P 0 ;0,1,2=380,3=90.000000
L 3.73894931 2.95543287 3.73636654 2.9527501 1 P 0 ;0,1,2=380,3=90.000000
L 3.73636654 2.9527501 3.73326624 2.95083317 1 P 0 ;0,1,2=380,3=90.000000
L 3.73326624 2.95083317 3.7280998 2.94929951 1 P 0 ;0,1,2=380,3=90.000000
L 3.7280998 2.94929951 3.7234498 2.94891624 1 P 0 ;0,1,2=380,3=90.000000
L 3.7234498 2.94891624 3.7187999 2.94968337 1 P 0 ;0,1,2=380,3=90.000000
L 3.7187999 2.94968337 3.71569961 2.95083317 1 P 0 ;0,1,2=380,3=90.000000
L 3.71569961 2.95083317 3.71259931 2.95313337 1 P 0 ;0,1,2=380,3=90.000000
L 3.71259931 2.95313337 3.71053307 2.95581683 1 P 0 ;0,1,2=380,3=90.000000
L 3.71053307 2.95581683 3.7095 2.95849961 1 P 0 ;0,1,2=380,3=90.000000
L 3.7095 2.95849961 3.7095 2.96118307 1 P 0 ;0,1,2=380,3=90.000000
L 3.7095 2.96118307 3.71053307 2.96386654 1 P 0 ;0,1,2=380,3=90.000000
L 3.71053307 2.96386654 3.71208278 2.96616673 1 P 0 ;0,1,2=380,3=90.000000
L 3.71208278 2.96616673 3.71414892 2.96808366 1 P 0 ;0,1,2=380,3=90.000000
L 3.7095 2.98949961 3.7405 2.98949961 1 P 0 ;0,1,2=380,3=90.000000
L 3.7405 2.98949961 3.7343003 2.9848999 1 P 0 ;0,1,2=380,3=90.000000
L 3.7095 2.9848999 3.7095 2.99409931 1 P 0 ;0,1,2=380,3=90.000000
L 3.7095 3.02049961 3.71001654 3.02318307 1 P 0 ;0,1,2=380,3=90.000000
L 3.71001654 3.02318307 3.71156614 3.0262498 1 P 0 ;0,1,2=380,3=90.000000
L 3.71156614 3.0262498 3.71414892 3.02816673 1 P 0 ;0,1,2=380,3=90.000000
L 3.71414892 3.02816673 3.71776673 3.02893327 1 P 0 ;0,1,2=380,3=90.000000
L 3.71776673 3.02893327 3.72138268 3.02816673 1 P 0 ;0,1,2=380,3=90.000000
L 3.72138268 3.02816673 3.72448287 3.02586654 1 P 0 ;0,1,2=380,3=90.000000
L 3.72448287 3.02586654 3.72603356 3.02241654 1 P 0 ;0,1,2=380,3=90.000000
L 3.72603356 3.02241654 3.72603356 3.01858337 1 P 0 ;0,1,2=380,3=90.000000
L 3.72603356 3.01858337 3.72706663 3.01628317 1 P 0 ;0,1,2=380,3=90.000000
L 3.72706663 3.01628317 3.72964941 3.01436614 1 P 0 ;0,1,2=380,3=90.000000
L 3.72964941 3.01436614 3.73326624 3.0135997 1 P 0 ;0,1,2=380,3=90.000000
L 3.73326624 3.0135997 3.73688307 3.0147501 1 P 0 ;0,1,2=380,3=90.000000
L 3.73688307 3.0147501 3.73946683 3.01743287 1 P 0 ;0,1,2=380,3=90.000000
L 3.73946683 3.01743287 3.7405 3.02049961 1 P 0 ;0,1,2=380,3=90.000000
L 3.7405 3.02049961 3.73946683 3.02356634 1 P 0 ;0,1,2=380,3=90.000000
L 3.73946683 3.02356634 3.73688307 3.0262498 1 P 0 ;0,1,2=380,3=90.000000
L 3.73688307 3.0262498 3.73326624 3.0274002 1 P 0 ;0,1,2=380,3=90.000000
L 3.73326624 3.0274002 3.72964941 3.02663307 1 P 0 ;0,1,2=380,3=90.000000
L 3.72964941 3.02663307 3.72706663 3.02471673 1 P 0 ;0,1,2=380,3=90.000000
L 3.72706663 3.02471673 3.72603356 3.02241654 1 P 0 ;0,1,2=380,3=90.000000
L 3.72603356 3.02241654 3.72603356 3.01858337 1 P 0 ;0,1,2=380,3=90.000000
L 3.72603356 3.01858337 3.72448287 3.01513337 1 P 0 ;0,1,2=380,3=90.000000
L 3.72448287 3.01513337 3.72138268 3.01283317 1 P 0 ;0,1,2=380,3=90.000000
L 3.72138268 3.01283317 3.71776673 3.01206663 1 P 0 ;0,1,2=380,3=90.000000
L 3.71776673 3.01206663 3.71414892 3.01283317 1 P 0 ;0,1,2=380,3=90.000000
L 3.71414892 3.01283317 3.71156614 3.0147501 1 P 0 ;0,1,2=380,3=90.000000
L 3.71156614 3.0147501 3.71001654 3.01781683 1 P 0 ;0,1,2=380,3=90.000000
L 3.71001654 3.01781683 3.7095 3.02049961 1 P 0 ;0,1,2=380,3=90.000000
L 3.7405 3.05149961 3.73946683 3.04843287 1 P 0 ;0,1,2=380,3=90.000000
L 3.73946683 3.04843287 3.73688307 3.04613337 1 P 0 ;0,1,2=380,3=90.000000
L 3.73688307 3.04613337 3.73378376 3.0445997 1 P 0 ;0,1,2=380,3=90.000000
L 3.73378376 3.0445997 3.72964941 3.0434499 1 P 0 ;0,1,2=380,3=90.000000
L 3.72964941 3.0434499 3.72499951 3.04306663 1 P 0 ;0,1,2=380,3=90.000000
L 3.72499951 3.04306663 3.72034951 3.0434499 1 P 0 ;0,1,2=380,3=90.000000
L 3.72034951 3.0434499 3.71621614 3.0445997 1 P 0 ;0,1,2=380,3=90.000000
L 3.71621614 3.0445997 3.71311585 3.04613337 1 P 0 ;0,1,2=380,3=90.000000
L 3.71311585 3.04613337 3.71053307 3.04843287 1 P 0 ;0,1,2=380,3=90.000000
L 3.71053307 3.04843287 3.7095 3.05149961 1 P 0 ;0,1,2=380,3=90.000000
L 3.7095 3.05149961 3.71053307 3.05456634 1 P 0 ;0,1,2=380,3=90.000000
L 3.71053307 3.05456634 3.71311585 3.05686654 1 P 0 ;0,1,2=380,3=90.000000
L 3.71311585 3.05686654 3.71621614 3.0584002 1 P 0 ;0,1,2=380,3=90.000000
L 3.71621614 3.0584002 3.72034951 3.05955 1 P 0 ;0,1,2=380,3=90.000000
L 3.72034951 3.05955 3.72499951 3.05993327 1 P 0 ;0,1,2=380,3=90.000000
L 3.72499951 3.05993327 3.72964941 3.05955 1 P 0 ;0,1,2=380,3=90.000000
L 3.72964941 3.05955 3.73378376 3.0584002 1 P 0 ;0,1,2=380,3=90.000000
L 3.73378376 3.0584002 3.73688307 3.05686654 1 P 0 ;0,1,2=380,3=90.000000
L 3.73688307 3.05686654 3.73946683 3.05456634 1 P 0 ;0,1,2=380,3=90.000000
L 3.73946683 3.05456634 3.7405 3.05149961 1 P 0 ;0,1,2=380,3=90.000000
L 5.109 2.491 5.109 2.417 1 P 0 
L 4.985 2.491 5.109 2.491 1 P 0 
L 5.109 2.417 4.985 2.417 1 P 0 
L 4.985 2.417 4.985 2.491 1 P 0 
L 5.05306673 2.53791624 5.05536693 2.53946683 1 P 0 ;0,1,2=381,3=0.000000
L 5.05536693 2.53946683 5.0580497 2.5405 1 P 0 ;0,1,2=381,3=0.000000
L 5.0580497 2.5405 5.06111644 2.5405 1 P 0 ;0,1,2=381,3=0.000000
L 5.06111644 2.5405 5.06456713 2.53894931 1 P 0 ;0,1,2=381,3=0.000000
L 5.06456713 2.53894931 5.0672499 2.53636654 1 P 0 ;0,1,2=381,3=0.000000
L 5.0672499 2.53636654 5.06916683 2.53326624 1 P 0 ;0,1,2=381,3=0.000000
L 5.06916683 2.53326624 5.07070049 2.5280998 1 P 0 ;0,1,2=381,3=0.000000
L 5.07070049 2.5280998 5.07108376 2.5234498 1 P 0 ;0,1,2=381,3=0.000000
L 5.07108376 2.5234498 5.07031663 2.5187999 1 P 0 ;0,1,2=381,3=0.000000
L 5.07031663 2.5187999 5.06916683 2.51569961 1 P 0 ;0,1,2=381,3=0.000000
L 5.06916683 2.51569961 5.06686663 2.51259931 1 P 0 ;0,1,2=381,3=0.000000
L 5.06686663 2.51259931 5.06418317 2.51053307 1 P 0 ;0,1,2=381,3=0.000000
L 5.06418317 2.51053307 5.06150039 2.5095 1 P 0 ;0,1,2=381,3=0.000000
L 5.06150039 2.5095 5.05881693 2.5095 1 P 0 ;0,1,2=381,3=0.000000
L 5.05881693 2.5095 5.05613346 2.51053307 1 P 0 ;0,1,2=381,3=0.000000
L 5.05613346 2.51053307 5.05383327 2.51208278 1 P 0 ;0,1,2=381,3=0.000000
L 5.05383327 2.51208278 5.05191634 2.51414892 1 P 0 ;0,1,2=381,3=0.000000
L 5.03050039 2.5095 5.03050039 2.5405 1 P 0 ;0,1,2=381,3=0.000000
L 5.03050039 2.5405 5.0351001 2.5343003 1 P 0 ;0,1,2=381,3=0.000000
L 5.0351001 2.5095 5.02590069 2.5095 1 P 0 ;0,1,2=381,3=0.000000
L 4.99950039 2.5095 4.99681693 2.51001654 1 P 0 ;0,1,2=381,3=0.000000
L 4.99681693 2.51001654 4.9937502 2.51156614 1 P 0 ;0,1,2=381,3=0.000000
L 4.9937502 2.51156614 4.99183327 2.51414892 1 P 0 ;0,1,2=381,3=0.000000
L 4.99183327 2.51414892 4.99106673 2.51776673 1 P 0 ;0,1,2=381,3=0.000000
L 4.99106673 2.51776673 4.99183327 2.52138268 1 P 0 ;0,1,2=381,3=0.000000
L 4.99183327 2.52138268 4.99413346 2.52448287 1 P 0 ;0,1,2=381,3=0.000000
L 4.99413346 2.52448287 4.99758346 2.52603356 1 P 0 ;0,1,2=381,3=0.000000
L 4.99758346 2.52603356 5.00141663 2.52603356 1 P 0 ;0,1,2=381,3=0.000000
L 5.00141663 2.52603356 5.00371683 2.52706663 1 P 0 ;0,1,2=381,3=0.000000
L 5.00371683 2.52706663 5.00563386 2.52964941 1 P 0 ;0,1,2=381,3=0.000000
L 5.00563386 2.52964941 5.0064003 2.53326624 1 P 0 ;0,1,2=381,3=0.000000
L 5.0064003 2.53326624 5.0052499 2.53688307 1 P 0 ;0,1,2=381,3=0.000000
L 5.0052499 2.53688307 5.00256713 2.53946683 1 P 0 ;0,1,2=381,3=0.000000
L 5.00256713 2.53946683 4.99950039 2.5405 1 P 0 ;0,1,2=381,3=0.000000
L 4.99950039 2.5405 4.99643366 2.53946683 1 P 0 ;0,1,2=381,3=0.000000
L 4.99643366 2.53946683 4.9937502 2.53688307 1 P 0 ;0,1,2=381,3=0.000000
L 4.9937502 2.53688307 4.9925998 2.53326624 1 P 0 ;0,1,2=381,3=0.000000
L 4.9925998 2.53326624 4.99336693 2.52964941 1 P 0 ;0,1,2=381,3=0.000000
L 4.99336693 2.52964941 4.99528327 2.52706663 1 P 0 ;0,1,2=381,3=0.000000
L 4.99528327 2.52706663 4.99758346 2.52603356 1 P 0 ;0,1,2=381,3=0.000000
L 4.99758346 2.52603356 5.00141663 2.52603356 1 P 0 ;0,1,2=381,3=0.000000
L 5.00141663 2.52603356 5.00486663 2.52448287 1 P 0 ;0,1,2=381,3=0.000000
L 5.00486663 2.52448287 5.00716683 2.52138268 1 P 0 ;0,1,2=381,3=0.000000
L 5.00716683 2.52138268 5.00793337 2.51776673 1 P 0 ;0,1,2=381,3=0.000000
L 5.00793337 2.51776673 5.00716683 2.51414892 1 P 0 ;0,1,2=381,3=0.000000
L 5.00716683 2.51414892 5.0052499 2.51156614 1 P 0 ;0,1,2=381,3=0.000000
L 5.0052499 2.51156614 5.00218317 2.51001654 1 P 0 ;0,1,2=381,3=0.000000
L 5.00218317 2.51001654 4.99950039 2.5095 1 P 0 ;0,1,2=381,3=0.000000
L 4.96850039 2.5095 4.96850039 2.5405 1 P 0 ;0,1,2=381,3=0.000000
L 4.96850039 2.5405 4.9731001 2.5343003 1 P 0 ;0,1,2=381,3=0.000000
L 4.9731001 2.5095 4.96390069 2.5095 1 P 0 ;0,1,2=381,3=0.000000
L 3.748 0.745 3.748 0.835 1 P 0 
L 3.792 0.745 3.748 0.745 1 P 0 
L 3.792 0.835 3.792 0.745 1 P 0 
L 3.748 0.835 3.792 0.835 1 P 0 
L 3.86791624 0.73693327 3.86946683 0.73463307 1 P 0 ;0,1,2=382,3=90.000000
L 3.86946683 0.73463307 3.8705 0.7319503 1 P 0 ;0,1,2=382,3=90.000000
L 3.8705 0.7319503 3.8705 0.72888356 1 P 0 ;0,1,2=382,3=90.000000
L 3.8705 0.72888356 3.86894931 0.72543287 1 P 0 ;0,1,2=382,3=90.000000
L 3.86894931 0.72543287 3.86636654 0.7227501 1 P 0 ;0,1,2=382,3=90.000000
L 3.86636654 0.7227501 3.86326624 0.72083317 1 P 0 ;0,1,2=382,3=90.000000
L 3.86326624 0.72083317 3.8580998 0.71929951 1 P 0 ;0,1,2=382,3=90.000000
L 3.8580998 0.71929951 3.8534498 0.71891624 1 P 0 ;0,1,2=382,3=90.000000
L 3.8534498 0.71891624 3.8487999 0.71968337 1 P 0 ;0,1,2=382,3=90.000000
L 3.8487999 0.71968337 3.84569961 0.72083317 1 P 0 ;0,1,2=382,3=90.000000
L 3.84569961 0.72083317 3.84259931 0.72313337 1 P 0 ;0,1,2=382,3=90.000000
L 3.84259931 0.72313337 3.84053307 0.72581683 1 P 0 ;0,1,2=382,3=90.000000
L 3.84053307 0.72581683 3.8395 0.72849961 1 P 0 ;0,1,2=382,3=90.000000
L 3.8395 0.72849961 3.8395 0.73118307 1 P 0 ;0,1,2=382,3=90.000000
L 3.8395 0.73118307 3.84053307 0.73386654 1 P 0 ;0,1,2=382,3=90.000000
L 3.84053307 0.73386654 3.84208278 0.73616673 1 P 0 ;0,1,2=382,3=90.000000
L 3.84208278 0.73616673 3.84414892 0.73808366 1 P 0 ;0,1,2=382,3=90.000000
L 3.86533346 0.75221644 3.86843278 0.75451663 1 P 0 ;0,1,2=382,3=90.000000
L 3.86843278 0.75451663 3.86998337 0.7572001 1 P 0 ;0,1,2=382,3=90.000000
L 3.86998337 0.7572001 3.8705 0.76026683 1 P 0 ;0,1,2=382,3=90.000000
L 3.8705 0.76026683 3.86946683 0.7641 1 P 0 ;0,1,2=382,3=90.000000
L 3.86946683 0.7641 3.86688307 0.76678346 1 P 0 ;0,1,2=382,3=90.000000
L 3.86688307 0.76678346 3.86378376 0.76755 1 P 0 ;0,1,2=382,3=90.000000
L 3.86378376 0.76755 3.86068258 0.76716673 1 P 0 ;0,1,2=382,3=90.000000
L 3.86068258 0.76716673 3.8580998 0.76563307 1 P 0 ;0,1,2=382,3=90.000000
L 3.8580998 0.76563307 3.85293327 0.75796663 1 P 0 ;0,1,2=382,3=90.000000
L 3.85293327 0.75796663 3.84931644 0.75451663 1 P 0 ;0,1,2=382,3=90.000000
L 3.84931644 0.75451663 3.84414892 0.75221644 1 P 0 ;0,1,2=382,3=90.000000
L 3.84414892 0.75221644 3.8395 0.7514499 1 P 0 ;0,1,2=382,3=90.000000
L 3.8395 0.7514499 3.8395 0.76755 1 P 0 ;0,1,2=382,3=90.000000
L 3.8395 0.7951 3.8705 0.7951 1 P 0 ;0,1,2=382,3=90.000000
L 3.8705 0.7951 3.84828327 0.78091624 1 P 0 ;0,1,2=382,3=90.000000
L 3.84828327 0.78091624 3.84828327 0.80008366 1 P 0 ;0,1,2=382,3=90.000000
L 3.84414892 0.81306663 3.84156614 0.81536614 1 P 0 ;0,1,2=382,3=90.000000
L 3.84156614 0.81536614 3.84001654 0.81804961 1 P 0 ;0,1,2=382,3=90.000000
L 3.84001654 0.81804961 3.8395 0.82149961 1 P 0 ;0,1,2=382,3=90.000000
L 3.8395 0.82149961 3.84053307 0.8249503 1 P 0 ;0,1,2=382,3=90.000000
L 3.84053307 0.8249503 3.84259931 0.82763307 1 P 0 ;0,1,2=382,3=90.000000
L 3.84259931 0.82763307 3.84621614 0.82955 1 P 0 ;0,1,2=382,3=90.000000
L 3.84621614 0.82955 3.85034951 0.82993327 1 P 0 ;0,1,2=382,3=90.000000
L 3.85034951 0.82993327 3.85448287 0.82916673 1 P 0 ;0,1,2=382,3=90.000000
L 3.85448287 0.82916673 3.85706663 0.8272498 1 P 0 ;0,1,2=382,3=90.000000
L 3.85706663 0.8272498 3.85913287 0.82456634 1 P 0 ;0,1,2=382,3=90.000000
L 3.85913287 0.82456634 3.85964941 0.82188356 1 P 0 ;0,1,2=382,3=90.000000
L 3.85964941 0.82188356 3.85913287 0.8192001 1 P 0 ;0,1,2=382,3=90.000000
L 3.85913287 0.8192001 3.85706663 0.8157501 1 P 0 ;0,1,2=382,3=90.000000
L 3.85706663 0.8157501 3.8705 0.8168999 1 P 0 ;0,1,2=382,3=90.000000
L 3.8705 0.8168999 3.8705 0.8272498 1 P 0 ;0,1,2=382,3=90.000000
L 3.498 1.4 3.542 1.4 1 P 0 
L 3.498 1.31 3.498 1.4 1 P 0 
L 3.542 1.31 3.498 1.31 1 P 0 
L 3.542 1.4 3.542 1.31 1 P 0 
L 3.53841624 1.16193327 3.53996683 1.15963307 1 P 0 ;0,1,2=383,3=90.000000
L 3.53996683 1.15963307 3.541 1.1569503 1 P 0 ;0,1,2=383,3=90.000000
L 3.541 1.1569503 3.541 1.15388356 1 P 0 ;0,1,2=383,3=90.000000
L 3.541 1.15388356 3.53944931 1.15043287 1 P 0 ;0,1,2=383,3=90.000000
L 3.53944931 1.15043287 3.53686654 1.1477501 1 P 0 ;0,1,2=383,3=90.000000
L 3.53686654 1.1477501 3.53376624 1.14583317 1 P 0 ;0,1,2=383,3=90.000000
L 3.53376624 1.14583317 3.5285998 1.14429951 1 P 0 ;0,1,2=383,3=90.000000
L 3.5285998 1.14429951 3.5239498 1.14391624 1 P 0 ;0,1,2=383,3=90.000000
L 3.5239498 1.14391624 3.5192999 1.14468337 1 P 0 ;0,1,2=383,3=90.000000
L 3.5192999 1.14468337 3.51619961 1.14583317 1 P 0 ;0,1,2=383,3=90.000000
L 3.51619961 1.14583317 3.51309931 1.14813337 1 P 0 ;0,1,2=383,3=90.000000
L 3.51309931 1.14813337 3.51103307 1.15081683 1 P 0 ;0,1,2=383,3=90.000000
L 3.51103307 1.15081683 3.51 1.15349961 1 P 0 ;0,1,2=383,3=90.000000
L 3.51 1.15349961 3.51 1.15618307 1 P 0 ;0,1,2=383,3=90.000000
L 3.51 1.15618307 3.51103307 1.15886654 1 P 0 ;0,1,2=383,3=90.000000
L 3.51103307 1.15886654 3.51258278 1.16116673 1 P 0 ;0,1,2=383,3=90.000000
L 3.51258278 1.16116673 3.51464892 1.16308366 1 P 0 ;0,1,2=383,3=90.000000
L 3.51 1.18449961 3.541 1.18449961 1 P 0 ;0,1,2=383,3=90.000000
L 3.541 1.18449961 3.5348003 1.1798999 1 P 0 ;0,1,2=383,3=90.000000
L 3.51 1.1798999 3.51 1.18909931 1 P 0 ;0,1,2=383,3=90.000000
L 3.51619961 1.20706663 3.51258278 1.20936614 1 P 0 ;0,1,2=383,3=90.000000
L 3.51258278 1.20936614 3.51051654 1.21243287 1 P 0 ;0,1,2=383,3=90.000000
L 3.51051654 1.21243287 3.51 1.21588356 1 P 0 ;0,1,2=383,3=90.000000
L 3.51 1.21588356 3.51051654 1.2189503 1 P 0 ;0,1,2=383,3=90.000000
L 3.51051654 1.2189503 3.51309931 1.22201703 1 P 0 ;0,1,2=383,3=90.000000
L 3.51309931 1.22201703 3.51619961 1.22393327 1 P 0 ;0,1,2=383,3=90.000000
L 3.51619961 1.22393327 3.5192999 1.22431654 1 P 0 ;0,1,2=383,3=90.000000
L 3.5192999 1.22431654 3.52291575 1.22355 1 P 0 ;0,1,2=383,3=90.000000
L 3.52291575 1.22355 3.52549951 1.22086654 1 P 0 ;0,1,2=383,3=90.000000
L 3.52549951 1.22086654 3.52653356 1.21818307 1 P 0 ;0,1,2=383,3=90.000000
L 3.52653356 1.21818307 3.52653356 1.21473307 1 P 0 ;0,1,2=383,3=90.000000
L 3.52653356 1.21818307 3.52808317 1.22048327 1 P 0 ;0,1,2=383,3=90.000000
L 3.52808317 1.22048327 3.53066594 1.2224002 1 P 0 ;0,1,2=383,3=90.000000
L 3.53066594 1.2224002 3.53376624 1.22316673 1 P 0 ;0,1,2=383,3=90.000000
L 3.53376624 1.22316673 3.53686654 1.2224002 1 P 0 ;0,1,2=383,3=90.000000
L 3.53686654 1.2224002 3.53944931 1.22048327 1 P 0 ;0,1,2=383,3=90.000000
L 3.53944931 1.22048327 3.541 1.21703327 1 P 0 ;0,1,2=383,3=90.000000
L 3.541 1.21703327 3.54048337 1.21358337 1 P 0 ;0,1,2=383,3=90.000000
L 3.54048337 1.21358337 3.53841624 1.21013337 1 P 0 ;0,1,2=383,3=90.000000
L 3.52291575 1.23921644 3.52653356 1.2418999 1 P 0 ;0,1,2=383,3=90.000000
L 3.52653356 1.2418999 3.5285998 1.2442001 1 P 0 ;0,1,2=383,3=90.000000
L 3.5285998 1.2442001 3.52963287 1.24726683 1 P 0 ;0,1,2=383,3=90.000000
L 3.52963287 1.24726683 3.5285998 1.2499503 1 P 0 ;0,1,2=383,3=90.000000
L 3.5285998 1.2499503 3.52653356 1.25186654 1 P 0 ;0,1,2=383,3=90.000000
L 3.52653356 1.25186654 3.52343327 1.2534002 1 P 0 ;0,1,2=383,3=90.000000
L 3.52343327 1.2534002 3.51981644 1.25378346 1 P 0 ;0,1,2=383,3=90.000000
L 3.51981644 1.25378346 3.51671614 1.2534002 1 P 0 ;0,1,2=383,3=90.000000
L 3.51671614 1.2534002 3.51361585 1.25186654 1 P 0 ;0,1,2=383,3=90.000000
L 3.51361585 1.25186654 3.51103307 1.24956634 1 P 0 ;0,1,2=383,3=90.000000
L 3.51103307 1.24956634 3.51 1.24688356 1 P 0 ;0,1,2=383,3=90.000000
L 3.51 1.24688356 3.51103307 1.24381683 1 P 0 ;0,1,2=383,3=90.000000
L 3.51103307 1.24381683 3.51413238 1.24113337 1 P 0 ;0,1,2=383,3=90.000000
L 3.51413238 1.24113337 3.51878327 1.2395997 1 P 0 ;0,1,2=383,3=90.000000
L 3.51878327 1.2395997 3.5239498 1.23921644 1 P 0 ;0,1,2=383,3=90.000000
L 3.5239498 1.23921644 3.53066594 1.23998287 1 P 0 ;0,1,2=383,3=90.000000
L 3.53066594 1.23998287 3.53428376 1.24113337 1 P 0 ;0,1,2=383,3=90.000000
L 3.53428376 1.24113337 3.5378997 1.24304961 1 P 0 ;0,1,2=383,3=90.000000
L 3.5378997 1.24304961 3.54048337 1.24573307 1 P 0 ;0,1,2=383,3=90.000000
L 3.54048337 1.24573307 3.541 1.24841654 1 P 0 ;0,1,2=383,3=90.000000
L 3.541 1.24841654 3.53996683 1.2511 1 P 0 ;0,1,2=383,3=90.000000
L 3.53996683 1.2511 3.53738307 1.25301703 1 P 0 ;0,1,2=383,3=90.000000
L 3.04503002 0.56 3.00103002 0.56 1 P 0 
L 3.04503002 0.65 3.04503002 0.56 1 P 0 
L 3.00103002 0.56 3.00103002 0.65 1 P 0 
L 3.00103002 0.65 3.04503002 0.65 1 P 0 
L 3.12291624 0.65243327 3.12446683 0.65013307 1 P 0 ;0,1,2=384,3=90.000000
L 3.12446683 0.65013307 3.1255 0.6474503 1 P 0 ;0,1,2=384,3=90.000000
L 3.1255 0.6474503 3.1255 0.64438356 1 P 0 ;0,1,2=384,3=90.000000
L 3.1255 0.64438356 3.12394931 0.64093287 1 P 0 ;0,1,2=384,3=90.000000
L 3.12394931 0.64093287 3.12136654 0.6382501 1 P 0 ;0,1,2=384,3=90.000000
L 3.12136654 0.6382501 3.11826624 0.63633317 1 P 0 ;0,1,2=384,3=90.000000
L 3.11826624 0.63633317 3.1130998 0.63479951 1 P 0 ;0,1,2=384,3=90.000000
L 3.1130998 0.63479951 3.1084498 0.63441624 1 P 0 ;0,1,2=384,3=90.000000
L 3.1084498 0.63441624 3.1037999 0.63518337 1 P 0 ;0,1,2=384,3=90.000000
L 3.1037999 0.63518337 3.10069961 0.63633317 1 P 0 ;0,1,2=384,3=90.000000
L 3.10069961 0.63633317 3.09759931 0.63863337 1 P 0 ;0,1,2=384,3=90.000000
L 3.09759931 0.63863337 3.09553307 0.64131683 1 P 0 ;0,1,2=384,3=90.000000
L 3.09553307 0.64131683 3.0945 0.64399961 1 P 0 ;0,1,2=384,3=90.000000
L 3.0945 0.64399961 3.0945 0.64668307 1 P 0 ;0,1,2=384,3=90.000000
L 3.0945 0.64668307 3.09553307 0.64936654 1 P 0 ;0,1,2=384,3=90.000000
L 3.09553307 0.64936654 3.09708278 0.65166673 1 P 0 ;0,1,2=384,3=90.000000
L 3.09708278 0.65166673 3.09914892 0.65358366 1 P 0 ;0,1,2=384,3=90.000000
L 3.10069961 0.66656663 3.09708278 0.66886614 1 P 0 ;0,1,2=384,3=90.000000
L 3.09708278 0.66886614 3.09501654 0.67193287 1 P 0 ;0,1,2=384,3=90.000000
L 3.09501654 0.67193287 3.0945 0.67538356 1 P 0 ;0,1,2=384,3=90.000000
L 3.0945 0.67538356 3.09501654 0.6784503 1 P 0 ;0,1,2=384,3=90.000000
L 3.09501654 0.6784503 3.09759931 0.68151703 1 P 0 ;0,1,2=384,3=90.000000
L 3.09759931 0.68151703 3.10069961 0.68343327 1 P 0 ;0,1,2=384,3=90.000000
L 3.10069961 0.68343327 3.1037999 0.68381654 1 P 0 ;0,1,2=384,3=90.000000
L 3.1037999 0.68381654 3.10741575 0.68305 1 P 0 ;0,1,2=384,3=90.000000
L 3.10741575 0.68305 3.10999951 0.68036654 1 P 0 ;0,1,2=384,3=90.000000
L 3.10999951 0.68036654 3.11103356 0.67768307 1 P 0 ;0,1,2=384,3=90.000000
L 3.11103356 0.67768307 3.11103356 0.67423307 1 P 0 ;0,1,2=384,3=90.000000
L 3.11103356 0.67768307 3.11258317 0.67998327 1 P 0 ;0,1,2=384,3=90.000000
L 3.11258317 0.67998327 3.11516594 0.6819002 1 P 0 ;0,1,2=384,3=90.000000
L 3.11516594 0.6819002 3.11826624 0.68266673 1 P 0 ;0,1,2=384,3=90.000000
L 3.11826624 0.68266673 3.12136654 0.6819002 1 P 0 ;0,1,2=384,3=90.000000
L 3.12136654 0.6819002 3.12394931 0.67998327 1 P 0 ;0,1,2=384,3=90.000000
L 3.12394931 0.67998327 3.1255 0.67653327 1 P 0 ;0,1,2=384,3=90.000000
L 3.1255 0.67653327 3.12498337 0.67308337 1 P 0 ;0,1,2=384,3=90.000000
L 3.12498337 0.67308337 3.12291624 0.66963337 1 P 0 ;0,1,2=384,3=90.000000
L 3.10741575 0.69871644 3.11103356 0.7013999 1 P 0 ;0,1,2=384,3=90.000000
L 3.11103356 0.7013999 3.1130998 0.7037001 1 P 0 ;0,1,2=384,3=90.000000
L 3.1130998 0.7037001 3.11413287 0.70676683 1 P 0 ;0,1,2=384,3=90.000000
L 3.11413287 0.70676683 3.1130998 0.7094503 1 P 0 ;0,1,2=384,3=90.000000
L 3.1130998 0.7094503 3.11103356 0.71136654 1 P 0 ;0,1,2=384,3=90.000000
L 3.11103356 0.71136654 3.10793327 0.7129002 1 P 0 ;0,1,2=384,3=90.000000
L 3.10793327 0.7129002 3.10431644 0.71328346 1 P 0 ;0,1,2=384,3=90.000000
L 3.10431644 0.71328346 3.10121614 0.7129002 1 P 0 ;0,1,2=384,3=90.000000
L 3.10121614 0.7129002 3.09811585 0.71136654 1 P 0 ;0,1,2=384,3=90.000000
L 3.09811585 0.71136654 3.09553307 0.70906634 1 P 0 ;0,1,2=384,3=90.000000
L 3.09553307 0.70906634 3.0945 0.70638356 1 P 0 ;0,1,2=384,3=90.000000
L 3.0945 0.70638356 3.09553307 0.70331683 1 P 0 ;0,1,2=384,3=90.000000
L 3.09553307 0.70331683 3.09863238 0.70063337 1 P 0 ;0,1,2=384,3=90.000000
L 3.09863238 0.70063337 3.10328327 0.6990997 1 P 0 ;0,1,2=384,3=90.000000
L 3.10328327 0.6990997 3.1084498 0.69871644 1 P 0 ;0,1,2=384,3=90.000000
L 3.1084498 0.69871644 3.11516594 0.69948287 1 P 0 ;0,1,2=384,3=90.000000
L 3.11516594 0.69948287 3.11878376 0.70063337 1 P 0 ;0,1,2=384,3=90.000000
L 3.11878376 0.70063337 3.1223997 0.70254961 1 P 0 ;0,1,2=384,3=90.000000
L 3.1223997 0.70254961 3.12498337 0.70523307 1 P 0 ;0,1,2=384,3=90.000000
L 3.12498337 0.70523307 3.1255 0.70791654 1 P 0 ;0,1,2=384,3=90.000000
L 3.1255 0.70791654 3.12446683 0.7106 1 P 0 ;0,1,2=384,3=90.000000
L 3.12446683 0.7106 3.12188307 0.71251703 1 P 0 ;0,1,2=384,3=90.000000
L 2.99503002 0.56 2.95103002 0.56 1 P 0 
L 2.99503002 0.65 2.99503002 0.56 1 P 0 
L 2.95103002 0.56 2.95103002 0.65 1 P 0 
L 2.95103002 0.65 2.99503002 0.65 1 P 0 
L 3.08091624 0.65243327 3.08246683 0.65013307 1 P 0 ;0,1,2=385,3=90.000000
L 3.08246683 0.65013307 3.0835 0.6474503 1 P 0 ;0,1,2=385,3=90.000000
L 3.0835 0.6474503 3.0835 0.64438356 1 P 0 ;0,1,2=385,3=90.000000
L 3.0835 0.64438356 3.08194931 0.64093287 1 P 0 ;0,1,2=385,3=90.000000
L 3.08194931 0.64093287 3.07936654 0.6382501 1 P 0 ;0,1,2=385,3=90.000000
L 3.07936654 0.6382501 3.07626624 0.63633317 1 P 0 ;0,1,2=385,3=90.000000
L 3.07626624 0.63633317 3.0710998 0.63479951 1 P 0 ;0,1,2=385,3=90.000000
L 3.0710998 0.63479951 3.0664498 0.63441624 1 P 0 ;0,1,2=385,3=90.000000
L 3.0664498 0.63441624 3.0617999 0.63518337 1 P 0 ;0,1,2=385,3=90.000000
L 3.0617999 0.63518337 3.05869961 0.63633317 1 P 0 ;0,1,2=385,3=90.000000
L 3.05869961 0.63633317 3.05559931 0.63863337 1 P 0 ;0,1,2=385,3=90.000000
L 3.05559931 0.63863337 3.05353307 0.64131683 1 P 0 ;0,1,2=385,3=90.000000
L 3.05353307 0.64131683 3.0525 0.64399961 1 P 0 ;0,1,2=385,3=90.000000
L 3.0525 0.64399961 3.0525 0.64668307 1 P 0 ;0,1,2=385,3=90.000000
L 3.0525 0.64668307 3.05353307 0.64936654 1 P 0 ;0,1,2=385,3=90.000000
L 3.05353307 0.64936654 3.05508278 0.65166673 1 P 0 ;0,1,2=385,3=90.000000
L 3.05508278 0.65166673 3.05714892 0.65358366 1 P 0 ;0,1,2=385,3=90.000000
L 3.05869961 0.66656663 3.05508278 0.66886614 1 P 0 ;0,1,2=385,3=90.000000
L 3.05508278 0.66886614 3.05301654 0.67193287 1 P 0 ;0,1,2=385,3=90.000000
L 3.05301654 0.67193287 3.0525 0.67538356 1 P 0 ;0,1,2=385,3=90.000000
L 3.0525 0.67538356 3.05301654 0.6784503 1 P 0 ;0,1,2=385,3=90.000000
L 3.05301654 0.6784503 3.05559931 0.68151703 1 P 0 ;0,1,2=385,3=90.000000
L 3.05559931 0.68151703 3.05869961 0.68343327 1 P 0 ;0,1,2=385,3=90.000000
L 3.05869961 0.68343327 3.0617999 0.68381654 1 P 0 ;0,1,2=385,3=90.000000
L 3.0617999 0.68381654 3.06541575 0.68305 1 P 0 ;0,1,2=385,3=90.000000
L 3.06541575 0.68305 3.06799951 0.68036654 1 P 0 ;0,1,2=385,3=90.000000
L 3.06799951 0.68036654 3.06903356 0.67768307 1 P 0 ;0,1,2=385,3=90.000000
L 3.06903356 0.67768307 3.06903356 0.67423307 1 P 0 ;0,1,2=385,3=90.000000
L 3.06903356 0.67768307 3.07058317 0.67998327 1 P 0 ;0,1,2=385,3=90.000000
L 3.07058317 0.67998327 3.07316594 0.6819002 1 P 0 ;0,1,2=385,3=90.000000
L 3.07316594 0.6819002 3.07626624 0.68266673 1 P 0 ;0,1,2=385,3=90.000000
L 3.07626624 0.68266673 3.07936654 0.6819002 1 P 0 ;0,1,2=385,3=90.000000
L 3.07936654 0.6819002 3.08194931 0.67998327 1 P 0 ;0,1,2=385,3=90.000000
L 3.08194931 0.67998327 3.0835 0.67653327 1 P 0 ;0,1,2=385,3=90.000000
L 3.0835 0.67653327 3.08298337 0.67308337 1 P 0 ;0,1,2=385,3=90.000000
L 3.08298337 0.67308337 3.08091624 0.66963337 1 P 0 ;0,1,2=385,3=90.000000
L 3.05714892 0.69756663 3.05456614 0.69986614 1 P 0 ;0,1,2=385,3=90.000000
L 3.05456614 0.69986614 3.05301654 0.70254961 1 P 0 ;0,1,2=385,3=90.000000
L 3.05301654 0.70254961 3.0525 0.70599961 1 P 0 ;0,1,2=385,3=90.000000
L 3.0525 0.70599961 3.05353307 0.7094503 1 P 0 ;0,1,2=385,3=90.000000
L 3.05353307 0.7094503 3.05559931 0.71213307 1 P 0 ;0,1,2=385,3=90.000000
L 3.05559931 0.71213307 3.05921614 0.71405 1 P 0 ;0,1,2=385,3=90.000000
L 3.05921614 0.71405 3.06334951 0.71443327 1 P 0 ;0,1,2=385,3=90.000000
L 3.06334951 0.71443327 3.06748287 0.71366673 1 P 0 ;0,1,2=385,3=90.000000
L 3.06748287 0.71366673 3.07006663 0.7117498 1 P 0 ;0,1,2=385,3=90.000000
L 3.07006663 0.7117498 3.07213287 0.70906634 1 P 0 ;0,1,2=385,3=90.000000
L 3.07213287 0.70906634 3.07264941 0.70638356 1 P 0 ;0,1,2=385,3=90.000000
L 3.07264941 0.70638356 3.07213287 0.7037001 1 P 0 ;0,1,2=385,3=90.000000
L 3.07213287 0.7037001 3.07006663 0.7002501 1 P 0 ;0,1,2=385,3=90.000000
L 3.07006663 0.7002501 3.0835 0.7013999 1 P 0 ;0,1,2=385,3=90.000000
L 3.0835 0.7013999 3.0835 0.7117498 1 P 0 ;0,1,2=385,3=90.000000
L 2.87255 0.56 2.82855 0.56 1 P 0 
L 2.87255 0.65 2.87255 0.56 1 P 0 
L 2.82855 0.56 2.82855 0.65 1 P 0 
L 2.82855 0.65 2.87255 0.65 1 P 0 
L 2.86541634 0.49886663 2.86666683 0.49726644 1 P 0 ;0,1,2=386,3=90.000000
L 2.86666683 0.49726644 2.8675 0.4954002 1 P 0 ;0,1,2=386,3=90.000000
L 2.8675 0.4954002 2.8675 0.49326683 1 P 0 ;0,1,2=386,3=90.000000
L 2.8675 0.49326683 2.86624941 0.49086634 1 P 0 ;0,1,2=386,3=90.000000
L 2.86624941 0.49086634 2.86416654 0.4890001 1 P 0 ;0,1,2=386,3=90.000000
L 2.86416654 0.4890001 2.86166634 0.48766654 1 P 0 ;0,1,2=386,3=90.000000
L 2.86166634 0.48766654 2.8574998 0.48659961 1 P 0 ;0,1,2=386,3=90.000000
L 2.8574998 0.48659961 2.8537498 0.48633297 1 P 0 ;0,1,2=386,3=90.000000
L 2.8537498 0.48633297 2.8499999 0.48686673 1 P 0 ;0,1,2=386,3=90.000000
L 2.8499999 0.48686673 2.84749961 0.48766654 1 P 0 ;0,1,2=386,3=90.000000
L 2.84749961 0.48766654 2.84499941 0.48926663 1 P 0 ;0,1,2=386,3=90.000000
L 2.84499941 0.48926663 2.84333307 0.49113346 1 P 0 ;0,1,2=386,3=90.000000
L 2.84333307 0.49113346 2.8425 0.4929997 1 P 0 ;0,1,2=386,3=90.000000
L 2.8425 0.4929997 2.8425 0.49486644 1 P 0 ;0,1,2=386,3=90.000000
L 2.8425 0.49486644 2.84333307 0.49673327 1 P 0 ;0,1,2=386,3=90.000000
L 2.84333307 0.49673327 2.84458287 0.49833337 1 P 0 ;0,1,2=386,3=90.000000
L 2.84458287 0.49833337 2.84624911 0.49966693 1 P 0 ;0,1,2=386,3=90.000000
L 2.84749961 0.50913327 2.84458287 0.51073297 1 P 0 ;0,1,2=386,3=90.000000
L 2.84458287 0.51073297 2.84291654 0.51286634 1 P 0 ;0,1,2=386,3=90.000000
L 2.84291654 0.51286634 2.8425 0.51526683 1 P 0 ;0,1,2=386,3=90.000000
L 2.8425 0.51526683 2.84291654 0.5174002 1 P 0 ;0,1,2=386,3=90.000000
L 2.84291654 0.5174002 2.84499941 0.51953356 1 P 0 ;0,1,2=386,3=90.000000
L 2.84499941 0.51953356 2.84749961 0.52086663 1 P 0 ;0,1,2=386,3=90.000000
L 2.84749961 0.52086663 2.8499999 0.52113317 1 P 0 ;0,1,2=386,3=90.000000
L 2.8499999 0.52113317 2.85291594 0.5206 1 P 0 ;0,1,2=386,3=90.000000
L 2.85291594 0.5206 2.85499961 0.51873327 1 P 0 ;0,1,2=386,3=90.000000
L 2.85499961 0.51873327 2.85583346 0.51686644 1 P 0 ;0,1,2=386,3=90.000000
L 2.85583346 0.51686644 2.85583346 0.51446654 1 P 0 ;0,1,2=386,3=90.000000
L 2.85583346 0.51686644 2.85708327 0.51846663 1 P 0 ;0,1,2=386,3=90.000000
L 2.85708327 0.51846663 2.85916614 0.5198001 1 P 0 ;0,1,2=386,3=90.000000
L 2.85916614 0.5198001 2.86166634 0.52033337 1 P 0 ;0,1,2=386,3=90.000000
L 2.86166634 0.52033337 2.86416654 0.5198001 1 P 0 ;0,1,2=386,3=90.000000
L 2.86416654 0.5198001 2.86624941 0.51846663 1 P 0 ;0,1,2=386,3=90.000000
L 2.86624941 0.51846663 2.8675 0.51606663 1 P 0 ;0,1,2=386,3=90.000000
L 2.8675 0.51606663 2.86708337 0.51366663 1 P 0 ;0,1,2=386,3=90.000000
L 2.86708337 0.51366663 2.86541634 0.51126663 1 P 0 ;0,1,2=386,3=90.000000
L 2.8425 0.5402 2.8675 0.5402 1 P 0 ;0,1,2=386,3=90.000000
L 2.8675 0.5402 2.84958327 0.53033297 1 P 0 ;0,1,2=386,3=90.000000
L 2.84958327 0.53033297 2.84958327 0.54366693 1 P 0 ;0,1,2=386,3=90.000000
L 2.82255 0.56 2.77855 0.56 1 P 0 
L 2.82255 0.65 2.82255 0.56 1 P 0 
L 2.77855 0.56 2.77855 0.65 1 P 0 
L 2.77855 0.65 2.82255 0.65 1 P 0 
L 2.80541634 0.49886663 2.80666683 0.49726644 1 P 0 ;0,1,2=387,3=90.000000
L 2.80666683 0.49726644 2.8075 0.4954002 1 P 0 ;0,1,2=387,3=90.000000
L 2.8075 0.4954002 2.8075 0.49326683 1 P 0 ;0,1,2=387,3=90.000000
L 2.8075 0.49326683 2.80624941 0.49086634 1 P 0 ;0,1,2=387,3=90.000000
L 2.80624941 0.49086634 2.80416654 0.4890001 1 P 0 ;0,1,2=387,3=90.000000
L 2.80416654 0.4890001 2.80166634 0.48766654 1 P 0 ;0,1,2=387,3=90.000000
L 2.80166634 0.48766654 2.7974998 0.48659961 1 P 0 ;0,1,2=387,3=90.000000
L 2.7974998 0.48659961 2.7937498 0.48633297 1 P 0 ;0,1,2=387,3=90.000000
L 2.7937498 0.48633297 2.7899999 0.48686673 1 P 0 ;0,1,2=387,3=90.000000
L 2.7899999 0.48686673 2.78749961 0.48766654 1 P 0 ;0,1,2=387,3=90.000000
L 2.78749961 0.48766654 2.78499941 0.48926663 1 P 0 ;0,1,2=387,3=90.000000
L 2.78499941 0.48926663 2.78333307 0.49113346 1 P 0 ;0,1,2=387,3=90.000000
L 2.78333307 0.49113346 2.7825 0.4929997 1 P 0 ;0,1,2=387,3=90.000000
L 2.7825 0.4929997 2.7825 0.49486644 1 P 0 ;0,1,2=387,3=90.000000
L 2.7825 0.49486644 2.78333307 0.49673327 1 P 0 ;0,1,2=387,3=90.000000
L 2.78333307 0.49673327 2.78458287 0.49833337 1 P 0 ;0,1,2=387,3=90.000000
L 2.78458287 0.49833337 2.78624911 0.49966693 1 P 0 ;0,1,2=387,3=90.000000
L 2.80333337 0.50993317 2.80583287 0.51153327 1 P 0 ;0,1,2=387,3=90.000000
L 2.80583287 0.51153327 2.80708337 0.5134 1 P 0 ;0,1,2=387,3=90.000000
L 2.80708337 0.5134 2.8075 0.51553337 1 P 0 ;0,1,2=387,3=90.000000
L 2.8075 0.51553337 2.80666683 0.5182 1 P 0 ;0,1,2=387,3=90.000000
L 2.80666683 0.5182 2.80458317 0.52006673 1 P 0 ;0,1,2=387,3=90.000000
L 2.80458317 0.52006673 2.80208366 0.5206 1 P 0 ;0,1,2=387,3=90.000000
L 2.80208366 0.5206 2.79958268 0.52033337 1 P 0 ;0,1,2=387,3=90.000000
L 2.79958268 0.52033337 2.7974998 0.51926644 1 P 0 ;0,1,2=387,3=90.000000
L 2.7974998 0.51926644 2.79333327 0.51393327 1 P 0 ;0,1,2=387,3=90.000000
L 2.79333327 0.51393327 2.79041644 0.51153327 1 P 0 ;0,1,2=387,3=90.000000
L 2.79041644 0.51153327 2.78624911 0.50993317 1 P 0 ;0,1,2=387,3=90.000000
L 2.78624911 0.50993317 2.7825 0.5093999 1 P 0 ;0,1,2=387,3=90.000000
L 2.7825 0.5093999 2.7825 0.5206 1 P 0 ;0,1,2=387,3=90.000000
L 2.7825 0.5369997 2.78291654 0.53886644 1 P 0 ;0,1,2=387,3=90.000000
L 2.78291654 0.53886644 2.78416624 0.5409998 1 P 0 ;0,1,2=387,3=90.000000
L 2.78416624 0.5409998 2.78624911 0.54233337 1 P 0 ;0,1,2=387,3=90.000000
L 2.78624911 0.54233337 2.78916673 0.54286663 1 P 0 ;0,1,2=387,3=90.000000
L 2.78916673 0.54286663 2.79208278 0.54233337 1 P 0 ;0,1,2=387,3=90.000000
L 2.79208278 0.54233337 2.79458297 0.54073327 1 P 0 ;0,1,2=387,3=90.000000
L 2.79458297 0.54073327 2.79583346 0.53833327 1 P 0 ;0,1,2=387,3=90.000000
L 2.79583346 0.53833327 2.79583346 0.53566663 1 P 0 ;0,1,2=387,3=90.000000
L 2.79583346 0.53566663 2.79666663 0.53406654 1 P 0 ;0,1,2=387,3=90.000000
L 2.79666663 0.53406654 2.79874951 0.53273297 1 P 0 ;0,1,2=387,3=90.000000
L 2.79874951 0.53273297 2.80166634 0.5321998 1 P 0 ;0,1,2=387,3=90.000000
L 2.80166634 0.5321998 2.80458317 0.5330001 1 P 0 ;0,1,2=387,3=90.000000
L 2.80458317 0.5330001 2.80666683 0.53486634 1 P 0 ;0,1,2=387,3=90.000000
L 2.80666683 0.53486634 2.8075 0.5369997 1 P 0 ;0,1,2=387,3=90.000000
L 2.8075 0.5369997 2.80666683 0.53913307 1 P 0 ;0,1,2=387,3=90.000000
L 2.80666683 0.53913307 2.80458317 0.5409998 1 P 0 ;0,1,2=387,3=90.000000
L 2.80458317 0.5409998 2.80166634 0.5418001 1 P 0 ;0,1,2=387,3=90.000000
L 2.80166634 0.5418001 2.79874951 0.54126644 1 P 0 ;0,1,2=387,3=90.000000
L 2.79874951 0.54126644 2.79666663 0.53993337 1 P 0 ;0,1,2=387,3=90.000000
L 2.79666663 0.53993337 2.79583346 0.53833327 1 P 0 ;0,1,2=387,3=90.000000
L 2.79583346 0.53833327 2.79583346 0.53566663 1 P 0 ;0,1,2=387,3=90.000000
L 2.79583346 0.53566663 2.79458297 0.53326663 1 P 0 ;0,1,2=387,3=90.000000
L 2.79458297 0.53326663 2.79208278 0.53166654 1 P 0 ;0,1,2=387,3=90.000000
L 2.79208278 0.53166654 2.78916673 0.53113327 1 P 0 ;0,1,2=387,3=90.000000
L 2.78916673 0.53113327 2.78624911 0.53166654 1 P 0 ;0,1,2=387,3=90.000000
L 2.78624911 0.53166654 2.78416624 0.5330001 1 P 0 ;0,1,2=387,3=90.000000
L 2.78416624 0.5330001 2.78291654 0.53513346 1 P 0 ;0,1,2=387,3=90.000000
L 2.78291654 0.53513346 2.7825 0.5369997 1 P 0 ;0,1,2=387,3=90.000000
L 2.73006998 0.56 2.68606998 0.56 1 P 0 
L 2.73006998 0.65 2.73006998 0.56 1 P 0 
L 2.68606998 0.56 2.68606998 0.65 1 P 0 
L 2.68606998 0.65 2.73006998 0.65 1 P 0 
L 2.72541634 0.46886663 2.72666683 0.46726644 1 P 0 ;0,1,2=388,3=90.000000
L 2.72666683 0.46726644 2.7275 0.4654002 1 P 0 ;0,1,2=388,3=90.000000
L 2.7275 0.4654002 2.7275 0.46326683 1 P 0 ;0,1,2=388,3=90.000000
L 2.7275 0.46326683 2.72624941 0.46086634 1 P 0 ;0,1,2=388,3=90.000000
L 2.72624941 0.46086634 2.72416654 0.4590001 1 P 0 ;0,1,2=388,3=90.000000
L 2.72416654 0.4590001 2.72166634 0.45766654 1 P 0 ;0,1,2=388,3=90.000000
L 2.72166634 0.45766654 2.7174998 0.45659961 1 P 0 ;0,1,2=388,3=90.000000
L 2.7174998 0.45659961 2.7137498 0.45633297 1 P 0 ;0,1,2=388,3=90.000000
L 2.7137498 0.45633297 2.7099999 0.45686673 1 P 0 ;0,1,2=388,3=90.000000
L 2.7099999 0.45686673 2.70749961 0.45766654 1 P 0 ;0,1,2=388,3=90.000000
L 2.70749961 0.45766654 2.70499941 0.45926663 1 P 0 ;0,1,2=388,3=90.000000
L 2.70499941 0.45926663 2.70333307 0.46113346 1 P 0 ;0,1,2=388,3=90.000000
L 2.70333307 0.46113346 2.7025 0.4629997 1 P 0 ;0,1,2=388,3=90.000000
L 2.7025 0.4629997 2.7025 0.46486644 1 P 0 ;0,1,2=388,3=90.000000
L 2.7025 0.46486644 2.70333307 0.46673327 1 P 0 ;0,1,2=388,3=90.000000
L 2.70333307 0.46673327 2.70458287 0.46833337 1 P 0 ;0,1,2=388,3=90.000000
L 2.70458287 0.46833337 2.70624911 0.46966693 1 P 0 ;0,1,2=388,3=90.000000
L 2.72333337 0.47993317 2.72583287 0.48153327 1 P 0 ;0,1,2=388,3=90.000000
L 2.72583287 0.48153327 2.72708337 0.4834 1 P 0 ;0,1,2=388,3=90.000000
L 2.72708337 0.4834 2.7275 0.48553337 1 P 0 ;0,1,2=388,3=90.000000
L 2.7275 0.48553337 2.72666683 0.4882 1 P 0 ;0,1,2=388,3=90.000000
L 2.72666683 0.4882 2.72458317 0.49006673 1 P 0 ;0,1,2=388,3=90.000000
L 2.72458317 0.49006673 2.72208366 0.4906 1 P 0 ;0,1,2=388,3=90.000000
L 2.72208366 0.4906 2.71958268 0.49033337 1 P 0 ;0,1,2=388,3=90.000000
L 2.71958268 0.49033337 2.7174998 0.48926644 1 P 0 ;0,1,2=388,3=90.000000
L 2.7174998 0.48926644 2.71333327 0.48393327 1 P 0 ;0,1,2=388,3=90.000000
L 2.71333327 0.48393327 2.71041644 0.48153327 1 P 0 ;0,1,2=388,3=90.000000
L 2.71041644 0.48153327 2.70624911 0.47993317 1 P 0 ;0,1,2=388,3=90.000000
L 2.70624911 0.47993317 2.7025 0.4793999 1 P 0 ;0,1,2=388,3=90.000000
L 2.7025 0.4793999 2.7025 0.4906 1 P 0 ;0,1,2=388,3=90.000000
L 2.7025 0.50646654 2.70791624 0.5069997 1 P 0 ;0,1,2=388,3=90.000000
L 2.70791624 0.5069997 2.71249931 0.5078 1 P 0 ;0,1,2=388,3=90.000000
L 2.71249931 0.5078 2.71666663 0.50886644 1 P 0 ;0,1,2=388,3=90.000000
L 2.71666663 0.50886644 2.7212498 0.5102 1 P 0 ;0,1,2=388,3=90.000000
L 2.7212498 0.5102 2.7275 0.51233337 1 P 0 ;0,1,2=388,3=90.000000
L 2.7275 0.51233337 2.7275 0.50166654 1 P 0 ;0,1,2=388,3=90.000000
L 2.68006998 0.56 2.63606998 0.56 1 P 0 
L 2.68006998 0.65 2.68006998 0.56 1 P 0 
L 2.63606998 0.56 2.63606998 0.65 1 P 0 
L 2.63606998 0.65 2.68006998 0.65 1 P 0 
L 2.66041634 0.46886663 2.66166683 0.46726644 1 P 0 ;0,1,2=389,3=90.000000
L 2.66166683 0.46726644 2.6625 0.4654002 1 P 0 ;0,1,2=389,3=90.000000
L 2.6625 0.4654002 2.6625 0.46326683 1 P 0 ;0,1,2=389,3=90.000000
L 2.6625 0.46326683 2.66124941 0.46086634 1 P 0 ;0,1,2=389,3=90.000000
L 2.66124941 0.46086634 2.65916654 0.4590001 1 P 0 ;0,1,2=389,3=90.000000
L 2.65916654 0.4590001 2.65666634 0.45766654 1 P 0 ;0,1,2=389,3=90.000000
L 2.65666634 0.45766654 2.6524998 0.45659961 1 P 0 ;0,1,2=389,3=90.000000
L 2.6524998 0.45659961 2.6487498 0.45633297 1 P 0 ;0,1,2=389,3=90.000000
L 2.6487498 0.45633297 2.6449999 0.45686673 1 P 0 ;0,1,2=389,3=90.000000
L 2.6449999 0.45686673 2.64249961 0.45766654 1 P 0 ;0,1,2=389,3=90.000000
L 2.64249961 0.45766654 2.63999941 0.45926663 1 P 0 ;0,1,2=389,3=90.000000
L 2.63999941 0.45926663 2.63833307 0.46113346 1 P 0 ;0,1,2=389,3=90.000000
L 2.63833307 0.46113346 2.6375 0.4629997 1 P 0 ;0,1,2=389,3=90.000000
L 2.6375 0.4629997 2.6375 0.46486644 1 P 0 ;0,1,2=389,3=90.000000
L 2.6375 0.46486644 2.63833307 0.46673327 1 P 0 ;0,1,2=389,3=90.000000
L 2.63833307 0.46673327 2.63958287 0.46833337 1 P 0 ;0,1,2=389,3=90.000000
L 2.63958287 0.46833337 2.64124911 0.46966693 1 P 0 ;0,1,2=389,3=90.000000
L 2.65833337 0.47993317 2.66083287 0.48153327 1 P 0 ;0,1,2=389,3=90.000000
L 2.66083287 0.48153327 2.66208337 0.4834 1 P 0 ;0,1,2=389,3=90.000000
L 2.66208337 0.4834 2.6625 0.48553337 1 P 0 ;0,1,2=389,3=90.000000
L 2.6625 0.48553337 2.66166683 0.4882 1 P 0 ;0,1,2=389,3=90.000000
L 2.66166683 0.4882 2.65958317 0.49006673 1 P 0 ;0,1,2=389,3=90.000000
L 2.65958317 0.49006673 2.65708366 0.4906 1 P 0 ;0,1,2=389,3=90.000000
L 2.65708366 0.4906 2.65458268 0.49033337 1 P 0 ;0,1,2=389,3=90.000000
L 2.65458268 0.49033337 2.6524998 0.48926644 1 P 0 ;0,1,2=389,3=90.000000
L 2.6524998 0.48926644 2.64833327 0.48393327 1 P 0 ;0,1,2=389,3=90.000000
L 2.64833327 0.48393327 2.64541644 0.48153327 1 P 0 ;0,1,2=389,3=90.000000
L 2.64541644 0.48153327 2.64124911 0.47993317 1 P 0 ;0,1,2=389,3=90.000000
L 2.64124911 0.47993317 2.6375 0.4793999 1 P 0 ;0,1,2=389,3=90.000000
L 2.6375 0.4793999 2.6375 0.4906 1 P 0 ;0,1,2=389,3=90.000000
L 2.64791594 0.50193317 2.65083346 0.5037999 1 P 0 ;0,1,2=389,3=90.000000
L 2.65083346 0.5037999 2.6524998 0.5054 1 P 0 ;0,1,2=389,3=90.000000
L 2.6524998 0.5054 2.65333297 0.50753337 1 P 0 ;0,1,2=389,3=90.000000
L 2.65333297 0.50753337 2.6524998 0.5094002 1 P 0 ;0,1,2=389,3=90.000000
L 2.6524998 0.5094002 2.65083346 0.51073327 1 P 0 ;0,1,2=389,3=90.000000
L 2.65083346 0.51073327 2.64833327 0.5118001 1 P 0 ;0,1,2=389,3=90.000000
L 2.64833327 0.5118001 2.64541644 0.51206673 1 P 0 ;0,1,2=389,3=90.000000
L 2.64541644 0.51206673 2.64291624 0.5118001 1 P 0 ;0,1,2=389,3=90.000000
L 2.64291624 0.5118001 2.64041604 0.51073327 1 P 0 ;0,1,2=389,3=90.000000
L 2.64041604 0.51073327 2.63833307 0.50913307 1 P 0 ;0,1,2=389,3=90.000000
L 2.63833307 0.50913307 2.6375 0.50726683 1 P 0 ;0,1,2=389,3=90.000000
L 2.6375 0.50726683 2.63833307 0.50513346 1 P 0 ;0,1,2=389,3=90.000000
L 2.63833307 0.50513346 2.64083258 0.50326663 1 P 0 ;0,1,2=389,3=90.000000
L 2.64083258 0.50326663 2.64458327 0.5021998 1 P 0 ;0,1,2=389,3=90.000000
L 2.64458327 0.5021998 2.6487498 0.50193317 1 P 0 ;0,1,2=389,3=90.000000
L 2.6487498 0.50193317 2.65416614 0.50246634 1 P 0 ;0,1,2=389,3=90.000000
L 2.65416614 0.50246634 2.65708366 0.50326663 1 P 0 ;0,1,2=389,3=90.000000
L 2.65708366 0.50326663 2.6599997 0.5045997 1 P 0 ;0,1,2=389,3=90.000000
L 2.6599997 0.5045997 2.66208337 0.50646654 1 P 0 ;0,1,2=389,3=90.000000
L 2.66208337 0.50646654 2.6625 0.50833327 1 P 0 ;0,1,2=389,3=90.000000
L 2.6625 0.50833327 2.66166683 0.5102 1 P 0 ;0,1,2=389,3=90.000000
L 2.66166683 0.5102 2.65958317 0.51153356 1 P 0 ;0,1,2=389,3=90.000000
L 2.53321998 0.56 2.48921998 0.56 1 P 0 
L 2.53321998 0.65 2.53321998 0.56 1 P 0 
L 2.48921998 0.56 2.48921998 0.65 1 P 0 
L 2.48921998 0.65 2.53321998 0.65 1 P 0 
L 2.53041634 0.50886663 2.53166683 0.50726644 1 P 0 ;0,1,2=390,3=90.000000
L 2.53166683 0.50726644 2.5325 0.5054002 1 P 0 ;0,1,2=390,3=90.000000
L 2.5325 0.5054002 2.5325 0.50326683 1 P 0 ;0,1,2=390,3=90.000000
L 2.5325 0.50326683 2.53124941 0.50086634 1 P 0 ;0,1,2=390,3=90.000000
L 2.53124941 0.50086634 2.52916654 0.4990001 1 P 0 ;0,1,2=390,3=90.000000
L 2.52916654 0.4990001 2.52666634 0.49766654 1 P 0 ;0,1,2=390,3=90.000000
L 2.52666634 0.49766654 2.5224998 0.49659961 1 P 0 ;0,1,2=390,3=90.000000
L 2.5224998 0.49659961 2.5187498 0.49633297 1 P 0 ;0,1,2=390,3=90.000000
L 2.5187498 0.49633297 2.5149999 0.49686673 1 P 0 ;0,1,2=390,3=90.000000
L 2.5149999 0.49686673 2.51249961 0.49766654 1 P 0 ;0,1,2=390,3=90.000000
L 2.51249961 0.49766654 2.50999941 0.49926663 1 P 0 ;0,1,2=390,3=90.000000
L 2.50999941 0.49926663 2.50833307 0.50113346 1 P 0 ;0,1,2=390,3=90.000000
L 2.50833307 0.50113346 2.5075 0.5029997 1 P 0 ;0,1,2=390,3=90.000000
L 2.5075 0.5029997 2.5075 0.50486644 1 P 0 ;0,1,2=390,3=90.000000
L 2.5075 0.50486644 2.50833307 0.50673327 1 P 0 ;0,1,2=390,3=90.000000
L 2.50833307 0.50673327 2.50958287 0.50833337 1 P 0 ;0,1,2=390,3=90.000000
L 2.50958287 0.50833337 2.51124911 0.50966693 1 P 0 ;0,1,2=390,3=90.000000
L 2.52833337 0.51993317 2.53083287 0.52153327 1 P 0 ;0,1,2=390,3=90.000000
L 2.53083287 0.52153327 2.53208337 0.5234 1 P 0 ;0,1,2=390,3=90.000000
L 2.53208337 0.5234 2.5325 0.52553337 1 P 0 ;0,1,2=390,3=90.000000
L 2.5325 0.52553337 2.53166683 0.5282 1 P 0 ;0,1,2=390,3=90.000000
L 2.53166683 0.5282 2.52958317 0.53006673 1 P 0 ;0,1,2=390,3=90.000000
L 2.52958317 0.53006673 2.52708366 0.5306 1 P 0 ;0,1,2=390,3=90.000000
L 2.52708366 0.5306 2.52458268 0.53033337 1 P 0 ;0,1,2=390,3=90.000000
L 2.52458268 0.53033337 2.5224998 0.52926644 1 P 0 ;0,1,2=390,3=90.000000
L 2.5224998 0.52926644 2.51833327 0.52393327 1 P 0 ;0,1,2=390,3=90.000000
L 2.51833327 0.52393327 2.51541644 0.52153327 1 P 0 ;0,1,2=390,3=90.000000
L 2.51541644 0.52153327 2.51124911 0.51993317 1 P 0 ;0,1,2=390,3=90.000000
L 2.51124911 0.51993317 2.5075 0.5193999 1 P 0 ;0,1,2=390,3=90.000000
L 2.5075 0.5193999 2.5075 0.5306 1 P 0 ;0,1,2=390,3=90.000000
L 2.51124911 0.54113327 2.50916624 0.54273297 1 P 0 ;0,1,2=390,3=90.000000
L 2.50916624 0.54273297 2.50791654 0.5445997 1 P 0 ;0,1,2=390,3=90.000000
L 2.50791654 0.5445997 2.5075 0.5469997 1 P 0 ;0,1,2=390,3=90.000000
L 2.5075 0.5469997 2.50833307 0.5494002 1 P 0 ;0,1,2=390,3=90.000000
L 2.50833307 0.5494002 2.50999941 0.55126644 1 P 0 ;0,1,2=390,3=90.000000
L 2.50999941 0.55126644 2.51291624 0.5526 1 P 0 ;0,1,2=390,3=90.000000
L 2.51291624 0.5526 2.51624961 0.55286663 1 P 0 ;0,1,2=390,3=90.000000
L 2.51624961 0.55286663 2.51958297 0.55233337 1 P 0 ;0,1,2=390,3=90.000000
L 2.51958297 0.55233337 2.52166663 0.5509998 1 P 0 ;0,1,2=390,3=90.000000
L 2.52166663 0.5509998 2.52333297 0.54913307 1 P 0 ;0,1,2=390,3=90.000000
L 2.52333297 0.54913307 2.52374951 0.54726683 1 P 0 ;0,1,2=390,3=90.000000
L 2.52374951 0.54726683 2.52333297 0.5454 1 P 0 ;0,1,2=390,3=90.000000
L 2.52333297 0.5454 2.52166663 0.5430001 1 P 0 ;0,1,2=390,3=90.000000
L 2.52166663 0.5430001 2.5325 0.5437999 1 P 0 ;0,1,2=390,3=90.000000
L 2.5325 0.5437999 2.5325 0.5509998 1 P 0 ;0,1,2=390,3=90.000000
L 2.48321998 0.56 2.43921998 0.56 1 P 0 
L 2.48321998 0.65 2.48321998 0.56 1 P 0 
L 2.43921998 0.56 2.43921998 0.65 1 P 0 
L 2.43921998 0.65 2.48321998 0.65 1 P 0 
L 2.47041634 0.50886663 2.47166683 0.50726644 1 P 0 ;0,1,2=391,3=90.000000
L 2.47166683 0.50726644 2.4725 0.5054002 1 P 0 ;0,1,2=391,3=90.000000
L 2.4725 0.5054002 2.4725 0.50326683 1 P 0 ;0,1,2=391,3=90.000000
L 2.4725 0.50326683 2.47124941 0.50086634 1 P 0 ;0,1,2=391,3=90.000000
L 2.47124941 0.50086634 2.46916654 0.4990001 1 P 0 ;0,1,2=391,3=90.000000
L 2.46916654 0.4990001 2.46666634 0.49766654 1 P 0 ;0,1,2=391,3=90.000000
L 2.46666634 0.49766654 2.4624998 0.49659961 1 P 0 ;0,1,2=391,3=90.000000
L 2.4624998 0.49659961 2.4587498 0.49633297 1 P 0 ;0,1,2=391,3=90.000000
L 2.4587498 0.49633297 2.4549999 0.49686673 1 P 0 ;0,1,2=391,3=90.000000
L 2.4549999 0.49686673 2.45249961 0.49766654 1 P 0 ;0,1,2=391,3=90.000000
L 2.45249961 0.49766654 2.44999941 0.49926663 1 P 0 ;0,1,2=391,3=90.000000
L 2.44999941 0.49926663 2.44833307 0.50113346 1 P 0 ;0,1,2=391,3=90.000000
L 2.44833307 0.50113346 2.4475 0.5029997 1 P 0 ;0,1,2=391,3=90.000000
L 2.4475 0.5029997 2.4475 0.50486644 1 P 0 ;0,1,2=391,3=90.000000
L 2.4475 0.50486644 2.44833307 0.50673327 1 P 0 ;0,1,2=391,3=90.000000
L 2.44833307 0.50673327 2.44958287 0.50833337 1 P 0 ;0,1,2=391,3=90.000000
L 2.44958287 0.50833337 2.45124911 0.50966693 1 P 0 ;0,1,2=391,3=90.000000
L 2.46833337 0.51993317 2.47083287 0.52153327 1 P 0 ;0,1,2=391,3=90.000000
L 2.47083287 0.52153327 2.47208337 0.5234 1 P 0 ;0,1,2=391,3=90.000000
L 2.47208337 0.5234 2.4725 0.52553337 1 P 0 ;0,1,2=391,3=90.000000
L 2.4725 0.52553337 2.47166683 0.5282 1 P 0 ;0,1,2=391,3=90.000000
L 2.47166683 0.5282 2.46958317 0.53006673 1 P 0 ;0,1,2=391,3=90.000000
L 2.46958317 0.53006673 2.46708366 0.5306 1 P 0 ;0,1,2=391,3=90.000000
L 2.46708366 0.5306 2.46458268 0.53033337 1 P 0 ;0,1,2=391,3=90.000000
L 2.46458268 0.53033337 2.4624998 0.52926644 1 P 0 ;0,1,2=391,3=90.000000
L 2.4624998 0.52926644 2.45833327 0.52393327 1 P 0 ;0,1,2=391,3=90.000000
L 2.45833327 0.52393327 2.45541644 0.52153327 1 P 0 ;0,1,2=391,3=90.000000
L 2.45541644 0.52153327 2.45124911 0.51993317 1 P 0 ;0,1,2=391,3=90.000000
L 2.45124911 0.51993317 2.4475 0.5193999 1 P 0 ;0,1,2=391,3=90.000000
L 2.4475 0.5193999 2.4475 0.5306 1 P 0 ;0,1,2=391,3=90.000000
L 2.4475 0.5502 2.4725 0.5502 1 P 0 ;0,1,2=391,3=90.000000
L 2.4725 0.5502 2.45458327 0.54033297 1 P 0 ;0,1,2=391,3=90.000000
L 2.45458327 0.54033297 2.45458327 0.55366693 1 P 0 ;0,1,2=391,3=90.000000
L 2.3651 0.5599 2.3211 0.5599 1 P 0 
L 2.3651 0.6499 2.3651 0.5599 1 P 0 
L 2.3211 0.5599 2.3211 0.6499 1 P 0 
L 2.3211 0.6499 2.3651 0.6499 1 P 0 
L 2.35291624 0.67743327 2.35446683 0.67513307 1 P 0 ;0,1,2=392,3=90.000000
L 2.35446683 0.67513307 2.3555 0.6724503 1 P 0 ;0,1,2=392,3=90.000000
L 2.3555 0.6724503 2.3555 0.66938356 1 P 0 ;0,1,2=392,3=90.000000
L 2.3555 0.66938356 2.35394931 0.66593287 1 P 0 ;0,1,2=392,3=90.000000
L 2.35394931 0.66593287 2.35136654 0.6632501 1 P 0 ;0,1,2=392,3=90.000000
L 2.35136654 0.6632501 2.34826624 0.66133317 1 P 0 ;0,1,2=392,3=90.000000
L 2.34826624 0.66133317 2.3430998 0.65979951 1 P 0 ;0,1,2=392,3=90.000000
L 2.3430998 0.65979951 2.3384498 0.65941624 1 P 0 ;0,1,2=392,3=90.000000
L 2.3384498 0.65941624 2.3337999 0.66018337 1 P 0 ;0,1,2=392,3=90.000000
L 2.3337999 0.66018337 2.33069961 0.66133317 1 P 0 ;0,1,2=392,3=90.000000
L 2.33069961 0.66133317 2.32759931 0.66363337 1 P 0 ;0,1,2=392,3=90.000000
L 2.32759931 0.66363337 2.32553307 0.66631683 1 P 0 ;0,1,2=392,3=90.000000
L 2.32553307 0.66631683 2.3245 0.66899961 1 P 0 ;0,1,2=392,3=90.000000
L 2.3245 0.66899961 2.3245 0.67168307 1 P 0 ;0,1,2=392,3=90.000000
L 2.3245 0.67168307 2.32553307 0.67436654 1 P 0 ;0,1,2=392,3=90.000000
L 2.32553307 0.67436654 2.32708278 0.67666673 1 P 0 ;0,1,2=392,3=90.000000
L 2.32708278 0.67666673 2.32914892 0.67858366 1 P 0 ;0,1,2=392,3=90.000000
L 2.3245 0.69999961 2.3555 0.69999961 1 P 0 ;0,1,2=392,3=90.000000
L 2.3555 0.69999961 2.3493003 0.6953999 1 P 0 ;0,1,2=392,3=90.000000
L 2.3245 0.6953999 2.3245 0.70459931 1 P 0 ;0,1,2=392,3=90.000000
L 2.32811585 0.72448287 2.32553307 0.72716634 1 P 0 ;0,1,2=392,3=90.000000
L 2.32553307 0.72716634 2.3245 0.73023307 1 P 0 ;0,1,2=392,3=90.000000
L 2.3245 0.73023307 2.32553307 0.7332998 1 P 0 ;0,1,2=392,3=90.000000
L 2.32553307 0.7332998 2.32863238 0.73598327 1 P 0 ;0,1,2=392,3=90.000000
L 2.32863238 0.73598327 2.33328327 0.7379002 1 P 0 ;0,1,2=392,3=90.000000
L 2.33328327 0.7379002 2.33793327 0.73866673 1 P 0 ;0,1,2=392,3=90.000000
L 2.33793327 0.73866673 2.34361634 0.73866673 1 P 0 ;0,1,2=392,3=90.000000
L 2.34361634 0.73866673 2.34826624 0.7379002 1 P 0 ;0,1,2=392,3=90.000000
L 2.34826624 0.7379002 2.3523997 0.73598327 1 P 0 ;0,1,2=392,3=90.000000
L 2.3523997 0.73598327 2.35446683 0.73368307 1 P 0 ;0,1,2=392,3=90.000000
L 2.35446683 0.73368307 2.3555 0.73099961 1 P 0 ;0,1,2=392,3=90.000000
L 2.3555 0.73099961 2.35446683 0.72793287 1 P 0 ;0,1,2=392,3=90.000000
L 2.35446683 0.72793287 2.3523997 0.72563337 1 P 0 ;0,1,2=392,3=90.000000
L 2.3523997 0.72563337 2.3493003 0.7240997 1 P 0 ;0,1,2=392,3=90.000000
L 2.3493003 0.7240997 2.34516594 0.72333317 1 P 0 ;0,1,2=392,3=90.000000
L 2.34516594 0.72333317 2.3415501 0.7240997 1 P 0 ;0,1,2=392,3=90.000000
L 2.3415501 0.7240997 2.33793327 0.72601663 1 P 0 ;0,1,2=392,3=90.000000
L 2.33793327 0.72601663 2.33586604 0.72831683 1 P 0 ;0,1,2=392,3=90.000000
L 2.33586604 0.72831683 2.33534951 0.73099961 1 P 0 ;0,1,2=392,3=90.000000
L 2.33534951 0.73099961 2.33638268 0.73406634 1 P 0 ;0,1,2=392,3=90.000000
L 2.33638268 0.73406634 2.33896634 0.73636654 1 P 0 ;0,1,2=392,3=90.000000
L 2.33896634 0.73636654 2.34361634 0.73866673 1 P 0 ;0,1,2=392,3=90.000000
L 2.41511004 0.56 2.37111004 0.56 1 P 0 
L 2.41511004 0.65 2.41511004 0.56 1 P 0 
L 2.37111004 0.56 2.37111004 0.65 1 P 0 
L 2.37111004 0.65 2.41511004 0.65 1 P 0 
L 2.40991624 0.49043327 2.41146683 0.48813307 1 P 0 ;0,1,2=393,3=90.000000
L 2.41146683 0.48813307 2.4125 0.4854503 1 P 0 ;0,1,2=393,3=90.000000
L 2.4125 0.4854503 2.4125 0.48238356 1 P 0 ;0,1,2=393,3=90.000000
L 2.4125 0.48238356 2.41094931 0.47893287 1 P 0 ;0,1,2=393,3=90.000000
L 2.41094931 0.47893287 2.40836654 0.4762501 1 P 0 ;0,1,2=393,3=90.000000
L 2.40836654 0.4762501 2.40526624 0.47433317 1 P 0 ;0,1,2=393,3=90.000000
L 2.40526624 0.47433317 2.4000998 0.47279951 1 P 0 ;0,1,2=393,3=90.000000
L 2.4000998 0.47279951 2.3954498 0.47241624 1 P 0 ;0,1,2=393,3=90.000000
L 2.3954498 0.47241624 2.3907999 0.47318337 1 P 0 ;0,1,2=393,3=90.000000
L 2.3907999 0.47318337 2.38769961 0.47433317 1 P 0 ;0,1,2=393,3=90.000000
L 2.38769961 0.47433317 2.38459931 0.47663337 1 P 0 ;0,1,2=393,3=90.000000
L 2.38459931 0.47663337 2.38253307 0.47931683 1 P 0 ;0,1,2=393,3=90.000000
L 2.38253307 0.47931683 2.3815 0.48199961 1 P 0 ;0,1,2=393,3=90.000000
L 2.3815 0.48199961 2.3815 0.48468307 1 P 0 ;0,1,2=393,3=90.000000
L 2.3815 0.48468307 2.38253307 0.48736654 1 P 0 ;0,1,2=393,3=90.000000
L 2.38253307 0.48736654 2.38408278 0.48966673 1 P 0 ;0,1,2=393,3=90.000000
L 2.38408278 0.48966673 2.38614892 0.49158366 1 P 0 ;0,1,2=393,3=90.000000
L 2.40733346 0.50571644 2.41043278 0.50801663 1 P 0 ;0,1,2=393,3=90.000000
L 2.41043278 0.50801663 2.41198337 0.5107001 1 P 0 ;0,1,2=393,3=90.000000
L 2.41198337 0.5107001 2.4125 0.51376683 1 P 0 ;0,1,2=393,3=90.000000
L 2.4125 0.51376683 2.41146683 0.5176 1 P 0 ;0,1,2=393,3=90.000000
L 2.41146683 0.5176 2.40888307 0.52028346 1 P 0 ;0,1,2=393,3=90.000000
L 2.40888307 0.52028346 2.40578376 0.52105 1 P 0 ;0,1,2=393,3=90.000000
L 2.40578376 0.52105 2.40268258 0.52066673 1 P 0 ;0,1,2=393,3=90.000000
L 2.40268258 0.52066673 2.4000998 0.51913307 1 P 0 ;0,1,2=393,3=90.000000
L 2.4000998 0.51913307 2.39493327 0.51146663 1 P 0 ;0,1,2=393,3=90.000000
L 2.39493327 0.51146663 2.39131644 0.50801663 1 P 0 ;0,1,2=393,3=90.000000
L 2.39131644 0.50801663 2.38614892 0.50571644 1 P 0 ;0,1,2=393,3=90.000000
L 2.38614892 0.50571644 2.3815 0.5049499 1 P 0 ;0,1,2=393,3=90.000000
L 2.3815 0.5049499 2.3815 0.52105 1 P 0 ;0,1,2=393,3=90.000000
L 2.38769961 0.53556663 2.38408278 0.53786614 1 P 0 ;0,1,2=393,3=90.000000
L 2.38408278 0.53786614 2.38201654 0.54093287 1 P 0 ;0,1,2=393,3=90.000000
L 2.38201654 0.54093287 2.3815 0.54438356 1 P 0 ;0,1,2=393,3=90.000000
L 2.3815 0.54438356 2.38201654 0.5474503 1 P 0 ;0,1,2=393,3=90.000000
L 2.38201654 0.5474503 2.38459931 0.55051703 1 P 0 ;0,1,2=393,3=90.000000
L 2.38459931 0.55051703 2.38769961 0.55243327 1 P 0 ;0,1,2=393,3=90.000000
L 2.38769961 0.55243327 2.3907999 0.55281654 1 P 0 ;0,1,2=393,3=90.000000
L 2.3907999 0.55281654 2.39441575 0.55205 1 P 0 ;0,1,2=393,3=90.000000
L 2.39441575 0.55205 2.39699951 0.54936654 1 P 0 ;0,1,2=393,3=90.000000
L 2.39699951 0.54936654 2.39803356 0.54668307 1 P 0 ;0,1,2=393,3=90.000000
L 2.39803356 0.54668307 2.39803356 0.54323307 1 P 0 ;0,1,2=393,3=90.000000
L 2.39803356 0.54668307 2.39958317 0.54898327 1 P 0 ;0,1,2=393,3=90.000000
L 2.39958317 0.54898327 2.40216594 0.5509002 1 P 0 ;0,1,2=393,3=90.000000
L 2.40216594 0.5509002 2.40526624 0.55166673 1 P 0 ;0,1,2=393,3=90.000000
L 2.40526624 0.55166673 2.40836654 0.5509002 1 P 0 ;0,1,2=393,3=90.000000
L 2.40836654 0.5509002 2.41094931 0.54898327 1 P 0 ;0,1,2=393,3=90.000000
L 2.41094931 0.54898327 2.4125 0.54553327 1 P 0 ;0,1,2=393,3=90.000000
L 2.4125 0.54553327 2.41198337 0.54208337 1 P 0 ;0,1,2=393,3=90.000000
L 2.41198337 0.54208337 2.40991624 0.53863337 1 P 0 ;0,1,2=393,3=90.000000
L 2.222 0.59 2.178 0.59 1 P 0 
L 2.222 0.68 2.222 0.59 1 P 0 
L 2.178 0.68 2.222 0.68 1 P 0 
L 2.178 0.59 2.178 0.68 1 P 0 
L 2.23791624 0.75693327 2.23946683 0.75463307 1 P 0 ;0,1,2=394,3=90.000000
L 2.23946683 0.75463307 2.2405 0.7519503 1 P 0 ;0,1,2=394,3=90.000000
L 2.2405 0.7519503 2.2405 0.74888356 1 P 0 ;0,1,2=394,3=90.000000
L 2.2405 0.74888356 2.23894931 0.74543287 1 P 0 ;0,1,2=394,3=90.000000
L 2.23894931 0.74543287 2.23636654 0.7427501 1 P 0 ;0,1,2=394,3=90.000000
L 2.23636654 0.7427501 2.23326624 0.74083317 1 P 0 ;0,1,2=394,3=90.000000
L 2.23326624 0.74083317 2.2280998 0.73929951 1 P 0 ;0,1,2=394,3=90.000000
L 2.2280998 0.73929951 2.2234498 0.73891624 1 P 0 ;0,1,2=394,3=90.000000
L 2.2234498 0.73891624 2.2187999 0.73968337 1 P 0 ;0,1,2=394,3=90.000000
L 2.2187999 0.73968337 2.21569961 0.74083317 1 P 0 ;0,1,2=394,3=90.000000
L 2.21569961 0.74083317 2.21259931 0.74313337 1 P 0 ;0,1,2=394,3=90.000000
L 2.21259931 0.74313337 2.21053307 0.74581683 1 P 0 ;0,1,2=394,3=90.000000
L 2.21053307 0.74581683 2.2095 0.74849961 1 P 0 ;0,1,2=394,3=90.000000
L 2.2095 0.74849961 2.2095 0.75118307 1 P 0 ;0,1,2=394,3=90.000000
L 2.2095 0.75118307 2.21053307 0.75386654 1 P 0 ;0,1,2=394,3=90.000000
L 2.21053307 0.75386654 2.21208278 0.75616673 1 P 0 ;0,1,2=394,3=90.000000
L 2.21208278 0.75616673 2.21414892 0.75808366 1 P 0 ;0,1,2=394,3=90.000000
L 2.23533346 0.77221644 2.23843278 0.77451663 1 P 0 ;0,1,2=394,3=90.000000
L 2.23843278 0.77451663 2.23998337 0.7772001 1 P 0 ;0,1,2=394,3=90.000000
L 2.23998337 0.7772001 2.2405 0.78026683 1 P 0 ;0,1,2=394,3=90.000000
L 2.2405 0.78026683 2.23946683 0.7841 1 P 0 ;0,1,2=394,3=90.000000
L 2.23946683 0.7841 2.23688307 0.78678346 1 P 0 ;0,1,2=394,3=90.000000
L 2.23688307 0.78678346 2.23378376 0.78755 1 P 0 ;0,1,2=394,3=90.000000
L 2.23378376 0.78755 2.23068258 0.78716673 1 P 0 ;0,1,2=394,3=90.000000
L 2.23068258 0.78716673 2.2280998 0.78563307 1 P 0 ;0,1,2=394,3=90.000000
L 2.2280998 0.78563307 2.22293327 0.77796663 1 P 0 ;0,1,2=394,3=90.000000
L 2.22293327 0.77796663 2.21931644 0.77451663 1 P 0 ;0,1,2=394,3=90.000000
L 2.21931644 0.77451663 2.21414892 0.77221644 1 P 0 ;0,1,2=394,3=90.000000
L 2.21414892 0.77221644 2.2095 0.7714499 1 P 0 ;0,1,2=394,3=90.000000
L 2.2095 0.7714499 2.2095 0.78755 1 P 0 ;0,1,2=394,3=90.000000
L 2.21311585 0.80398287 2.21053307 0.80666634 1 P 0 ;0,1,2=394,3=90.000000
L 2.21053307 0.80666634 2.2095 0.80973307 1 P 0 ;0,1,2=394,3=90.000000
L 2.2095 0.80973307 2.21053307 0.8127998 1 P 0 ;0,1,2=394,3=90.000000
L 2.21053307 0.8127998 2.21363238 0.81548327 1 P 0 ;0,1,2=394,3=90.000000
L 2.21363238 0.81548327 2.21828327 0.8174002 1 P 0 ;0,1,2=394,3=90.000000
L 2.21828327 0.8174002 2.22293327 0.81816673 1 P 0 ;0,1,2=394,3=90.000000
L 2.22293327 0.81816673 2.22861634 0.81816673 1 P 0 ;0,1,2=394,3=90.000000
L 2.22861634 0.81816673 2.23326624 0.8174002 1 P 0 ;0,1,2=394,3=90.000000
L 2.23326624 0.8174002 2.2373997 0.81548327 1 P 0 ;0,1,2=394,3=90.000000
L 2.2373997 0.81548327 2.23946683 0.81318307 1 P 0 ;0,1,2=394,3=90.000000
L 2.23946683 0.81318307 2.2405 0.81049961 1 P 0 ;0,1,2=394,3=90.000000
L 2.2405 0.81049961 2.23946683 0.80743287 1 P 0 ;0,1,2=394,3=90.000000
L 2.23946683 0.80743287 2.2373997 0.80513337 1 P 0 ;0,1,2=394,3=90.000000
L 2.2373997 0.80513337 2.2343003 0.8035997 1 P 0 ;0,1,2=394,3=90.000000
L 2.2343003 0.8035997 2.23016594 0.80283317 1 P 0 ;0,1,2=394,3=90.000000
L 2.23016594 0.80283317 2.2265501 0.8035997 1 P 0 ;0,1,2=394,3=90.000000
L 2.2265501 0.8035997 2.22293327 0.80551663 1 P 0 ;0,1,2=394,3=90.000000
L 2.22293327 0.80551663 2.22086604 0.80781683 1 P 0 ;0,1,2=394,3=90.000000
L 2.22086604 0.80781683 2.22034951 0.81049961 1 P 0 ;0,1,2=394,3=90.000000
L 2.22034951 0.81049961 2.22138268 0.81356634 1 P 0 ;0,1,2=394,3=90.000000
L 2.22138268 0.81356634 2.22396634 0.81586654 1 P 0 ;0,1,2=394,3=90.000000
L 2.22396634 0.81586654 2.22861634 0.81816673 1 P 0 ;0,1,2=394,3=90.000000
L 2.2405 0.84149961 2.23946683 0.83843287 1 P 0 ;0,1,2=394,3=90.000000
L 2.23946683 0.83843287 2.23688307 0.83613337 1 P 0 ;0,1,2=394,3=90.000000
L 2.23688307 0.83613337 2.23378376 0.8345997 1 P 0 ;0,1,2=394,3=90.000000
L 2.23378376 0.8345997 2.22964941 0.8334499 1 P 0 ;0,1,2=394,3=90.000000
L 2.22964941 0.8334499 2.22499951 0.83306663 1 P 0 ;0,1,2=394,3=90.000000
L 2.22499951 0.83306663 2.22034951 0.8334499 1 P 0 ;0,1,2=394,3=90.000000
L 2.22034951 0.8334499 2.21621614 0.8345997 1 P 0 ;0,1,2=394,3=90.000000
L 2.21621614 0.8345997 2.21311585 0.83613337 1 P 0 ;0,1,2=394,3=90.000000
L 2.21311585 0.83613337 2.21053307 0.83843287 1 P 0 ;0,1,2=394,3=90.000000
L 2.21053307 0.83843287 2.2095 0.84149961 1 P 0 ;0,1,2=394,3=90.000000
L 2.2095 0.84149961 2.21053307 0.84456634 1 P 0 ;0,1,2=394,3=90.000000
L 2.21053307 0.84456634 2.21311585 0.84686654 1 P 0 ;0,1,2=394,3=90.000000
L 2.21311585 0.84686654 2.21621614 0.8484002 1 P 0 ;0,1,2=394,3=90.000000
L 2.21621614 0.8484002 2.22034951 0.84955 1 P 0 ;0,1,2=394,3=90.000000
L 2.22034951 0.84955 2.22499951 0.84993327 1 P 0 ;0,1,2=394,3=90.000000
L 2.22499951 0.84993327 2.22964941 0.84955 1 P 0 ;0,1,2=394,3=90.000000
L 2.22964941 0.84955 2.23378376 0.8484002 1 P 0 ;0,1,2=394,3=90.000000
L 2.23378376 0.8484002 2.23688307 0.84686654 1 P 0 ;0,1,2=394,3=90.000000
L 2.23688307 0.84686654 2.23946683 0.84456634 1 P 0 ;0,1,2=394,3=90.000000
L 2.23946683 0.84456634 2.2405 0.84149961 1 P 0 ;0,1,2=394,3=90.000000
L 2.177 0.59 2.133 0.59 1 P 0 
L 2.177 0.68 2.177 0.59 1 P 0 
L 2.133 0.68 2.177 0.68 1 P 0 
L 2.133 0.59 2.133 0.68 1 P 0 
L 2.19791624 0.75693327 2.19946683 0.75463307 1 P 0 ;0,1,2=395,3=90.000000
L 2.19946683 0.75463307 2.2005 0.7519503 1 P 0 ;0,1,2=395,3=90.000000
L 2.2005 0.7519503 2.2005 0.74888356 1 P 0 ;0,1,2=395,3=90.000000
L 2.2005 0.74888356 2.19894931 0.74543287 1 P 0 ;0,1,2=395,3=90.000000
L 2.19894931 0.74543287 2.19636654 0.7427501 1 P 0 ;0,1,2=395,3=90.000000
L 2.19636654 0.7427501 2.19326624 0.74083317 1 P 0 ;0,1,2=395,3=90.000000
L 2.19326624 0.74083317 2.1880998 0.73929951 1 P 0 ;0,1,2=395,3=90.000000
L 2.1880998 0.73929951 2.1834498 0.73891624 1 P 0 ;0,1,2=395,3=90.000000
L 2.1834498 0.73891624 2.1787999 0.73968337 1 P 0 ;0,1,2=395,3=90.000000
L 2.1787999 0.73968337 2.17569961 0.74083317 1 P 0 ;0,1,2=395,3=90.000000
L 2.17569961 0.74083317 2.17259931 0.74313337 1 P 0 ;0,1,2=395,3=90.000000
L 2.17259931 0.74313337 2.17053307 0.74581683 1 P 0 ;0,1,2=395,3=90.000000
L 2.17053307 0.74581683 2.1695 0.74849961 1 P 0 ;0,1,2=395,3=90.000000
L 2.1695 0.74849961 2.1695 0.75118307 1 P 0 ;0,1,2=395,3=90.000000
L 2.1695 0.75118307 2.17053307 0.75386654 1 P 0 ;0,1,2=395,3=90.000000
L 2.17053307 0.75386654 2.17208278 0.75616673 1 P 0 ;0,1,2=395,3=90.000000
L 2.17208278 0.75616673 2.17414892 0.75808366 1 P 0 ;0,1,2=395,3=90.000000
L 2.19533346 0.77221644 2.19843278 0.77451663 1 P 0 ;0,1,2=395,3=90.000000
L 2.19843278 0.77451663 2.19998337 0.7772001 1 P 0 ;0,1,2=395,3=90.000000
L 2.19998337 0.7772001 2.2005 0.78026683 1 P 0 ;0,1,2=395,3=90.000000
L 2.2005 0.78026683 2.19946683 0.7841 1 P 0 ;0,1,2=395,3=90.000000
L 2.19946683 0.7841 2.19688307 0.78678346 1 P 0 ;0,1,2=395,3=90.000000
L 2.19688307 0.78678346 2.19378376 0.78755 1 P 0 ;0,1,2=395,3=90.000000
L 2.19378376 0.78755 2.19068258 0.78716673 1 P 0 ;0,1,2=395,3=90.000000
L 2.19068258 0.78716673 2.1880998 0.78563307 1 P 0 ;0,1,2=395,3=90.000000
L 2.1880998 0.78563307 2.18293327 0.77796663 1 P 0 ;0,1,2=395,3=90.000000
L 2.18293327 0.77796663 2.17931644 0.77451663 1 P 0 ;0,1,2=395,3=90.000000
L 2.17931644 0.77451663 2.17414892 0.77221644 1 P 0 ;0,1,2=395,3=90.000000
L 2.17414892 0.77221644 2.1695 0.7714499 1 P 0 ;0,1,2=395,3=90.000000
L 2.1695 0.7714499 2.1695 0.78755 1 P 0 ;0,1,2=395,3=90.000000
L 2.1695 0.81049961 2.17001654 0.81318307 1 P 0 ;0,1,2=395,3=90.000000
L 2.17001654 0.81318307 2.17156614 0.8162498 1 P 0 ;0,1,2=395,3=90.000000
L 2.17156614 0.8162498 2.17414892 0.81816673 1 P 0 ;0,1,2=395,3=90.000000
L 2.17414892 0.81816673 2.17776673 0.81893327 1 P 0 ;0,1,2=395,3=90.000000
L 2.17776673 0.81893327 2.18138268 0.81816673 1 P 0 ;0,1,2=395,3=90.000000
L 2.18138268 0.81816673 2.18448287 0.81586654 1 P 0 ;0,1,2=395,3=90.000000
L 2.18448287 0.81586654 2.18603356 0.81241654 1 P 0 ;0,1,2=395,3=90.000000
L 2.18603356 0.81241654 2.18603356 0.80858337 1 P 0 ;0,1,2=395,3=90.000000
L 2.18603356 0.80858337 2.18706663 0.80628317 1 P 0 ;0,1,2=395,3=90.000000
L 2.18706663 0.80628317 2.18964941 0.80436614 1 P 0 ;0,1,2=395,3=90.000000
L 2.18964941 0.80436614 2.19326624 0.8035997 1 P 0 ;0,1,2=395,3=90.000000
L 2.19326624 0.8035997 2.19688307 0.8047501 1 P 0 ;0,1,2=395,3=90.000000
L 2.19688307 0.8047501 2.19946683 0.80743287 1 P 0 ;0,1,2=395,3=90.000000
L 2.19946683 0.80743287 2.2005 0.81049961 1 P 0 ;0,1,2=395,3=90.000000
L 2.2005 0.81049961 2.19946683 0.81356634 1 P 0 ;0,1,2=395,3=90.000000
L 2.19946683 0.81356634 2.19688307 0.8162498 1 P 0 ;0,1,2=395,3=90.000000
L 2.19688307 0.8162498 2.19326624 0.8174002 1 P 0 ;0,1,2=395,3=90.000000
L 2.19326624 0.8174002 2.18964941 0.81663307 1 P 0 ;0,1,2=395,3=90.000000
L 2.18964941 0.81663307 2.18706663 0.81471673 1 P 0 ;0,1,2=395,3=90.000000
L 2.18706663 0.81471673 2.18603356 0.81241654 1 P 0 ;0,1,2=395,3=90.000000
L 2.18603356 0.81241654 2.18603356 0.80858337 1 P 0 ;0,1,2=395,3=90.000000
L 2.18603356 0.80858337 2.18448287 0.80513337 1 P 0 ;0,1,2=395,3=90.000000
L 2.18448287 0.80513337 2.18138268 0.80283317 1 P 0 ;0,1,2=395,3=90.000000
L 2.18138268 0.80283317 2.17776673 0.80206663 1 P 0 ;0,1,2=395,3=90.000000
L 2.17776673 0.80206663 2.17414892 0.80283317 1 P 0 ;0,1,2=395,3=90.000000
L 2.17414892 0.80283317 2.17156614 0.8047501 1 P 0 ;0,1,2=395,3=90.000000
L 2.17156614 0.8047501 2.17001654 0.80781683 1 P 0 ;0,1,2=395,3=90.000000
L 2.17001654 0.80781683 2.1695 0.81049961 1 P 0 ;0,1,2=395,3=90.000000
L 2.17311585 0.83498287 2.17053307 0.83766634 1 P 0 ;0,1,2=395,3=90.000000
L 2.17053307 0.83766634 2.1695 0.84073307 1 P 0 ;0,1,2=395,3=90.000000
L 2.1695 0.84073307 2.17053307 0.8437998 1 P 0 ;0,1,2=395,3=90.000000
L 2.17053307 0.8437998 2.17363238 0.84648327 1 P 0 ;0,1,2=395,3=90.000000
L 2.17363238 0.84648327 2.17828327 0.8484002 1 P 0 ;0,1,2=395,3=90.000000
L 2.17828327 0.8484002 2.18293327 0.84916673 1 P 0 ;0,1,2=395,3=90.000000
L 2.18293327 0.84916673 2.18861634 0.84916673 1 P 0 ;0,1,2=395,3=90.000000
L 2.18861634 0.84916673 2.19326624 0.8484002 1 P 0 ;0,1,2=395,3=90.000000
L 2.19326624 0.8484002 2.1973997 0.84648327 1 P 0 ;0,1,2=395,3=90.000000
L 2.1973997 0.84648327 2.19946683 0.84418307 1 P 0 ;0,1,2=395,3=90.000000
L 2.19946683 0.84418307 2.2005 0.84149961 1 P 0 ;0,1,2=395,3=90.000000
L 2.2005 0.84149961 2.19946683 0.83843287 1 P 0 ;0,1,2=395,3=90.000000
L 2.19946683 0.83843287 2.1973997 0.83613337 1 P 0 ;0,1,2=395,3=90.000000
L 2.1973997 0.83613337 2.1943003 0.8345997 1 P 0 ;0,1,2=395,3=90.000000
L 2.1943003 0.8345997 2.19016594 0.83383317 1 P 0 ;0,1,2=395,3=90.000000
L 2.19016594 0.83383317 2.1865501 0.8345997 1 P 0 ;0,1,2=395,3=90.000000
L 2.1865501 0.8345997 2.18293327 0.83651663 1 P 0 ;0,1,2=395,3=90.000000
L 2.18293327 0.83651663 2.18086604 0.83881683 1 P 0 ;0,1,2=395,3=90.000000
L 2.18086604 0.83881683 2.18034951 0.84149961 1 P 0 ;0,1,2=395,3=90.000000
L 2.18034951 0.84149961 2.18138268 0.84456634 1 P 0 ;0,1,2=395,3=90.000000
L 2.18138268 0.84456634 2.18396634 0.84686654 1 P 0 ;0,1,2=395,3=90.000000
L 2.18396634 0.84686654 2.18861634 0.84916673 1 P 0 ;0,1,2=395,3=90.000000
L 3.483 1.765 3.483 1.855 1 P 0 
L 3.527 1.765 3.483 1.765 1 P 0 
L 3.527 1.855 3.527 1.765 1 P 0 
L 3.483 1.855 3.527 1.855 1 P 0 
L 3.45791624 1.77243327 3.45946683 1.77013307 1 P 0 ;0,1,2=396,3=90.000000
L 3.45946683 1.77013307 3.4605 1.7674503 1 P 0 ;0,1,2=396,3=90.000000
L 3.4605 1.7674503 3.4605 1.76438356 1 P 0 ;0,1,2=396,3=90.000000
L 3.4605 1.76438356 3.45894931 1.76093287 1 P 0 ;0,1,2=396,3=90.000000
L 3.45894931 1.76093287 3.45636654 1.7582501 1 P 0 ;0,1,2=396,3=90.000000
L 3.45636654 1.7582501 3.45326624 1.75633317 1 P 0 ;0,1,2=396,3=90.000000
L 3.45326624 1.75633317 3.4480998 1.75479951 1 P 0 ;0,1,2=396,3=90.000000
L 3.4480998 1.75479951 3.4434498 1.75441624 1 P 0 ;0,1,2=396,3=90.000000
L 3.4434498 1.75441624 3.4387999 1.75518337 1 P 0 ;0,1,2=396,3=90.000000
L 3.4387999 1.75518337 3.43569961 1.75633317 1 P 0 ;0,1,2=396,3=90.000000
L 3.43569961 1.75633317 3.43259931 1.75863337 1 P 0 ;0,1,2=396,3=90.000000
L 3.43259931 1.75863337 3.43053307 1.76131683 1 P 0 ;0,1,2=396,3=90.000000
L 3.43053307 1.76131683 3.4295 1.76399961 1 P 0 ;0,1,2=396,3=90.000000
L 3.4295 1.76399961 3.4295 1.76668307 1 P 0 ;0,1,2=396,3=90.000000
L 3.4295 1.76668307 3.43053307 1.76936654 1 P 0 ;0,1,2=396,3=90.000000
L 3.43053307 1.76936654 3.43208278 1.77166673 1 P 0 ;0,1,2=396,3=90.000000
L 3.43208278 1.77166673 3.43414892 1.77358366 1 P 0 ;0,1,2=396,3=90.000000
L 3.44241575 1.78771644 3.44603356 1.7903999 1 P 0 ;0,1,2=396,3=90.000000
L 3.44603356 1.7903999 3.4480998 1.7927001 1 P 0 ;0,1,2=396,3=90.000000
L 3.4480998 1.7927001 3.44913287 1.79576683 1 P 0 ;0,1,2=396,3=90.000000
L 3.44913287 1.79576683 3.4480998 1.7984503 1 P 0 ;0,1,2=396,3=90.000000
L 3.4480998 1.7984503 3.44603356 1.80036654 1 P 0 ;0,1,2=396,3=90.000000
L 3.44603356 1.80036654 3.44293327 1.8019002 1 P 0 ;0,1,2=396,3=90.000000
L 3.44293327 1.8019002 3.43931644 1.80228346 1 P 0 ;0,1,2=396,3=90.000000
L 3.43931644 1.80228346 3.43621614 1.8019002 1 P 0 ;0,1,2=396,3=90.000000
L 3.43621614 1.8019002 3.43311585 1.80036654 1 P 0 ;0,1,2=396,3=90.000000
L 3.43311585 1.80036654 3.43053307 1.79806634 1 P 0 ;0,1,2=396,3=90.000000
L 3.43053307 1.79806634 3.4295 1.79538356 1 P 0 ;0,1,2=396,3=90.000000
L 3.4295 1.79538356 3.43053307 1.79231683 1 P 0 ;0,1,2=396,3=90.000000
L 3.43053307 1.79231683 3.43363238 1.78963337 1 P 0 ;0,1,2=396,3=90.000000
L 3.43363238 1.78963337 3.43828327 1.7880997 1 P 0 ;0,1,2=396,3=90.000000
L 3.43828327 1.7880997 3.4434498 1.78771644 1 P 0 ;0,1,2=396,3=90.000000
L 3.4434498 1.78771644 3.45016594 1.78848287 1 P 0 ;0,1,2=396,3=90.000000
L 3.45016594 1.78848287 3.45378376 1.78963337 1 P 0 ;0,1,2=396,3=90.000000
L 3.45378376 1.78963337 3.4573997 1.79154961 1 P 0 ;0,1,2=396,3=90.000000
L 3.4573997 1.79154961 3.45998337 1.79423307 1 P 0 ;0,1,2=396,3=90.000000
L 3.45998337 1.79423307 3.4605 1.79691654 1 P 0 ;0,1,2=396,3=90.000000
L 3.4605 1.79691654 3.45946683 1.7996 1 P 0 ;0,1,2=396,3=90.000000
L 3.45946683 1.7996 3.45688307 1.80151703 1 P 0 ;0,1,2=396,3=90.000000
L 3.4295 1.82523307 3.43621614 1.82599961 1 P 0 ;0,1,2=396,3=90.000000
L 3.43621614 1.82599961 3.44189921 1.8271501 1 P 0 ;0,1,2=396,3=90.000000
L 3.44189921 1.8271501 3.44706663 1.82868307 1 P 0 ;0,1,2=396,3=90.000000
L 3.44706663 1.82868307 3.4527497 1.8306 1 P 0 ;0,1,2=396,3=90.000000
L 3.4527497 1.8306 3.4605 1.83366673 1 P 0 ;0,1,2=396,3=90.000000
L 3.4605 1.83366673 3.4605 1.81833317 1 P 0 ;0,1,2=396,3=90.000000
L 3.94228996 1.31561004 3.94228996 1.27161004 1 P 0 
L 3.85228996 1.27161004 3.85228996 1.31561004 1 P 0 
L 3.94228996 1.27161004 3.85228996 1.27161004 1 P 0 
L 3.85228996 1.31561004 3.94228996 1.31561004 1 P 0 
L 4.05306673 1.29791624 4.05536693 1.29946683 1 P 0 ;0,1,2=397,3=0.000000
L 4.05536693 1.29946683 4.0580497 1.3005 1 P 0 ;0,1,2=397,3=0.000000
L 4.0580497 1.3005 4.06111644 1.3005 1 P 0 ;0,1,2=397,3=0.000000
L 4.06111644 1.3005 4.06456713 1.29894931 1 P 0 ;0,1,2=397,3=0.000000
L 4.06456713 1.29894931 4.0672499 1.29636654 1 P 0 ;0,1,2=397,3=0.000000
L 4.0672499 1.29636654 4.06916683 1.29326624 1 P 0 ;0,1,2=397,3=0.000000
L 4.06916683 1.29326624 4.07070049 1.2880998 1 P 0 ;0,1,2=397,3=0.000000
L 4.07070049 1.2880998 4.07108376 1.2834498 1 P 0 ;0,1,2=397,3=0.000000
L 4.07108376 1.2834498 4.07031663 1.2787999 1 P 0 ;0,1,2=397,3=0.000000
L 4.07031663 1.2787999 4.06916683 1.27569961 1 P 0 ;0,1,2=397,3=0.000000
L 4.06916683 1.27569961 4.06686663 1.27259931 1 P 0 ;0,1,2=397,3=0.000000
L 4.06686663 1.27259931 4.06418317 1.27053307 1 P 0 ;0,1,2=397,3=0.000000
L 4.06418317 1.27053307 4.06150039 1.2695 1 P 0 ;0,1,2=397,3=0.000000
L 4.06150039 1.2695 4.05881693 1.2695 1 P 0 ;0,1,2=397,3=0.000000
L 4.05881693 1.2695 4.05613346 1.27053307 1 P 0 ;0,1,2=397,3=0.000000
L 4.05613346 1.27053307 4.05383327 1.27208278 1 P 0 ;0,1,2=397,3=0.000000
L 4.05383327 1.27208278 4.05191634 1.27414892 1 P 0 ;0,1,2=397,3=0.000000
L 4.03050039 1.2695 4.03050039 1.3005 1 P 0 ;0,1,2=397,3=0.000000
L 4.03050039 1.3005 4.0351001 1.2943003 1 P 0 ;0,1,2=397,3=0.000000
L 4.0351001 1.2695 4.02590069 1.2695 1 P 0 ;0,1,2=397,3=0.000000
L 3.99950039 1.2695 3.99950039 1.3005 1 P 0 ;0,1,2=397,3=0.000000
L 3.99950039 1.3005 4.0041001 1.2943003 1 P 0 ;0,1,2=397,3=0.000000
L 4.0041001 1.2695 3.99490069 1.2695 1 P 0 ;0,1,2=397,3=0.000000
L 3.97578356 1.28241575 3.9731001 1.28603356 1 P 0 ;0,1,2=397,3=0.000000
L 3.9731001 1.28603356 3.9707999 1.2880998 1 P 0 ;0,1,2=397,3=0.000000
L 3.9707999 1.2880998 3.96773317 1.28913287 1 P 0 ;0,1,2=397,3=0.000000
L 3.96773317 1.28913287 3.9650497 1.2880998 1 P 0 ;0,1,2=397,3=0.000000
L 3.9650497 1.2880998 3.96313346 1.28603356 1 P 0 ;0,1,2=397,3=0.000000
L 3.96313346 1.28603356 3.9615998 1.28293327 1 P 0 ;0,1,2=397,3=0.000000
L 3.9615998 1.28293327 3.96121654 1.27931644 1 P 0 ;0,1,2=397,3=0.000000
L 3.96121654 1.27931644 3.9615998 1.27621614 1 P 0 ;0,1,2=397,3=0.000000
L 3.9615998 1.27621614 3.96313346 1.27311585 1 P 0 ;0,1,2=397,3=0.000000
L 3.96313346 1.27311585 3.96543366 1.27053307 1 P 0 ;0,1,2=397,3=0.000000
L 3.96543366 1.27053307 3.96811644 1.2695 1 P 0 ;0,1,2=397,3=0.000000
L 3.96811644 1.2695 3.97118317 1.27053307 1 P 0 ;0,1,2=397,3=0.000000
L 3.97118317 1.27053307 3.97386663 1.27363238 1 P 0 ;0,1,2=397,3=0.000000
L 3.97386663 1.27363238 3.9754003 1.27828327 1 P 0 ;0,1,2=397,3=0.000000
L 3.9754003 1.27828327 3.97578356 1.2834498 1 P 0 ;0,1,2=397,3=0.000000
L 3.97578356 1.2834498 3.97501713 1.29016594 1 P 0 ;0,1,2=397,3=0.000000
L 3.97501713 1.29016594 3.97386663 1.29378376 1 P 0 ;0,1,2=397,3=0.000000
L 3.97386663 1.29378376 3.97195039 1.2973997 1 P 0 ;0,1,2=397,3=0.000000
L 3.97195039 1.2973997 3.96926693 1.29998337 1 P 0 ;0,1,2=397,3=0.000000
L 3.96926693 1.29998337 3.96658346 1.3005 1 P 0 ;0,1,2=397,3=0.000000
L 3.96658346 1.3005 3.9639 1.29946683 1 P 0 ;0,1,2=397,3=0.000000
L 3.9639 1.29946683 3.96198297 1.29688307 1 P 0 ;0,1,2=397,3=0.000000
L 3.8203 1.767 3.9103 1.767 1 P 0 
L 3.8203 1.723 3.8203 1.767 1 P 0 
L 3.9103 1.723 3.8203 1.723 1 P 0 
L 3.9103 1.767 3.9103 1.723 1 P 0 
L 3.88713337 1.81291634 3.88873356 1.81416683 1 P 0 ;0,1,2=398,3=0.000000
L 3.88873356 1.81416683 3.8905998 1.815 1 P 0 ;0,1,2=398,3=0.000000
L 3.8905998 1.815 3.89273317 1.815 1 P 0 ;0,1,2=398,3=0.000000
L 3.89273317 1.815 3.89513366 1.81374941 1 P 0 ;0,1,2=398,3=0.000000
L 3.89513366 1.81374941 3.8969999 1.81166654 1 P 0 ;0,1,2=398,3=0.000000
L 3.8969999 1.81166654 3.89833346 1.80916634 1 P 0 ;0,1,2=398,3=0.000000
L 3.89833346 1.80916634 3.89940039 1.8049998 1 P 0 ;0,1,2=398,3=0.000000
L 3.89940039 1.8049998 3.89966703 1.8012498 1 P 0 ;0,1,2=398,3=0.000000
L 3.89966703 1.8012498 3.89913327 1.7974999 1 P 0 ;0,1,2=398,3=0.000000
L 3.89913327 1.7974999 3.89833346 1.79499961 1 P 0 ;0,1,2=398,3=0.000000
L 3.89833346 1.79499961 3.89673337 1.79249941 1 P 0 ;0,1,2=398,3=0.000000
L 3.89673337 1.79249941 3.89486654 1.79083307 1 P 0 ;0,1,2=398,3=0.000000
L 3.89486654 1.79083307 3.8930003 1.79 1 P 0 ;0,1,2=398,3=0.000000
L 3.8930003 1.79 3.89113356 1.79 1 P 0 ;0,1,2=398,3=0.000000
L 3.89113356 1.79 3.88926673 1.79083307 1 P 0 ;0,1,2=398,3=0.000000
L 3.88926673 1.79083307 3.88766663 1.79208287 1 P 0 ;0,1,2=398,3=0.000000
L 3.88766663 1.79208287 3.88633307 1.79374911 1 P 0 ;0,1,2=398,3=0.000000
L 3.8710003 1.79 3.8710003 1.815 1 P 0 ;0,1,2=398,3=0.000000
L 3.8710003 1.815 3.8742001 1.8100003 1 P 0 ;0,1,2=398,3=0.000000
L 3.8742001 1.79 3.86780049 1.79 1 P 0 ;0,1,2=398,3=0.000000
L 3.8490003 1.815 3.85113366 1.81416683 1 P 0 ;0,1,2=398,3=0.000000
L 3.85113366 1.81416683 3.85273337 1.81208317 1 P 0 ;0,1,2=398,3=0.000000
L 3.85273337 1.81208317 3.8538002 1.80958366 1 P 0 ;0,1,2=398,3=0.000000
L 3.8538002 1.80958366 3.8546001 1.80624951 1 P 0 ;0,1,2=398,3=0.000000
L 3.8546001 1.80624951 3.85486673 1.80249961 1 P 0 ;0,1,2=398,3=0.000000
L 3.85486673 1.80249961 3.8546001 1.79874961 1 P 0 ;0,1,2=398,3=0.000000
L 3.8546001 1.79874961 3.8538002 1.79541624 1 P 0 ;0,1,2=398,3=0.000000
L 3.8538002 1.79541624 3.85273337 1.79291604 1 P 0 ;0,1,2=398,3=0.000000
L 3.85273337 1.79291604 3.85113366 1.79083307 1 P 0 ;0,1,2=398,3=0.000000
L 3.85113366 1.79083307 3.8490003 1.79 1 P 0 ;0,1,2=398,3=0.000000
L 3.8490003 1.79 3.84686693 1.79083307 1 P 0 ;0,1,2=398,3=0.000000
L 3.84686693 1.79083307 3.84526673 1.79291604 1 P 0 ;0,1,2=398,3=0.000000
L 3.84526673 1.79291604 3.8441999 1.79541624 1 P 0 ;0,1,2=398,3=0.000000
L 3.8441999 1.79541624 3.8434 1.79874961 1 P 0 ;0,1,2=398,3=0.000000
L 3.8434 1.79874961 3.84313337 1.80249961 1 P 0 ;0,1,2=398,3=0.000000
L 3.84313337 1.80249961 3.8434 1.80624951 1 P 0 ;0,1,2=398,3=0.000000
L 3.8434 1.80624951 3.8441999 1.80958366 1 P 0 ;0,1,2=398,3=0.000000
L 3.8441999 1.80958366 3.84526673 1.81208317 1 P 0 ;0,1,2=398,3=0.000000
L 3.84526673 1.81208317 3.84686693 1.81416683 1 P 0 ;0,1,2=398,3=0.000000
L 3.84686693 1.81416683 3.8490003 1.815 1 P 0 ;0,1,2=398,3=0.000000
L 3.8238 1.79 3.8238 1.815 1 P 0 ;0,1,2=398,3=0.000000
L 3.8238 1.815 3.83366703 1.79708327 1 P 0 ;0,1,2=398,3=0.000000
L 3.83366703 1.79708327 3.82033307 1.79708327 1 P 0 ;0,1,2=398,3=0.000000
L 3.958 3.405 3.958 3.495 1 P 0 
L 3.958 3.495 4.002 3.495 1 P 0 
L 4.002 3.495 4.002 3.405 1 P 0 
L 4.002 3.405 3.958 3.405 1 P 0 
L 4.04291624 3.40693327 4.04446683 3.40463307 1 P 0 ;0,1,2=399,3=90.000000
L 4.04446683 3.40463307 4.0455 3.4019503 1 P 0 ;0,1,2=399,3=90.000000
L 4.0455 3.4019503 4.0455 3.39888356 1 P 0 ;0,1,2=399,3=90.000000
L 4.0455 3.39888356 4.04394931 3.39543287 1 P 0 ;0,1,2=399,3=90.000000
L 4.04394931 3.39543287 4.04136654 3.3927501 1 P 0 ;0,1,2=399,3=90.000000
L 4.04136654 3.3927501 4.03826624 3.39083317 1 P 0 ;0,1,2=399,3=90.000000
L 4.03826624 3.39083317 4.0330998 3.38929951 1 P 0 ;0,1,2=399,3=90.000000
L 4.0330998 3.38929951 4.0284498 3.38891624 1 P 0 ;0,1,2=399,3=90.000000
L 4.0284498 3.38891624 4.0237999 3.38968337 1 P 0 ;0,1,2=399,3=90.000000
L 4.0237999 3.38968337 4.02069961 3.39083317 1 P 0 ;0,1,2=399,3=90.000000
L 4.02069961 3.39083317 4.01759931 3.39313337 1 P 0 ;0,1,2=399,3=90.000000
L 4.01759931 3.39313337 4.01553307 3.39581683 1 P 0 ;0,1,2=399,3=90.000000
L 4.01553307 3.39581683 4.0145 3.39849961 1 P 0 ;0,1,2=399,3=90.000000
L 4.0145 3.39849961 4.0145 3.40118307 1 P 0 ;0,1,2=399,3=90.000000
L 4.0145 3.40118307 4.01553307 3.40386654 1 P 0 ;0,1,2=399,3=90.000000
L 4.01553307 3.40386654 4.01708278 3.40616673 1 P 0 ;0,1,2=399,3=90.000000
L 4.01708278 3.40616673 4.01914892 3.40808366 1 P 0 ;0,1,2=399,3=90.000000
L 4.0145 3.42949961 4.0455 3.42949961 1 P 0 ;0,1,2=399,3=90.000000
L 4.0455 3.42949961 4.0393003 3.4248999 1 P 0 ;0,1,2=399,3=90.000000
L 4.0145 3.4248999 4.0145 3.43409931 1 P 0 ;0,1,2=399,3=90.000000
L 4.04033346 3.45321644 4.04343278 3.45551663 1 P 0 ;0,1,2=399,3=90.000000
L 4.04343278 3.45551663 4.04498337 3.4582001 1 P 0 ;0,1,2=399,3=90.000000
L 4.04498337 3.4582001 4.0455 3.46126683 1 P 0 ;0,1,2=399,3=90.000000
L 4.0455 3.46126683 4.04446683 3.4651 1 P 0 ;0,1,2=399,3=90.000000
L 4.04446683 3.4651 4.04188307 3.46778346 1 P 0 ;0,1,2=399,3=90.000000
L 4.04188307 3.46778346 4.03878376 3.46855 1 P 0 ;0,1,2=399,3=90.000000
L 4.03878376 3.46855 4.03568258 3.46816673 1 P 0 ;0,1,2=399,3=90.000000
L 4.03568258 3.46816673 4.0330998 3.46663307 1 P 0 ;0,1,2=399,3=90.000000
L 4.0330998 3.46663307 4.02793327 3.45896663 1 P 0 ;0,1,2=399,3=90.000000
L 4.02793327 3.45896663 4.02431644 3.45551663 1 P 0 ;0,1,2=399,3=90.000000
L 4.02431644 3.45551663 4.01914892 3.45321644 1 P 0 ;0,1,2=399,3=90.000000
L 4.01914892 3.45321644 4.0145 3.4524499 1 P 0 ;0,1,2=399,3=90.000000
L 4.0145 3.4524499 4.0145 3.46855 1 P 0 ;0,1,2=399,3=90.000000
L 4.02069961 3.48306663 4.01708278 3.48536614 1 P 0 ;0,1,2=399,3=90.000000
L 4.01708278 3.48536614 4.01501654 3.48843287 1 P 0 ;0,1,2=399,3=90.000000
L 4.01501654 3.48843287 4.0145 3.49188356 1 P 0 ;0,1,2=399,3=90.000000
L 4.0145 3.49188356 4.01501654 3.4949503 1 P 0 ;0,1,2=399,3=90.000000
L 4.01501654 3.4949503 4.01759931 3.49801703 1 P 0 ;0,1,2=399,3=90.000000
L 4.01759931 3.49801703 4.02069961 3.49993327 1 P 0 ;0,1,2=399,3=90.000000
L 4.02069961 3.49993327 4.0237999 3.50031654 1 P 0 ;0,1,2=399,3=90.000000
L 4.0237999 3.50031654 4.02741575 3.49955 1 P 0 ;0,1,2=399,3=90.000000
L 4.02741575 3.49955 4.02999951 3.49686654 1 P 0 ;0,1,2=399,3=90.000000
L 4.02999951 3.49686654 4.03103356 3.49418307 1 P 0 ;0,1,2=399,3=90.000000
L 4.03103356 3.49418307 4.03103356 3.49073307 1 P 0 ;0,1,2=399,3=90.000000
L 4.03103356 3.49418307 4.03258317 3.49648327 1 P 0 ;0,1,2=399,3=90.000000
L 4.03258317 3.49648327 4.03516594 3.4984002 1 P 0 ;0,1,2=399,3=90.000000
L 4.03516594 3.4984002 4.03826624 3.49916673 1 P 0 ;0,1,2=399,3=90.000000
L 4.03826624 3.49916673 4.04136654 3.4984002 1 P 0 ;0,1,2=399,3=90.000000
L 4.04136654 3.4984002 4.04394931 3.49648327 1 P 0 ;0,1,2=399,3=90.000000
L 4.04394931 3.49648327 4.0455 3.49303327 1 P 0 ;0,1,2=399,3=90.000000
L 4.0455 3.49303327 4.04498337 3.48958337 1 P 0 ;0,1,2=399,3=90.000000
L 4.04498337 3.48958337 4.04291624 3.48613337 1 P 0 ;0,1,2=399,3=90.000000
L 0.678 3.45 0.722 3.45 1 P 0 
L 0.722 3.45 0.722 3.36 1 P 0 
L 0.722 3.36 0.678 3.36 1 P 0 
L 0.678 3.36 0.678 3.45 1 P 0 
L 0.76291624 3.38743327 0.76446683 3.38513307 1 P 0 ;0,1,2=400,3=90.000000
L 0.76446683 3.38513307 0.7655 3.3824503 1 P 0 ;0,1,2=400,3=90.000000
L 0.7655 3.3824503 0.7655 3.37938356 1 P 0 ;0,1,2=400,3=90.000000
L 0.7655 3.37938356 0.76394931 3.37593287 1 P 0 ;0,1,2=400,3=90.000000
L 0.76394931 3.37593287 0.76136654 3.3732501 1 P 0 ;0,1,2=400,3=90.000000
L 0.76136654 3.3732501 0.75826624 3.37133317 1 P 0 ;0,1,2=400,3=90.000000
L 0.75826624 3.37133317 0.7530998 3.36979951 1 P 0 ;0,1,2=400,3=90.000000
L 0.7530998 3.36979951 0.7484498 3.36941624 1 P 0 ;0,1,2=400,3=90.000000
L 0.7484498 3.36941624 0.7437999 3.37018337 1 P 0 ;0,1,2=400,3=90.000000
L 0.7437999 3.37018337 0.74069961 3.37133317 1 P 0 ;0,1,2=400,3=90.000000
L 0.74069961 3.37133317 0.73759931 3.37363337 1 P 0 ;0,1,2=400,3=90.000000
L 0.73759931 3.37363337 0.73553307 3.37631683 1 P 0 ;0,1,2=400,3=90.000000
L 0.73553307 3.37631683 0.7345 3.37899961 1 P 0 ;0,1,2=400,3=90.000000
L 0.7345 3.37899961 0.7345 3.38168307 1 P 0 ;0,1,2=400,3=90.000000
L 0.7345 3.38168307 0.73553307 3.38436654 1 P 0 ;0,1,2=400,3=90.000000
L 0.73553307 3.38436654 0.73708278 3.38666673 1 P 0 ;0,1,2=400,3=90.000000
L 0.73708278 3.38666673 0.73914892 3.38858366 1 P 0 ;0,1,2=400,3=90.000000
L 0.73811585 3.40348287 0.73553307 3.40616634 1 P 0 ;0,1,2=400,3=90.000000
L 0.73553307 3.40616634 0.7345 3.40923307 1 P 0 ;0,1,2=400,3=90.000000
L 0.7345 3.40923307 0.73553307 3.4122998 1 P 0 ;0,1,2=400,3=90.000000
L 0.73553307 3.4122998 0.73863238 3.41498327 1 P 0 ;0,1,2=400,3=90.000000
L 0.73863238 3.41498327 0.74328327 3.4169002 1 P 0 ;0,1,2=400,3=90.000000
L 0.74328327 3.4169002 0.74793327 3.41766673 1 P 0 ;0,1,2=400,3=90.000000
L 0.74793327 3.41766673 0.75361634 3.41766673 1 P 0 ;0,1,2=400,3=90.000000
L 0.75361634 3.41766673 0.75826624 3.4169002 1 P 0 ;0,1,2=400,3=90.000000
L 0.75826624 3.4169002 0.7623997 3.41498327 1 P 0 ;0,1,2=400,3=90.000000
L 0.7623997 3.41498327 0.76446683 3.41268307 1 P 0 ;0,1,2=400,3=90.000000
L 0.76446683 3.41268307 0.7655 3.40999961 1 P 0 ;0,1,2=400,3=90.000000
L 0.7655 3.40999961 0.76446683 3.40693287 1 P 0 ;0,1,2=400,3=90.000000
L 0.76446683 3.40693287 0.7623997 3.40463337 1 P 0 ;0,1,2=400,3=90.000000
L 0.7623997 3.40463337 0.7593003 3.4030997 1 P 0 ;0,1,2=400,3=90.000000
L 0.7593003 3.4030997 0.75516594 3.40233317 1 P 0 ;0,1,2=400,3=90.000000
L 0.75516594 3.40233317 0.7515501 3.4030997 1 P 0 ;0,1,2=400,3=90.000000
L 0.7515501 3.4030997 0.74793327 3.40501663 1 P 0 ;0,1,2=400,3=90.000000
L 0.74793327 3.40501663 0.74586604 3.40731683 1 P 0 ;0,1,2=400,3=90.000000
L 0.74586604 3.40731683 0.74534951 3.40999961 1 P 0 ;0,1,2=400,3=90.000000
L 0.74534951 3.40999961 0.74638268 3.41306634 1 P 0 ;0,1,2=400,3=90.000000
L 0.74638268 3.41306634 0.74896634 3.41536654 1 P 0 ;0,1,2=400,3=90.000000
L 0.74896634 3.41536654 0.75361634 3.41766673 1 P 0 ;0,1,2=400,3=90.000000
L 0.7345 3.4456 0.7655 3.4456 1 P 0 ;0,1,2=400,3=90.000000
L 0.7655 3.4456 0.74328327 3.43141624 1 P 0 ;0,1,2=400,3=90.000000
L 0.74328327 3.43141624 0.74328327 3.45058366 1 P 0 ;0,1,2=400,3=90.000000
L 1.243 3.63 1.287 3.63 1 P 0 
L 1.243 3.54 1.243 3.63 1 P 0 
L 1.287 3.63 1.287 3.54 1 P 0 
L 1.287 3.54 1.243 3.54 1 P 0 
L 1.28291624 3.67193327 1.28446683 3.66963307 1 P 0 ;0,1,2=401,3=90.000000
L 1.28446683 3.66963307 1.2855 3.6669503 1 P 0 ;0,1,2=401,3=90.000000
L 1.2855 3.6669503 1.2855 3.66388356 1 P 0 ;0,1,2=401,3=90.000000
L 1.2855 3.66388356 1.28394931 3.66043287 1 P 0 ;0,1,2=401,3=90.000000
L 1.28394931 3.66043287 1.28136654 3.6577501 1 P 0 ;0,1,2=401,3=90.000000
L 1.28136654 3.6577501 1.27826624 3.65583317 1 P 0 ;0,1,2=401,3=90.000000
L 1.27826624 3.65583317 1.2730998 3.65429951 1 P 0 ;0,1,2=401,3=90.000000
L 1.2730998 3.65429951 1.2684498 3.65391624 1 P 0 ;0,1,2=401,3=90.000000
L 1.2684498 3.65391624 1.2637999 3.65468337 1 P 0 ;0,1,2=401,3=90.000000
L 1.2637999 3.65468337 1.26069961 3.65583317 1 P 0 ;0,1,2=401,3=90.000000
L 1.26069961 3.65583317 1.25759931 3.65813337 1 P 0 ;0,1,2=401,3=90.000000
L 1.25759931 3.65813337 1.25553307 3.66081683 1 P 0 ;0,1,2=401,3=90.000000
L 1.25553307 3.66081683 1.2545 3.66349961 1 P 0 ;0,1,2=401,3=90.000000
L 1.2545 3.66349961 1.2545 3.66618307 1 P 0 ;0,1,2=401,3=90.000000
L 1.2545 3.66618307 1.25553307 3.66886654 1 P 0 ;0,1,2=401,3=90.000000
L 1.25553307 3.66886654 1.25708278 3.67116673 1 P 0 ;0,1,2=401,3=90.000000
L 1.25708278 3.67116673 1.25914892 3.67308366 1 P 0 ;0,1,2=401,3=90.000000
L 1.2545 3.69449961 1.2855 3.69449961 1 P 0 ;0,1,2=401,3=90.000000
L 1.2855 3.69449961 1.2793003 3.6898999 1 P 0 ;0,1,2=401,3=90.000000
L 1.2545 3.6898999 1.2545 3.69909931 1 P 0 ;0,1,2=401,3=90.000000
L 1.2855 3.72549961 1.28446683 3.72243287 1 P 0 ;0,1,2=401,3=90.000000
L 1.28446683 3.72243287 1.28188307 3.72013337 1 P 0 ;0,1,2=401,3=90.000000
L 1.28188307 3.72013337 1.27878376 3.7185997 1 P 0 ;0,1,2=401,3=90.000000
L 1.27878376 3.7185997 1.27464941 3.7174499 1 P 0 ;0,1,2=401,3=90.000000
L 1.27464941 3.7174499 1.26999951 3.71706663 1 P 0 ;0,1,2=401,3=90.000000
L 1.26999951 3.71706663 1.26534951 3.7174499 1 P 0 ;0,1,2=401,3=90.000000
L 1.26534951 3.7174499 1.26121614 3.7185997 1 P 0 ;0,1,2=401,3=90.000000
L 1.26121614 3.7185997 1.25811585 3.72013337 1 P 0 ;0,1,2=401,3=90.000000
L 1.25811585 3.72013337 1.25553307 3.72243287 1 P 0 ;0,1,2=401,3=90.000000
L 1.25553307 3.72243287 1.2545 3.72549961 1 P 0 ;0,1,2=401,3=90.000000
L 1.2545 3.72549961 1.25553307 3.72856634 1 P 0 ;0,1,2=401,3=90.000000
L 1.25553307 3.72856634 1.25811585 3.73086654 1 P 0 ;0,1,2=401,3=90.000000
L 1.25811585 3.73086654 1.26121614 3.7324002 1 P 0 ;0,1,2=401,3=90.000000
L 1.26121614 3.7324002 1.26534951 3.73355 1 P 0 ;0,1,2=401,3=90.000000
L 1.26534951 3.73355 1.26999951 3.73393327 1 P 0 ;0,1,2=401,3=90.000000
L 1.26999951 3.73393327 1.27464941 3.73355 1 P 0 ;0,1,2=401,3=90.000000
L 1.27464941 3.73355 1.27878376 3.7324002 1 P 0 ;0,1,2=401,3=90.000000
L 1.27878376 3.7324002 1.28188307 3.73086654 1 P 0 ;0,1,2=401,3=90.000000
L 1.28188307 3.73086654 1.28446683 3.72856634 1 P 0 ;0,1,2=401,3=90.000000
L 1.28446683 3.72856634 1.2855 3.72549961 1 P 0 ;0,1,2=401,3=90.000000
L 1.2545 3.75649961 1.2855 3.75649961 1 P 0 ;0,1,2=401,3=90.000000
L 1.2855 3.75649961 1.2793003 3.7518999 1 P 0 ;0,1,2=401,3=90.000000
L 1.2545 3.7518999 1.2545 3.76109931 1 P 0 ;0,1,2=401,3=90.000000
L 4.192 3.495 4.192 3.405 1 P 0 
L 4.148 3.405 4.148 3.495 1 P 0 
L 4.148 3.495 4.192 3.495 1 P 0 
L 4.192 3.405 4.148 3.405 1 P 0 
L 4.23291624 3.40693327 4.23446683 3.40463307 1 P 0 ;0,1,2=402,3=90.000000
L 4.23446683 3.40463307 4.2355 3.4019503 1 P 0 ;0,1,2=402,3=90.000000
L 4.2355 3.4019503 4.2355 3.39888356 1 P 0 ;0,1,2=402,3=90.000000
L 4.2355 3.39888356 4.23394931 3.39543287 1 P 0 ;0,1,2=402,3=90.000000
L 4.23394931 3.39543287 4.23136654 3.3927501 1 P 0 ;0,1,2=402,3=90.000000
L 4.23136654 3.3927501 4.22826624 3.39083317 1 P 0 ;0,1,2=402,3=90.000000
L 4.22826624 3.39083317 4.2230998 3.38929951 1 P 0 ;0,1,2=402,3=90.000000
L 4.2230998 3.38929951 4.2184498 3.38891624 1 P 0 ;0,1,2=402,3=90.000000
L 4.2184498 3.38891624 4.2137999 3.38968337 1 P 0 ;0,1,2=402,3=90.000000
L 4.2137999 3.38968337 4.21069961 3.39083317 1 P 0 ;0,1,2=402,3=90.000000
L 4.21069961 3.39083317 4.20759931 3.39313337 1 P 0 ;0,1,2=402,3=90.000000
L 4.20759931 3.39313337 4.20553307 3.39581683 1 P 0 ;0,1,2=402,3=90.000000
L 4.20553307 3.39581683 4.2045 3.39849961 1 P 0 ;0,1,2=402,3=90.000000
L 4.2045 3.39849961 4.2045 3.40118307 1 P 0 ;0,1,2=402,3=90.000000
L 4.2045 3.40118307 4.20553307 3.40386654 1 P 0 ;0,1,2=402,3=90.000000
L 4.20553307 3.40386654 4.20708278 3.40616673 1 P 0 ;0,1,2=402,3=90.000000
L 4.20708278 3.40616673 4.20914892 3.40808366 1 P 0 ;0,1,2=402,3=90.000000
L 4.2045 3.42949961 4.2355 3.42949961 1 P 0 ;0,1,2=402,3=90.000000
L 4.2355 3.42949961 4.2293003 3.4248999 1 P 0 ;0,1,2=402,3=90.000000
L 4.2045 3.4248999 4.2045 3.43409931 1 P 0 ;0,1,2=402,3=90.000000
L 4.2355 3.46049961 4.23446683 3.45743287 1 P 0 ;0,1,2=402,3=90.000000
L 4.23446683 3.45743287 4.23188307 3.45513337 1 P 0 ;0,1,2=402,3=90.000000
L 4.23188307 3.45513337 4.22878376 3.4535997 1 P 0 ;0,1,2=402,3=90.000000
L 4.22878376 3.4535997 4.22464941 3.4524499 1 P 0 ;0,1,2=402,3=90.000000
L 4.22464941 3.4524499 4.21999951 3.45206663 1 P 0 ;0,1,2=402,3=90.000000
L 4.21999951 3.45206663 4.21534951 3.4524499 1 P 0 ;0,1,2=402,3=90.000000
L 4.21534951 3.4524499 4.21121614 3.4535997 1 P 0 ;0,1,2=402,3=90.000000
L 4.21121614 3.4535997 4.20811585 3.45513337 1 P 0 ;0,1,2=402,3=90.000000
L 4.20811585 3.45513337 4.20553307 3.45743287 1 P 0 ;0,1,2=402,3=90.000000
L 4.20553307 3.45743287 4.2045 3.46049961 1 P 0 ;0,1,2=402,3=90.000000
L 4.2045 3.46049961 4.20553307 3.46356634 1 P 0 ;0,1,2=402,3=90.000000
L 4.20553307 3.46356634 4.20811585 3.46586654 1 P 0 ;0,1,2=402,3=90.000000
L 4.20811585 3.46586654 4.21121614 3.4674002 1 P 0 ;0,1,2=402,3=90.000000
L 4.21121614 3.4674002 4.21534951 3.46855 1 P 0 ;0,1,2=402,3=90.000000
L 4.21534951 3.46855 4.21999951 3.46893327 1 P 0 ;0,1,2=402,3=90.000000
L 4.21999951 3.46893327 4.22464941 3.46855 1 P 0 ;0,1,2=402,3=90.000000
L 4.22464941 3.46855 4.22878376 3.4674002 1 P 0 ;0,1,2=402,3=90.000000
L 4.22878376 3.4674002 4.23188307 3.46586654 1 P 0 ;0,1,2=402,3=90.000000
L 4.23188307 3.46586654 4.23446683 3.46356634 1 P 0 ;0,1,2=402,3=90.000000
L 4.23446683 3.46356634 4.2355 3.46049961 1 P 0 ;0,1,2=402,3=90.000000
L 4.23033346 3.48421644 4.23343278 3.48651663 1 P 0 ;0,1,2=402,3=90.000000
L 4.23343278 3.48651663 4.23498337 3.4892001 1 P 0 ;0,1,2=402,3=90.000000
L 4.23498337 3.4892001 4.2355 3.49226683 1 P 0 ;0,1,2=402,3=90.000000
L 4.2355 3.49226683 4.23446683 3.4961 1 P 0 ;0,1,2=402,3=90.000000
L 4.23446683 3.4961 4.23188307 3.49878346 1 P 0 ;0,1,2=402,3=90.000000
L 4.23188307 3.49878346 4.22878376 3.49955 1 P 0 ;0,1,2=402,3=90.000000
L 4.22878376 3.49955 4.22568258 3.49916673 1 P 0 ;0,1,2=402,3=90.000000
L 4.22568258 3.49916673 4.2230998 3.49763307 1 P 0 ;0,1,2=402,3=90.000000
L 4.2230998 3.49763307 4.21793327 3.48996663 1 P 0 ;0,1,2=402,3=90.000000
L 4.21793327 3.48996663 4.21431644 3.48651663 1 P 0 ;0,1,2=402,3=90.000000
L 4.21431644 3.48651663 4.20914892 3.48421644 1 P 0 ;0,1,2=402,3=90.000000
L 4.20914892 3.48421644 4.2045 3.4834499 1 P 0 ;0,1,2=402,3=90.000000
L 4.2045 3.4834499 4.2045 3.49955 1 P 0 ;0,1,2=402,3=90.000000
L 0.175 3.097 0.265 3.097 1 P 0 
L 0.265 3.097 0.265 3.053 1 P 0 
L 0.265 3.053 0.175 3.053 1 P 0 
L 0.175 3.053 0.175 3.097 1 P 0 
L 0.12256673 3.09291624 0.12486693 3.09446683 1 P 0 ;0,1,2=403,3=0.000000
L 0.12486693 3.09446683 0.1275497 3.0955 1 P 0 ;0,1,2=403,3=0.000000
L 0.1275497 3.0955 0.13061644 3.0955 1 P 0 ;0,1,2=403,3=0.000000
L 0.13061644 3.0955 0.13406713 3.09394931 1 P 0 ;0,1,2=403,3=0.000000
L 0.13406713 3.09394931 0.1367499 3.09136654 1 P 0 ;0,1,2=403,3=0.000000
L 0.1367499 3.09136654 0.13866683 3.08826624 1 P 0 ;0,1,2=403,3=0.000000
L 0.13866683 3.08826624 0.14020049 3.0830998 1 P 0 ;0,1,2=403,3=0.000000
L 0.14020049 3.0830998 0.14058376 3.0784498 1 P 0 ;0,1,2=403,3=0.000000
L 0.14058376 3.0784498 0.13981663 3.0737999 1 P 0 ;0,1,2=403,3=0.000000
L 0.13981663 3.0737999 0.13866683 3.07069961 1 P 0 ;0,1,2=403,3=0.000000
L 0.13866683 3.07069961 0.13636663 3.06759931 1 P 0 ;0,1,2=403,3=0.000000
L 0.13636663 3.06759931 0.13368317 3.06553307 1 P 0 ;0,1,2=403,3=0.000000
L 0.13368317 3.06553307 0.13100039 3.0645 1 P 0 ;0,1,2=403,3=0.000000
L 0.13100039 3.0645 0.12831693 3.0645 1 P 0 ;0,1,2=403,3=0.000000
L 0.12831693 3.0645 0.12563346 3.06553307 1 P 0 ;0,1,2=403,3=0.000000
L 0.12563346 3.06553307 0.12333327 3.06708278 1 P 0 ;0,1,2=403,3=0.000000
L 0.12333327 3.06708278 0.12141634 3.06914892 1 P 0 ;0,1,2=403,3=0.000000
L 0.10843337 3.07069961 0.10613386 3.06708278 1 P 0 ;0,1,2=403,3=0.000000
L 0.10613386 3.06708278 0.10306713 3.06501654 1 P 0 ;0,1,2=403,3=0.000000
L 0.10306713 3.06501654 0.09961644 3.0645 1 P 0 ;0,1,2=403,3=0.000000
L 0.09961644 3.0645 0.0965497 3.06501654 1 P 0 ;0,1,2=403,3=0.000000
L 0.0965497 3.06501654 0.09348297 3.06759931 1 P 0 ;0,1,2=403,3=0.000000
L 0.09348297 3.06759931 0.09156673 3.07069961 1 P 0 ;0,1,2=403,3=0.000000
L 0.09156673 3.07069961 0.09118346 3.0737999 1 P 0 ;0,1,2=403,3=0.000000
L 0.09118346 3.0737999 0.09195 3.07741575 1 P 0 ;0,1,2=403,3=0.000000
L 0.09195 3.07741575 0.09463346 3.07999951 1 P 0 ;0,1,2=403,3=0.000000
L 0.09463346 3.07999951 0.09731693 3.08103356 1 P 0 ;0,1,2=403,3=0.000000
L 0.09731693 3.08103356 0.10076693 3.08103356 1 P 0 ;0,1,2=403,3=0.000000
L 0.09731693 3.08103356 0.09501673 3.08258317 1 P 0 ;0,1,2=403,3=0.000000
L 0.09501673 3.08258317 0.0930998 3.08516594 1 P 0 ;0,1,2=403,3=0.000000
L 0.0930998 3.08516594 0.09233327 3.08826624 1 P 0 ;0,1,2=403,3=0.000000
L 0.09233327 3.08826624 0.0930998 3.09136654 1 P 0 ;0,1,2=403,3=0.000000
L 0.0930998 3.09136654 0.09501673 3.09394931 1 P 0 ;0,1,2=403,3=0.000000
L 0.09501673 3.09394931 0.09846673 3.0955 1 P 0 ;0,1,2=403,3=0.000000
L 0.09846673 3.0955 0.10191663 3.09498337 1 P 0 ;0,1,2=403,3=0.000000
L 0.10191663 3.09498337 0.10536663 3.09291624 1 P 0 ;0,1,2=403,3=0.000000
L 0.07551713 3.06811585 0.07283366 3.06553307 1 P 0 ;0,1,2=403,3=0.000000
L 0.07283366 3.06553307 0.06976693 3.0645 1 P 0 ;0,1,2=403,3=0.000000
L 0.06976693 3.0645 0.0667002 3.06553307 1 P 0 ;0,1,2=403,3=0.000000
L 0.0667002 3.06553307 0.06401673 3.06863238 1 P 0 ;0,1,2=403,3=0.000000
L 0.06401673 3.06863238 0.0620998 3.07328327 1 P 0 ;0,1,2=403,3=0.000000
L 0.0620998 3.07328327 0.06133327 3.07793327 1 P 0 ;0,1,2=403,3=0.000000
L 0.06133327 3.07793327 0.06133327 3.08361634 1 P 0 ;0,1,2=403,3=0.000000
L 0.06133327 3.08361634 0.0620998 3.08826624 1 P 0 ;0,1,2=403,3=0.000000
L 0.0620998 3.08826624 0.06401673 3.0923997 1 P 0 ;0,1,2=403,3=0.000000
L 0.06401673 3.0923997 0.06631693 3.09446683 1 P 0 ;0,1,2=403,3=0.000000
L 0.06631693 3.09446683 0.06900039 3.0955 1 P 0 ;0,1,2=403,3=0.000000
L 0.06900039 3.0955 0.07206713 3.09446683 1 P 0 ;0,1,2=403,3=0.000000
L 0.07206713 3.09446683 0.07436663 3.0923997 1 P 0 ;0,1,2=403,3=0.000000
L 0.07436663 3.0923997 0.0759003 3.0893003 1 P 0 ;0,1,2=403,3=0.000000
L 0.0759003 3.0893003 0.07666683 3.08516594 1 P 0 ;0,1,2=403,3=0.000000
L 0.07666683 3.08516594 0.0759003 3.0815501 1 P 0 ;0,1,2=403,3=0.000000
L 0.0759003 3.0815501 0.07398337 3.07793327 1 P 0 ;0,1,2=403,3=0.000000
L 0.07398337 3.07793327 0.07168317 3.07586604 1 P 0 ;0,1,2=403,3=0.000000
L 0.07168317 3.07586604 0.06900039 3.07534951 1 P 0 ;0,1,2=403,3=0.000000
L 0.06900039 3.07534951 0.06593366 3.07638268 1 P 0 ;0,1,2=403,3=0.000000
L 0.06593366 3.07638268 0.06363346 3.07896634 1 P 0 ;0,1,2=403,3=0.000000
L 0.06363346 3.07896634 0.06133327 3.08361634 1 P 0 ;0,1,2=403,3=0.000000
L 0.701 0.637 0.701 0.593 1 P 0 
L 0.611 0.637 0.701 0.637 1 P 0 
L 0.701 0.593 0.611 0.593 1 P 0 
L 0.611 0.593 0.611 0.637 1 P 0 
L 0.68756673 0.58291624 0.68986693 0.58446683 1 P 0 ;0,1,2=404,3=0.000000
L 0.68986693 0.58446683 0.6925497 0.5855 1 P 0 ;0,1,2=404,3=0.000000
L 0.6925497 0.5855 0.69561644 0.5855 1 P 0 ;0,1,2=404,3=0.000000
L 0.69561644 0.5855 0.69906713 0.58394931 1 P 0 ;0,1,2=404,3=0.000000
L 0.69906713 0.58394931 0.7017499 0.58136654 1 P 0 ;0,1,2=404,3=0.000000
L 0.7017499 0.58136654 0.70366683 0.57826624 1 P 0 ;0,1,2=404,3=0.000000
L 0.70366683 0.57826624 0.70520049 0.5730998 1 P 0 ;0,1,2=404,3=0.000000
L 0.70520049 0.5730998 0.70558376 0.5684498 1 P 0 ;0,1,2=404,3=0.000000
L 0.70558376 0.5684498 0.70481663 0.5637999 1 P 0 ;0,1,2=404,3=0.000000
L 0.70481663 0.5637999 0.70366683 0.56069961 1 P 0 ;0,1,2=404,3=0.000000
L 0.70366683 0.56069961 0.70136663 0.55759931 1 P 0 ;0,1,2=404,3=0.000000
L 0.70136663 0.55759931 0.69868317 0.55553307 1 P 0 ;0,1,2=404,3=0.000000
L 0.69868317 0.55553307 0.69600039 0.5545 1 P 0 ;0,1,2=404,3=0.000000
L 0.69600039 0.5545 0.69331693 0.5545 1 P 0 ;0,1,2=404,3=0.000000
L 0.69331693 0.5545 0.69063346 0.55553307 1 P 0 ;0,1,2=404,3=0.000000
L 0.69063346 0.55553307 0.68833327 0.55708278 1 P 0 ;0,1,2=404,3=0.000000
L 0.68833327 0.55708278 0.68641634 0.55914892 1 P 0 ;0,1,2=404,3=0.000000
L 0.66500039 0.5545 0.66231693 0.55501654 1 P 0 ;0,1,2=404,3=0.000000
L 0.66231693 0.55501654 0.6592502 0.55656614 1 P 0 ;0,1,2=404,3=0.000000
L 0.6592502 0.55656614 0.65733327 0.55914892 1 P 0 ;0,1,2=404,3=0.000000
L 0.65733327 0.55914892 0.65656673 0.56276673 1 P 0 ;0,1,2=404,3=0.000000
L 0.65656673 0.56276673 0.65733327 0.56638268 1 P 0 ;0,1,2=404,3=0.000000
L 0.65733327 0.56638268 0.65963346 0.56948287 1 P 0 ;0,1,2=404,3=0.000000
L 0.65963346 0.56948287 0.66308346 0.57103356 1 P 0 ;0,1,2=404,3=0.000000
L 0.66308346 0.57103356 0.66691663 0.57103356 1 P 0 ;0,1,2=404,3=0.000000
L 0.66691663 0.57103356 0.66921683 0.57206663 1 P 0 ;0,1,2=404,3=0.000000
L 0.66921683 0.57206663 0.67113386 0.57464941 1 P 0 ;0,1,2=404,3=0.000000
L 0.67113386 0.57464941 0.6719003 0.57826624 1 P 0 ;0,1,2=404,3=0.000000
L 0.6719003 0.57826624 0.6707499 0.58188307 1 P 0 ;0,1,2=404,3=0.000000
L 0.6707499 0.58188307 0.66806713 0.58446683 1 P 0 ;0,1,2=404,3=0.000000
L 0.66806713 0.58446683 0.66500039 0.5855 1 P 0 ;0,1,2=404,3=0.000000
L 0.66500039 0.5855 0.66193366 0.58446683 1 P 0 ;0,1,2=404,3=0.000000
L 0.66193366 0.58446683 0.6592502 0.58188307 1 P 0 ;0,1,2=404,3=0.000000
L 0.6592502 0.58188307 0.6580998 0.57826624 1 P 0 ;0,1,2=404,3=0.000000
L 0.6580998 0.57826624 0.65886693 0.57464941 1 P 0 ;0,1,2=404,3=0.000000
L 0.65886693 0.57464941 0.66078327 0.57206663 1 P 0 ;0,1,2=404,3=0.000000
L 0.66078327 0.57206663 0.66308346 0.57103356 1 P 0 ;0,1,2=404,3=0.000000
L 0.66308346 0.57103356 0.66691663 0.57103356 1 P 0 ;0,1,2=404,3=0.000000
L 0.66691663 0.57103356 0.67036663 0.56948287 1 P 0 ;0,1,2=404,3=0.000000
L 0.67036663 0.56948287 0.67266683 0.56638268 1 P 0 ;0,1,2=404,3=0.000000
L 0.67266683 0.56638268 0.67343337 0.56276673 1 P 0 ;0,1,2=404,3=0.000000
L 0.67343337 0.56276673 0.67266683 0.55914892 1 P 0 ;0,1,2=404,3=0.000000
L 0.67266683 0.55914892 0.6707499 0.55656614 1 P 0 ;0,1,2=404,3=0.000000
L 0.6707499 0.55656614 0.66768317 0.55501654 1 P 0 ;0,1,2=404,3=0.000000
L 0.66768317 0.55501654 0.66500039 0.5545 1 P 0 ;0,1,2=404,3=0.000000
L 0.64128356 0.58033346 0.63898337 0.58343278 1 P 0 ;0,1,2=404,3=0.000000
L 0.63898337 0.58343278 0.6362999 0.58498337 1 P 0 ;0,1,2=404,3=0.000000
L 0.6362999 0.58498337 0.63323317 0.5855 1 P 0 ;0,1,2=404,3=0.000000
L 0.63323317 0.5855 0.6294 0.58446683 1 P 0 ;0,1,2=404,3=0.000000
L 0.6294 0.58446683 0.62671654 0.58188307 1 P 0 ;0,1,2=404,3=0.000000
L 0.62671654 0.58188307 0.62595 0.57878376 1 P 0 ;0,1,2=404,3=0.000000
L 0.62595 0.57878376 0.62633327 0.57568258 1 P 0 ;0,1,2=404,3=0.000000
L 0.62633327 0.57568258 0.62786693 0.5730998 1 P 0 ;0,1,2=404,3=0.000000
L 0.62786693 0.5730998 0.63553337 0.56793327 1 P 0 ;0,1,2=404,3=0.000000
L 0.63553337 0.56793327 0.63898337 0.56431644 1 P 0 ;0,1,2=404,3=0.000000
L 0.63898337 0.56431644 0.64128356 0.55914892 1 P 0 ;0,1,2=404,3=0.000000
L 0.64128356 0.55914892 0.6420501 0.5545 1 P 0 ;0,1,2=404,3=0.000000
L 0.6420501 0.5545 0.62595 0.5545 1 P 0 ;0,1,2=404,3=0.000000
L 0.882 0.857 0.882 0.767 1 P 0 
L 0.838 0.767 0.838 0.857 1 P 0 
L 0.838 0.857 0.882 0.857 1 P 0 
L 0.882 0.767 0.838 0.767 1 P 0 
L 0.91791624 0.76793327 0.91946683 0.76563307 1 P 0 ;0,1,2=405,3=90.000000
L 0.91946683 0.76563307 0.9205 0.7629503 1 P 0 ;0,1,2=405,3=90.000000
L 0.9205 0.7629503 0.9205 0.75988356 1 P 0 ;0,1,2=405,3=90.000000
L 0.9205 0.75988356 0.91894931 0.75643287 1 P 0 ;0,1,2=405,3=90.000000
L 0.91894931 0.75643287 0.91636654 0.7537501 1 P 0 ;0,1,2=405,3=90.000000
L 0.91636654 0.7537501 0.91326624 0.75183317 1 P 0 ;0,1,2=405,3=90.000000
L 0.91326624 0.75183317 0.9080998 0.75029951 1 P 0 ;0,1,2=405,3=90.000000
L 0.9080998 0.75029951 0.9034498 0.74991624 1 P 0 ;0,1,2=405,3=90.000000
L 0.9034498 0.74991624 0.8987999 0.75068337 1 P 0 ;0,1,2=405,3=90.000000
L 0.8987999 0.75068337 0.89569961 0.75183317 1 P 0 ;0,1,2=405,3=90.000000
L 0.89569961 0.75183317 0.89259931 0.75413337 1 P 0 ;0,1,2=405,3=90.000000
L 0.89259931 0.75413337 0.89053307 0.75681683 1 P 0 ;0,1,2=405,3=90.000000
L 0.89053307 0.75681683 0.8895 0.75949961 1 P 0 ;0,1,2=405,3=90.000000
L 0.8895 0.75949961 0.8895 0.76218307 1 P 0 ;0,1,2=405,3=90.000000
L 0.8895 0.76218307 0.89053307 0.76486654 1 P 0 ;0,1,2=405,3=90.000000
L 0.89053307 0.76486654 0.89208278 0.76716673 1 P 0 ;0,1,2=405,3=90.000000
L 0.89208278 0.76716673 0.89414892 0.76908366 1 P 0 ;0,1,2=405,3=90.000000
L 0.8895 0.79049961 0.9205 0.79049961 1 P 0 ;0,1,2=405,3=90.000000
L 0.9205 0.79049961 0.9143003 0.7858999 1 P 0 ;0,1,2=405,3=90.000000
L 0.8895 0.7858999 0.8895 0.79509931 1 P 0 ;0,1,2=405,3=90.000000
L 1.778 4.09 1.822 4.09 1 P 0 
L 1.778 4 1.778 4.09 1 P 0 
L 1.822 4.09 1.822 4 1 P 0 
L 1.822 4 1.778 4 1 P 0 
L 1.86891624 4.01643327 1.87046683 4.01413307 1 P 0 ;0,1,2=406,3=90.000000
L 1.87046683 4.01413307 1.8715 4.0114503 1 P 0 ;0,1,2=406,3=90.000000
L 1.8715 4.0114503 1.8715 4.00838356 1 P 0 ;0,1,2=406,3=90.000000
L 1.8715 4.00838356 1.86994931 4.00493287 1 P 0 ;0,1,2=406,3=90.000000
L 1.86994931 4.00493287 1.86736654 4.0022501 1 P 0 ;0,1,2=406,3=90.000000
L 1.86736654 4.0022501 1.86426624 4.00033317 1 P 0 ;0,1,2=406,3=90.000000
L 1.86426624 4.00033317 1.8590998 3.99879951 1 P 0 ;0,1,2=406,3=90.000000
L 1.8590998 3.99879951 1.8544498 3.99841624 1 P 0 ;0,1,2=406,3=90.000000
L 1.8544498 3.99841624 1.8497999 3.99918337 1 P 0 ;0,1,2=406,3=90.000000
L 1.8497999 3.99918337 1.84669961 4.00033317 1 P 0 ;0,1,2=406,3=90.000000
L 1.84669961 4.00033317 1.84359931 4.00263337 1 P 0 ;0,1,2=406,3=90.000000
L 1.84359931 4.00263337 1.84153307 4.00531683 1 P 0 ;0,1,2=406,3=90.000000
L 1.84153307 4.00531683 1.8405 4.00799961 1 P 0 ;0,1,2=406,3=90.000000
L 1.8405 4.00799961 1.8405 4.01068307 1 P 0 ;0,1,2=406,3=90.000000
L 1.8405 4.01068307 1.84153307 4.01336654 1 P 0 ;0,1,2=406,3=90.000000
L 1.84153307 4.01336654 1.84308278 4.01566673 1 P 0 ;0,1,2=406,3=90.000000
L 1.84308278 4.01566673 1.84514892 4.01758366 1 P 0 ;0,1,2=406,3=90.000000
L 1.8405 4.0436 1.8715 4.0436 1 P 0 ;0,1,2=406,3=90.000000
L 1.8715 4.0436 1.84928327 4.02941624 1 P 0 ;0,1,2=406,3=90.000000
L 1.84928327 4.02941624 1.84928327 4.04858366 1 P 0 ;0,1,2=406,3=90.000000
L 1.84514892 4.06156663 1.84256614 4.06386614 1 P 0 ;0,1,2=406,3=90.000000
L 1.84256614 4.06386614 1.84101654 4.06654961 1 P 0 ;0,1,2=406,3=90.000000
L 1.84101654 4.06654961 1.8405 4.06999961 1 P 0 ;0,1,2=406,3=90.000000
L 1.8405 4.06999961 1.84153307 4.0734503 1 P 0 ;0,1,2=406,3=90.000000
L 1.84153307 4.0734503 1.84359931 4.07613307 1 P 0 ;0,1,2=406,3=90.000000
L 1.84359931 4.07613307 1.84721614 4.07805 1 P 0 ;0,1,2=406,3=90.000000
L 1.84721614 4.07805 1.85134951 4.07843327 1 P 0 ;0,1,2=406,3=90.000000
L 1.85134951 4.07843327 1.85548287 4.07766673 1 P 0 ;0,1,2=406,3=90.000000
L 1.85548287 4.07766673 1.85806663 4.0757498 1 P 0 ;0,1,2=406,3=90.000000
L 1.85806663 4.0757498 1.86013287 4.07306634 1 P 0 ;0,1,2=406,3=90.000000
L 1.86013287 4.07306634 1.86064941 4.07038356 1 P 0 ;0,1,2=406,3=90.000000
L 1.86064941 4.07038356 1.86013287 4.0677001 1 P 0 ;0,1,2=406,3=90.000000
L 1.86013287 4.0677001 1.85806663 4.0642501 1 P 0 ;0,1,2=406,3=90.000000
L 1.85806663 4.0642501 1.8715 4.0653999 1 P 0 ;0,1,2=406,3=90.000000
L 1.8715 4.0653999 1.8715 4.0757498 1 P 0 ;0,1,2=406,3=90.000000
L 1.79 3.932 1.79 3.888 1 P 0 
L 1.7 3.932 1.79 3.932 1 P 0 
L 1.79 3.888 1.7 3.888 1 P 0 
L 1.7 3.888 1.7 3.932 1 P 0 
L 1.86356673 3.92291624 1.86586693 3.92446683 1 P 0 ;0,1,2=407,3=0.000000
L 1.86586693 3.92446683 1.8685497 3.9255 1 P 0 ;0,1,2=407,3=0.000000
L 1.8685497 3.9255 1.87161644 3.9255 1 P 0 ;0,1,2=407,3=0.000000
L 1.87161644 3.9255 1.87506713 3.92394931 1 P 0 ;0,1,2=407,3=0.000000
L 1.87506713 3.92394931 1.8777499 3.92136654 1 P 0 ;0,1,2=407,3=0.000000
L 1.8777499 3.92136654 1.87966683 3.91826624 1 P 0 ;0,1,2=407,3=0.000000
L 1.87966683 3.91826624 1.88120049 3.9130998 1 P 0 ;0,1,2=407,3=0.000000
L 1.88120049 3.9130998 1.88158376 3.9084498 1 P 0 ;0,1,2=407,3=0.000000
L 1.88158376 3.9084498 1.88081663 3.9037999 1 P 0 ;0,1,2=407,3=0.000000
L 1.88081663 3.9037999 1.87966683 3.90069961 1 P 0 ;0,1,2=407,3=0.000000
L 1.87966683 3.90069961 1.87736663 3.89759931 1 P 0 ;0,1,2=407,3=0.000000
L 1.87736663 3.89759931 1.87468317 3.89553307 1 P 0 ;0,1,2=407,3=0.000000
L 1.87468317 3.89553307 1.87200039 3.8945 1 P 0 ;0,1,2=407,3=0.000000
L 1.87200039 3.8945 1.86931693 3.8945 1 P 0 ;0,1,2=407,3=0.000000
L 1.86931693 3.8945 1.86663346 3.89553307 1 P 0 ;0,1,2=407,3=0.000000
L 1.86663346 3.89553307 1.86433327 3.89708278 1 P 0 ;0,1,2=407,3=0.000000
L 1.86433327 3.89708278 1.86241634 3.89914892 1 P 0 ;0,1,2=407,3=0.000000
L 1.8364 3.8945 1.8364 3.9255 1 P 0 ;0,1,2=407,3=0.000000
L 1.8364 3.9255 1.85058376 3.90328327 1 P 0 ;0,1,2=407,3=0.000000
L 1.85058376 3.90328327 1.83141634 3.90328327 1 P 0 ;0,1,2=407,3=0.000000
L 1.8054 3.8945 1.8054 3.9255 1 P 0 ;0,1,2=407,3=0.000000
L 1.8054 3.9255 1.81958376 3.90328327 1 P 0 ;0,1,2=407,3=0.000000
L 1.81958376 3.90328327 1.80041634 3.90328327 1 P 0 ;0,1,2=407,3=0.000000
L 1.411 4.058 1.501 4.058 1 P 0 
L 1.501 4.058 1.501 4.014 1 P 0 
L 1.501 4.014 1.411 4.014 1 P 0 
L 1.411 4.014 1.411 4.058 1 P 0 
L 1.31956673 4.02491624 1.32186693 4.02646683 1 P 0 ;0,1,2=408,3=0.000000
L 1.32186693 4.02646683 1.3245497 4.0275 1 P 0 ;0,1,2=408,3=0.000000
L 1.3245497 4.0275 1.32761644 4.0275 1 P 0 ;0,1,2=408,3=0.000000
L 1.32761644 4.0275 1.33106713 4.02594931 1 P 0 ;0,1,2=408,3=0.000000
L 1.33106713 4.02594931 1.3337499 4.02336654 1 P 0 ;0,1,2=408,3=0.000000
L 1.3337499 4.02336654 1.33566683 4.02026624 1 P 0 ;0,1,2=408,3=0.000000
L 1.33566683 4.02026624 1.33720049 4.0150998 1 P 0 ;0,1,2=408,3=0.000000
L 1.33720049 4.0150998 1.33758376 4.0104498 1 P 0 ;0,1,2=408,3=0.000000
L 1.33758376 4.0104498 1.33681663 4.0057999 1 P 0 ;0,1,2=408,3=0.000000
L 1.33681663 4.0057999 1.33566683 4.00269961 1 P 0 ;0,1,2=408,3=0.000000
L 1.33566683 4.00269961 1.33336663 3.99959931 1 P 0 ;0,1,2=408,3=0.000000
L 1.33336663 3.99959931 1.33068317 3.99753307 1 P 0 ;0,1,2=408,3=0.000000
L 1.33068317 3.99753307 1.32800039 3.9965 1 P 0 ;0,1,2=408,3=0.000000
L 1.32800039 3.9965 1.32531693 3.9965 1 P 0 ;0,1,2=408,3=0.000000
L 1.32531693 3.9965 1.32263346 3.99753307 1 P 0 ;0,1,2=408,3=0.000000
L 1.32263346 3.99753307 1.32033327 3.99908278 1 P 0 ;0,1,2=408,3=0.000000
L 1.32033327 3.99908278 1.31841634 4.00114892 1 P 0 ;0,1,2=408,3=0.000000
L 1.2924 3.9965 1.2924 4.0275 1 P 0 ;0,1,2=408,3=0.000000
L 1.2924 4.0275 1.30658376 4.00528327 1 P 0 ;0,1,2=408,3=0.000000
L 1.30658376 4.00528327 1.28741634 4.00528327 1 P 0 ;0,1,2=408,3=0.000000
L 1.27328356 4.02233346 1.27098337 4.02543278 1 P 0 ;0,1,2=408,3=0.000000
L 1.27098337 4.02543278 1.2682999 4.02698337 1 P 0 ;0,1,2=408,3=0.000000
L 1.2682999 4.02698337 1.26523317 4.0275 1 P 0 ;0,1,2=408,3=0.000000
L 1.26523317 4.0275 1.2614 4.02646683 1 P 0 ;0,1,2=408,3=0.000000
L 1.2614 4.02646683 1.25871654 4.02388307 1 P 0 ;0,1,2=408,3=0.000000
L 1.25871654 4.02388307 1.25795 4.02078376 1 P 0 ;0,1,2=408,3=0.000000
L 1.25795 4.02078376 1.25833327 4.01768258 1 P 0 ;0,1,2=408,3=0.000000
L 1.25833327 4.01768258 1.25986693 4.0150998 1 P 0 ;0,1,2=408,3=0.000000
L 1.25986693 4.0150998 1.26753337 4.00993327 1 P 0 ;0,1,2=408,3=0.000000
L 1.26753337 4.00993327 1.27098337 4.00631644 1 P 0 ;0,1,2=408,3=0.000000
L 1.27098337 4.00631644 1.27328356 4.00114892 1 P 0 ;0,1,2=408,3=0.000000
L 1.27328356 4.00114892 1.2740501 3.9965 1 P 0 ;0,1,2=408,3=0.000000
L 1.2740501 3.9965 1.25795 3.9965 1 P 0 ;0,1,2=408,3=0.000000
L 4.758 1.88711004 4.802 1.88711004 1 P 0 
L 4.802 1.88711004 4.802 1.79711004 1 P 0 
L 4.802 1.79711004 4.758 1.79711004 1 P 0 
L 4.758 1.79711004 4.758 1.88711004 1 P 0 
L 4.85041634 1.76786663 4.85166683 1.76626644 1 P 0 ;0,1,2=409,3=90.000000
L 4.85166683 1.76626644 4.8525 1.7644002 1 P 0 ;0,1,2=409,3=90.000000
L 4.8525 1.7644002 4.8525 1.76226683 1 P 0 ;0,1,2=409,3=90.000000
L 4.8525 1.76226683 4.85124941 1.75986634 1 P 0 ;0,1,2=409,3=90.000000
L 4.85124941 1.75986634 4.84916654 1.7580001 1 P 0 ;0,1,2=409,3=90.000000
L 4.84916654 1.7580001 4.84666634 1.75666654 1 P 0 ;0,1,2=409,3=90.000000
L 4.84666634 1.75666654 4.8424998 1.75559961 1 P 0 ;0,1,2=409,3=90.000000
L 4.8424998 1.75559961 4.8387498 1.75533297 1 P 0 ;0,1,2=409,3=90.000000
L 4.8387498 1.75533297 4.8349999 1.75586673 1 P 0 ;0,1,2=409,3=90.000000
L 4.8349999 1.75586673 4.83249961 1.75666654 1 P 0 ;0,1,2=409,3=90.000000
L 4.83249961 1.75666654 4.82999941 1.75826663 1 P 0 ;0,1,2=409,3=90.000000
L 4.82999941 1.75826663 4.82833307 1.76013346 1 P 0 ;0,1,2=409,3=90.000000
L 4.82833307 1.76013346 4.8275 1.7619997 1 P 0 ;0,1,2=409,3=90.000000
L 4.8275 1.7619997 4.8275 1.76386644 1 P 0 ;0,1,2=409,3=90.000000
L 4.8275 1.76386644 4.82833307 1.76573327 1 P 0 ;0,1,2=409,3=90.000000
L 4.82833307 1.76573327 4.82958287 1.76733337 1 P 0 ;0,1,2=409,3=90.000000
L 4.82958287 1.76733337 4.83124911 1.76866693 1 P 0 ;0,1,2=409,3=90.000000
L 4.8275 1.7839997 4.8525 1.7839997 1 P 0 ;0,1,2=409,3=90.000000
L 4.8525 1.7839997 4.8475003 1.7807999 1 P 0 ;0,1,2=409,3=90.000000
L 4.8275 1.7807999 4.8275 1.78719951 1 P 0 ;0,1,2=409,3=90.000000
L 4.8275 1.8092 4.8525 1.8092 1 P 0 ;0,1,2=409,3=90.000000
L 4.8525 1.8092 4.83458327 1.79933297 1 P 0 ;0,1,2=409,3=90.000000
L 4.83458327 1.79933297 4.83458327 1.81266693 1 P 0 ;0,1,2=409,3=90.000000
L 4.83124911 1.82213327 4.82916624 1.82373297 1 P 0 ;0,1,2=409,3=90.000000
L 4.82916624 1.82373297 4.82791654 1.8255997 1 P 0 ;0,1,2=409,3=90.000000
L 4.82791654 1.8255997 4.8275 1.8279997 1 P 0 ;0,1,2=409,3=90.000000
L 4.8275 1.8279997 4.82833307 1.8304002 1 P 0 ;0,1,2=409,3=90.000000
L 4.82833307 1.8304002 4.82999941 1.83226644 1 P 0 ;0,1,2=409,3=90.000000
L 4.82999941 1.83226644 4.83291624 1.8336 1 P 0 ;0,1,2=409,3=90.000000
L 4.83291624 1.8336 4.83624961 1.83386663 1 P 0 ;0,1,2=409,3=90.000000
L 4.83624961 1.83386663 4.83958297 1.83333337 1 P 0 ;0,1,2=409,3=90.000000
L 4.83958297 1.83333337 4.84166663 1.8319998 1 P 0 ;0,1,2=409,3=90.000000
L 4.84166663 1.8319998 4.84333297 1.83013307 1 P 0 ;0,1,2=409,3=90.000000
L 4.84333297 1.83013307 4.84374951 1.82826683 1 P 0 ;0,1,2=409,3=90.000000
L 4.84374951 1.82826683 4.84333297 1.8264 1 P 0 ;0,1,2=409,3=90.000000
L 4.84333297 1.8264 4.84166663 1.8240001 1 P 0 ;0,1,2=409,3=90.000000
L 4.84166663 1.8240001 4.8525 1.8247999 1 P 0 ;0,1,2=409,3=90.000000
L 4.8525 1.8247999 4.8525 1.8319998 1 P 0 ;0,1,2=409,3=90.000000
L 5.655 2.002 5.655 1.958 1 P 0 
L 5.565 2.002 5.655 2.002 1 P 0 
L 5.655 1.958 5.565 1.958 1 P 0 
L 5.565 1.958 5.565 2.002 1 P 0 
L 5.63806673 1.93291624 5.64036693 1.93446683 1 P 0 ;0,1,2=410,3=0.000000
L 5.64036693 1.93446683 5.6430497 1.9355 1 P 0 ;0,1,2=410,3=0.000000
L 5.6430497 1.9355 5.64611644 1.9355 1 P 0 ;0,1,2=410,3=0.000000
L 5.64611644 1.9355 5.64956713 1.93394931 1 P 0 ;0,1,2=410,3=0.000000
L 5.64956713 1.93394931 5.6522499 1.93136654 1 P 0 ;0,1,2=410,3=0.000000
L 5.6522499 1.93136654 5.65416683 1.92826624 1 P 0 ;0,1,2=410,3=0.000000
L 5.65416683 1.92826624 5.65570049 1.9230998 1 P 0 ;0,1,2=410,3=0.000000
L 5.65570049 1.9230998 5.65608376 1.9184498 1 P 0 ;0,1,2=410,3=0.000000
L 5.65608376 1.9184498 5.65531663 1.9137999 1 P 0 ;0,1,2=410,3=0.000000
L 5.65531663 1.9137999 5.65416683 1.91069961 1 P 0 ;0,1,2=410,3=0.000000
L 5.65416683 1.91069961 5.65186663 1.90759931 1 P 0 ;0,1,2=410,3=0.000000
L 5.65186663 1.90759931 5.64918317 1.90553307 1 P 0 ;0,1,2=410,3=0.000000
L 5.64918317 1.90553307 5.64650039 1.9045 1 P 0 ;0,1,2=410,3=0.000000
L 5.64650039 1.9045 5.64381693 1.9045 1 P 0 ;0,1,2=410,3=0.000000
L 5.64381693 1.9045 5.64113346 1.90553307 1 P 0 ;0,1,2=410,3=0.000000
L 5.64113346 1.90553307 5.63883327 1.90708278 1 P 0 ;0,1,2=410,3=0.000000
L 5.63883327 1.90708278 5.63691634 1.90914892 1 P 0 ;0,1,2=410,3=0.000000
L 5.62278356 1.93033346 5.62048337 1.93343278 1 P 0 ;0,1,2=410,3=0.000000
L 5.62048337 1.93343278 5.6177999 1.93498337 1 P 0 ;0,1,2=410,3=0.000000
L 5.6177999 1.93498337 5.61473317 1.9355 1 P 0 ;0,1,2=410,3=0.000000
L 5.61473317 1.9355 5.6109 1.93446683 1 P 0 ;0,1,2=410,3=0.000000
L 5.6109 1.93446683 5.60821654 1.93188307 1 P 0 ;0,1,2=410,3=0.000000
L 5.60821654 1.93188307 5.60745 1.92878376 1 P 0 ;0,1,2=410,3=0.000000
L 5.60745 1.92878376 5.60783327 1.92568258 1 P 0 ;0,1,2=410,3=0.000000
L 5.60783327 1.92568258 5.60936693 1.9230998 1 P 0 ;0,1,2=410,3=0.000000
L 5.60936693 1.9230998 5.61703337 1.91793327 1 P 0 ;0,1,2=410,3=0.000000
L 5.61703337 1.91793327 5.62048337 1.91431644 1 P 0 ;0,1,2=410,3=0.000000
L 5.62048337 1.91431644 5.62278356 1.90914892 1 P 0 ;0,1,2=410,3=0.000000
L 5.62278356 1.90914892 5.6235501 1.9045 1 P 0 ;0,1,2=410,3=0.000000
L 5.6235501 1.9045 5.60745 1.9045 1 P 0 ;0,1,2=410,3=0.000000
L 5.59178356 1.91741575 5.5891001 1.92103356 1 P 0 ;0,1,2=410,3=0.000000
L 5.5891001 1.92103356 5.5867999 1.9230998 1 P 0 ;0,1,2=410,3=0.000000
L 5.5867999 1.9230998 5.58373317 1.92413287 1 P 0 ;0,1,2=410,3=0.000000
L 5.58373317 1.92413287 5.5810497 1.9230998 1 P 0 ;0,1,2=410,3=0.000000
L 5.5810497 1.9230998 5.57913346 1.92103356 1 P 0 ;0,1,2=410,3=0.000000
L 5.57913346 1.92103356 5.5775998 1.91793327 1 P 0 ;0,1,2=410,3=0.000000
L 5.5775998 1.91793327 5.57721654 1.91431644 1 P 0 ;0,1,2=410,3=0.000000
L 5.57721654 1.91431644 5.5775998 1.91121614 1 P 0 ;0,1,2=410,3=0.000000
L 5.5775998 1.91121614 5.57913346 1.90811585 1 P 0 ;0,1,2=410,3=0.000000
L 5.57913346 1.90811585 5.58143366 1.90553307 1 P 0 ;0,1,2=410,3=0.000000
L 5.58143366 1.90553307 5.58411644 1.9045 1 P 0 ;0,1,2=410,3=0.000000
L 5.58411644 1.9045 5.58718317 1.90553307 1 P 0 ;0,1,2=410,3=0.000000
L 5.58718317 1.90553307 5.58986663 1.90863238 1 P 0 ;0,1,2=410,3=0.000000
L 5.58986663 1.90863238 5.5914003 1.91328327 1 P 0 ;0,1,2=410,3=0.000000
L 5.5914003 1.91328327 5.59178356 1.9184498 1 P 0 ;0,1,2=410,3=0.000000
L 5.59178356 1.9184498 5.59101713 1.92516594 1 P 0 ;0,1,2=410,3=0.000000
L 5.59101713 1.92516594 5.58986663 1.92878376 1 P 0 ;0,1,2=410,3=0.000000
L 5.58986663 1.92878376 5.58795039 1.9323997 1 P 0 ;0,1,2=410,3=0.000000
L 5.58795039 1.9323997 5.58526693 1.93498337 1 P 0 ;0,1,2=410,3=0.000000
L 5.58526693 1.93498337 5.58258346 1.9355 1 P 0 ;0,1,2=410,3=0.000000
L 5.58258346 1.9355 5.5799 1.93446683 1 P 0 ;0,1,2=410,3=0.000000
L 5.5799 1.93446683 5.57798297 1.93188307 1 P 0 ;0,1,2=410,3=0.000000
L 5.56078356 1.91741575 5.5581001 1.92103356 1 P 0 ;0,1,2=410,3=0.000000
L 5.5581001 1.92103356 5.5557999 1.9230998 1 P 0 ;0,1,2=410,3=0.000000
L 5.5557999 1.9230998 5.55273317 1.92413287 1 P 0 ;0,1,2=410,3=0.000000
L 5.55273317 1.92413287 5.5500497 1.9230998 1 P 0 ;0,1,2=410,3=0.000000
L 5.5500497 1.9230998 5.54813346 1.92103356 1 P 0 ;0,1,2=410,3=0.000000
L 5.54813346 1.92103356 5.5465998 1.91793327 1 P 0 ;0,1,2=410,3=0.000000
L 5.5465998 1.91793327 5.54621654 1.91431644 1 P 0 ;0,1,2=410,3=0.000000
L 5.54621654 1.91431644 5.5465998 1.91121614 1 P 0 ;0,1,2=410,3=0.000000
L 5.5465998 1.91121614 5.54813346 1.90811585 1 P 0 ;0,1,2=410,3=0.000000
L 5.54813346 1.90811585 5.55043366 1.90553307 1 P 0 ;0,1,2=410,3=0.000000
L 5.55043366 1.90553307 5.55311644 1.9045 1 P 0 ;0,1,2=410,3=0.000000
L 5.55311644 1.9045 5.55618317 1.90553307 1 P 0 ;0,1,2=410,3=0.000000
L 5.55618317 1.90553307 5.55886663 1.90863238 1 P 0 ;0,1,2=410,3=0.000000
L 5.55886663 1.90863238 5.5604003 1.91328327 1 P 0 ;0,1,2=410,3=0.000000
L 5.5604003 1.91328327 5.56078356 1.9184498 1 P 0 ;0,1,2=410,3=0.000000
L 5.56078356 1.9184498 5.56001713 1.92516594 1 P 0 ;0,1,2=410,3=0.000000
L 5.56001713 1.92516594 5.55886663 1.92878376 1 P 0 ;0,1,2=410,3=0.000000
L 5.55886663 1.92878376 5.55695039 1.9323997 1 P 0 ;0,1,2=410,3=0.000000
L 5.55695039 1.9323997 5.55426693 1.93498337 1 P 0 ;0,1,2=410,3=0.000000
L 5.55426693 1.93498337 5.55158346 1.9355 1 P 0 ;0,1,2=410,3=0.000000
L 5.55158346 1.9355 5.5489 1.93446683 1 P 0 ;0,1,2=410,3=0.000000
L 5.5489 1.93446683 5.54698297 1.93188307 1 P 0 ;0,1,2=410,3=0.000000
L 1.608 3.57 1.652 3.57 1 P 0 
L 1.652 3.57 1.652 3.48 1 P 0 
L 1.652 3.48 1.608 3.48 1 P 0 
L 1.608 3.48 1.608 3.57 1 P 0 
L 1.64291624 3.40743327 1.64446683 3.40513307 1 P 0 ;0,1,2=411,3=90.000000
L 1.64446683 3.40513307 1.6455 3.4024503 1 P 0 ;0,1,2=411,3=90.000000
L 1.6455 3.4024503 1.6455 3.39938356 1 P 0 ;0,1,2=411,3=90.000000
L 1.6455 3.39938356 1.64394931 3.39593287 1 P 0 ;0,1,2=411,3=90.000000
L 1.64394931 3.39593287 1.64136654 3.3932501 1 P 0 ;0,1,2=411,3=90.000000
L 1.64136654 3.3932501 1.63826624 3.39133317 1 P 0 ;0,1,2=411,3=90.000000
L 1.63826624 3.39133317 1.6330998 3.38979951 1 P 0 ;0,1,2=411,3=90.000000
L 1.6330998 3.38979951 1.6284498 3.38941624 1 P 0 ;0,1,2=411,3=90.000000
L 1.6284498 3.38941624 1.6237999 3.39018337 1 P 0 ;0,1,2=411,3=90.000000
L 1.6237999 3.39018337 1.62069961 3.39133317 1 P 0 ;0,1,2=411,3=90.000000
L 1.62069961 3.39133317 1.61759931 3.39363337 1 P 0 ;0,1,2=411,3=90.000000
L 1.61759931 3.39363337 1.61553307 3.39631683 1 P 0 ;0,1,2=411,3=90.000000
L 1.61553307 3.39631683 1.6145 3.39899961 1 P 0 ;0,1,2=411,3=90.000000
L 1.6145 3.39899961 1.6145 3.40168307 1 P 0 ;0,1,2=411,3=90.000000
L 1.6145 3.40168307 1.61553307 3.40436654 1 P 0 ;0,1,2=411,3=90.000000
L 1.61553307 3.40436654 1.61708278 3.40666673 1 P 0 ;0,1,2=411,3=90.000000
L 1.61708278 3.40666673 1.61914892 3.40858366 1 P 0 ;0,1,2=411,3=90.000000
L 1.6145 3.42999961 1.61501654 3.43268307 1 P 0 ;0,1,2=411,3=90.000000
L 1.61501654 3.43268307 1.61656614 3.4357498 1 P 0 ;0,1,2=411,3=90.000000
L 1.61656614 3.4357498 1.61914892 3.43766673 1 P 0 ;0,1,2=411,3=90.000000
L 1.61914892 3.43766673 1.62276673 3.43843327 1 P 0 ;0,1,2=411,3=90.000000
L 1.62276673 3.43843327 1.62638268 3.43766673 1 P 0 ;0,1,2=411,3=90.000000
L 1.62638268 3.43766673 1.62948287 3.43536654 1 P 0 ;0,1,2=411,3=90.000000
L 1.62948287 3.43536654 1.63103356 3.43191654 1 P 0 ;0,1,2=411,3=90.000000
L 1.63103356 3.43191654 1.63103356 3.42808337 1 P 0 ;0,1,2=411,3=90.000000
L 1.63103356 3.42808337 1.63206663 3.42578317 1 P 0 ;0,1,2=411,3=90.000000
L 1.63206663 3.42578317 1.63464941 3.42386614 1 P 0 ;0,1,2=411,3=90.000000
L 1.63464941 3.42386614 1.63826624 3.4230997 1 P 0 ;0,1,2=411,3=90.000000
L 1.63826624 3.4230997 1.64188307 3.4242501 1 P 0 ;0,1,2=411,3=90.000000
L 1.64188307 3.4242501 1.64446683 3.42693287 1 P 0 ;0,1,2=411,3=90.000000
L 1.64446683 3.42693287 1.6455 3.42999961 1 P 0 ;0,1,2=411,3=90.000000
L 1.6455 3.42999961 1.64446683 3.43306634 1 P 0 ;0,1,2=411,3=90.000000
L 1.64446683 3.43306634 1.64188307 3.4357498 1 P 0 ;0,1,2=411,3=90.000000
L 1.64188307 3.4357498 1.63826624 3.4369002 1 P 0 ;0,1,2=411,3=90.000000
L 1.63826624 3.4369002 1.63464941 3.43613307 1 P 0 ;0,1,2=411,3=90.000000
L 1.63464941 3.43613307 1.63206663 3.43421673 1 P 0 ;0,1,2=411,3=90.000000
L 1.63206663 3.43421673 1.63103356 3.43191654 1 P 0 ;0,1,2=411,3=90.000000
L 1.63103356 3.43191654 1.63103356 3.42808337 1 P 0 ;0,1,2=411,3=90.000000
L 1.63103356 3.42808337 1.62948287 3.42463337 1 P 0 ;0,1,2=411,3=90.000000
L 1.62948287 3.42463337 1.62638268 3.42233317 1 P 0 ;0,1,2=411,3=90.000000
L 1.62638268 3.42233317 1.62276673 3.42156663 1 P 0 ;0,1,2=411,3=90.000000
L 1.62276673 3.42156663 1.61914892 3.42233317 1 P 0 ;0,1,2=411,3=90.000000
L 1.61914892 3.42233317 1.61656614 3.4242501 1 P 0 ;0,1,2=411,3=90.000000
L 1.61656614 3.4242501 1.61501654 3.42731683 1 P 0 ;0,1,2=411,3=90.000000
L 1.61501654 3.42731683 1.6145 3.42999961 1 P 0 ;0,1,2=411,3=90.000000
L 1.6145 3.46099961 1.61501654 3.46368307 1 P 0 ;0,1,2=411,3=90.000000
L 1.61501654 3.46368307 1.61656614 3.4667498 1 P 0 ;0,1,2=411,3=90.000000
L 1.61656614 3.4667498 1.61914892 3.46866673 1 P 0 ;0,1,2=411,3=90.000000
L 1.61914892 3.46866673 1.62276673 3.46943327 1 P 0 ;0,1,2=411,3=90.000000
L 1.62276673 3.46943327 1.62638268 3.46866673 1 P 0 ;0,1,2=411,3=90.000000
L 1.62638268 3.46866673 1.62948287 3.46636654 1 P 0 ;0,1,2=411,3=90.000000
L 1.62948287 3.46636654 1.63103356 3.46291654 1 P 0 ;0,1,2=411,3=90.000000
L 1.63103356 3.46291654 1.63103356 3.45908337 1 P 0 ;0,1,2=411,3=90.000000
L 1.63103356 3.45908337 1.63206663 3.45678317 1 P 0 ;0,1,2=411,3=90.000000
L 1.63206663 3.45678317 1.63464941 3.45486614 1 P 0 ;0,1,2=411,3=90.000000
L 1.63464941 3.45486614 1.63826624 3.4540997 1 P 0 ;0,1,2=411,3=90.000000
L 1.63826624 3.4540997 1.64188307 3.4552501 1 P 0 ;0,1,2=411,3=90.000000
L 1.64188307 3.4552501 1.64446683 3.45793287 1 P 0 ;0,1,2=411,3=90.000000
L 1.64446683 3.45793287 1.6455 3.46099961 1 P 0 ;0,1,2=411,3=90.000000
L 1.6455 3.46099961 1.64446683 3.46406634 1 P 0 ;0,1,2=411,3=90.000000
L 1.64446683 3.46406634 1.64188307 3.4667498 1 P 0 ;0,1,2=411,3=90.000000
L 1.64188307 3.4667498 1.63826624 3.4679002 1 P 0 ;0,1,2=411,3=90.000000
L 1.63826624 3.4679002 1.63464941 3.46713307 1 P 0 ;0,1,2=411,3=90.000000
L 1.63464941 3.46713307 1.63206663 3.46521673 1 P 0 ;0,1,2=411,3=90.000000
L 1.63206663 3.46521673 1.63103356 3.46291654 1 P 0 ;0,1,2=411,3=90.000000
L 1.63103356 3.46291654 1.63103356 3.45908337 1 P 0 ;0,1,2=411,3=90.000000
L 1.63103356 3.45908337 1.62948287 3.45563337 1 P 0 ;0,1,2=411,3=90.000000
L 1.62948287 3.45563337 1.62638268 3.45333317 1 P 0 ;0,1,2=411,3=90.000000
L 1.62638268 3.45333317 1.62276673 3.45256663 1 P 0 ;0,1,2=411,3=90.000000
L 1.62276673 3.45256663 1.61914892 3.45333317 1 P 0 ;0,1,2=411,3=90.000000
L 1.61914892 3.45333317 1.61656614 3.4552501 1 P 0 ;0,1,2=411,3=90.000000
L 1.61656614 3.4552501 1.61501654 3.45831683 1 P 0 ;0,1,2=411,3=90.000000
L 1.61501654 3.45831683 1.6145 3.46099961 1 P 0 ;0,1,2=411,3=90.000000
L 5.412 1.67 5.412 1.58 1 P 0 
L 5.368 1.67 5.412 1.67 1 P 0 
L 5.412 1.58 5.368 1.58 1 P 0 
L 5.368 1.58 5.368 1.67 1 P 0 
L 5.47291624 1.61693327 5.47446683 1.61463307 1 P 0 ;0,1,2=412,3=90.000000
L 5.47446683 1.61463307 5.4755 1.6119503 1 P 0 ;0,1,2=412,3=90.000000
L 5.4755 1.6119503 5.4755 1.60888356 1 P 0 ;0,1,2=412,3=90.000000
L 5.4755 1.60888356 5.47394931 1.60543287 1 P 0 ;0,1,2=412,3=90.000000
L 5.47394931 1.60543287 5.47136654 1.6027501 1 P 0 ;0,1,2=412,3=90.000000
L 5.47136654 1.6027501 5.46826624 1.60083317 1 P 0 ;0,1,2=412,3=90.000000
L 5.46826624 1.60083317 5.4630998 1.59929951 1 P 0 ;0,1,2=412,3=90.000000
L 5.4630998 1.59929951 5.4584498 1.59891624 1 P 0 ;0,1,2=412,3=90.000000
L 5.4584498 1.59891624 5.4537999 1.59968337 1 P 0 ;0,1,2=412,3=90.000000
L 5.4537999 1.59968337 5.45069961 1.60083317 1 P 0 ;0,1,2=412,3=90.000000
L 5.45069961 1.60083317 5.44759931 1.60313337 1 P 0 ;0,1,2=412,3=90.000000
L 5.44759931 1.60313337 5.44553307 1.60581683 1 P 0 ;0,1,2=412,3=90.000000
L 5.44553307 1.60581683 5.4445 1.60849961 1 P 0 ;0,1,2=412,3=90.000000
L 5.4445 1.60849961 5.4445 1.61118307 1 P 0 ;0,1,2=412,3=90.000000
L 5.4445 1.61118307 5.44553307 1.61386654 1 P 0 ;0,1,2=412,3=90.000000
L 5.44553307 1.61386654 5.44708278 1.61616673 1 P 0 ;0,1,2=412,3=90.000000
L 5.44708278 1.61616673 5.44914892 1.61808366 1 P 0 ;0,1,2=412,3=90.000000
L 5.4445 1.63949961 5.4755 1.63949961 1 P 0 ;0,1,2=412,3=90.000000
L 5.4755 1.63949961 5.4693003 1.6348999 1 P 0 ;0,1,2=412,3=90.000000
L 5.4445 1.6348999 5.4445 1.64409931 1 P 0 ;0,1,2=412,3=90.000000
L 5.4445 1.66973307 5.45121614 1.67049961 1 P 0 ;0,1,2=412,3=90.000000
L 5.45121614 1.67049961 5.45689921 1.6716501 1 P 0 ;0,1,2=412,3=90.000000
L 5.45689921 1.6716501 5.46206663 1.67318307 1 P 0 ;0,1,2=412,3=90.000000
L 5.46206663 1.67318307 5.4677497 1.6751 1 P 0 ;0,1,2=412,3=90.000000
L 5.4677497 1.6751 5.4755 1.67816673 1 P 0 ;0,1,2=412,3=90.000000
L 5.4755 1.67816673 5.4755 1.66283317 1 P 0 ;0,1,2=412,3=90.000000
L 5.4445 1.70149961 5.44501654 1.70418307 1 P 0 ;0,1,2=412,3=90.000000
L 5.44501654 1.70418307 5.44656614 1.7072498 1 P 0 ;0,1,2=412,3=90.000000
L 5.44656614 1.7072498 5.44914892 1.70916673 1 P 0 ;0,1,2=412,3=90.000000
L 5.44914892 1.70916673 5.45276673 1.70993327 1 P 0 ;0,1,2=412,3=90.000000
L 5.45276673 1.70993327 5.45638268 1.70916673 1 P 0 ;0,1,2=412,3=90.000000
L 5.45638268 1.70916673 5.45948287 1.70686654 1 P 0 ;0,1,2=412,3=90.000000
L 5.45948287 1.70686654 5.46103356 1.70341654 1 P 0 ;0,1,2=412,3=90.000000
L 5.46103356 1.70341654 5.46103356 1.69958337 1 P 0 ;0,1,2=412,3=90.000000
L 5.46103356 1.69958337 5.46206663 1.69728317 1 P 0 ;0,1,2=412,3=90.000000
L 5.46206663 1.69728317 5.46464941 1.69536614 1 P 0 ;0,1,2=412,3=90.000000
L 5.46464941 1.69536614 5.46826624 1.6945997 1 P 0 ;0,1,2=412,3=90.000000
L 5.46826624 1.6945997 5.47188307 1.6957501 1 P 0 ;0,1,2=412,3=90.000000
L 5.47188307 1.6957501 5.47446683 1.69843287 1 P 0 ;0,1,2=412,3=90.000000
L 5.47446683 1.69843287 5.4755 1.70149961 1 P 0 ;0,1,2=412,3=90.000000
L 5.4755 1.70149961 5.47446683 1.70456634 1 P 0 ;0,1,2=412,3=90.000000
L 5.47446683 1.70456634 5.47188307 1.7072498 1 P 0 ;0,1,2=412,3=90.000000
L 5.47188307 1.7072498 5.46826624 1.7084002 1 P 0 ;0,1,2=412,3=90.000000
L 5.46826624 1.7084002 5.46464941 1.70763307 1 P 0 ;0,1,2=412,3=90.000000
L 5.46464941 1.70763307 5.46206663 1.70571673 1 P 0 ;0,1,2=412,3=90.000000
L 5.46206663 1.70571673 5.46103356 1.70341654 1 P 0 ;0,1,2=412,3=90.000000
L 5.46103356 1.70341654 5.46103356 1.69958337 1 P 0 ;0,1,2=412,3=90.000000
L 5.46103356 1.69958337 5.45948287 1.69613337 1 P 0 ;0,1,2=412,3=90.000000
L 5.45948287 1.69613337 5.45638268 1.69383317 1 P 0 ;0,1,2=412,3=90.000000
L 5.45638268 1.69383317 5.45276673 1.69306663 1 P 0 ;0,1,2=412,3=90.000000
L 5.45276673 1.69306663 5.44914892 1.69383317 1 P 0 ;0,1,2=412,3=90.000000
L 5.44914892 1.69383317 5.44656614 1.6957501 1 P 0 ;0,1,2=412,3=90.000000
L 5.44656614 1.6957501 5.44501654 1.69881683 1 P 0 ;0,1,2=412,3=90.000000
L 5.44501654 1.69881683 5.4445 1.70149961 1 P 0 ;0,1,2=412,3=90.000000
L 3.675 2.192 3.675 2.148 1 P 0 
L 3.585 2.192 3.675 2.192 1 P 0 
L 3.675 2.148 3.585 2.148 1 P 0 
L 3.585 2.148 3.585 2.192 1 P 0 
L 3.68806673 2.10791624 3.69036693 2.10946683 1 P 0 ;0,1,2=413,3=0.000000
L 3.69036693 2.10946683 3.6930497 2.1105 1 P 0 ;0,1,2=413,3=0.000000
L 3.6930497 2.1105 3.69611644 2.1105 1 P 0 ;0,1,2=413,3=0.000000
L 3.69611644 2.1105 3.69956713 2.10894931 1 P 0 ;0,1,2=413,3=0.000000
L 3.69956713 2.10894931 3.7022499 2.10636654 1 P 0 ;0,1,2=413,3=0.000000
L 3.7022499 2.10636654 3.70416683 2.10326624 1 P 0 ;0,1,2=413,3=0.000000
L 3.70416683 2.10326624 3.70570049 2.0980998 1 P 0 ;0,1,2=413,3=0.000000
L 3.70570049 2.0980998 3.70608376 2.0934498 1 P 0 ;0,1,2=413,3=0.000000
L 3.70608376 2.0934498 3.70531663 2.0887999 1 P 0 ;0,1,2=413,3=0.000000
L 3.70531663 2.0887999 3.70416683 2.08569961 1 P 0 ;0,1,2=413,3=0.000000
L 3.70416683 2.08569961 3.70186663 2.08259931 1 P 0 ;0,1,2=413,3=0.000000
L 3.70186663 2.08259931 3.69918317 2.08053307 1 P 0 ;0,1,2=413,3=0.000000
L 3.69918317 2.08053307 3.69650039 2.0795 1 P 0 ;0,1,2=413,3=0.000000
L 3.69650039 2.0795 3.69381693 2.0795 1 P 0 ;0,1,2=413,3=0.000000
L 3.69381693 2.0795 3.69113346 2.08053307 1 P 0 ;0,1,2=413,3=0.000000
L 3.69113346 2.08053307 3.68883327 2.08208278 1 P 0 ;0,1,2=413,3=0.000000
L 3.68883327 2.08208278 3.68691634 2.08414892 1 P 0 ;0,1,2=413,3=0.000000
L 3.66550039 2.0795 3.66550039 2.1105 1 P 0 ;0,1,2=413,3=0.000000
L 3.66550039 2.1105 3.6701001 2.1043003 1 P 0 ;0,1,2=413,3=0.000000
L 3.6701001 2.0795 3.66090069 2.0795 1 P 0 ;0,1,2=413,3=0.000000
L 3.64293337 2.08414892 3.64063386 2.08156614 1 P 0 ;0,1,2=413,3=0.000000
L 3.64063386 2.08156614 3.63795039 2.08001654 1 P 0 ;0,1,2=413,3=0.000000
L 3.63795039 2.08001654 3.63450039 2.0795 1 P 0 ;0,1,2=413,3=0.000000
L 3.63450039 2.0795 3.6310497 2.08053307 1 P 0 ;0,1,2=413,3=0.000000
L 3.6310497 2.08053307 3.62836693 2.08259931 1 P 0 ;0,1,2=413,3=0.000000
L 3.62836693 2.08259931 3.62645 2.08621614 1 P 0 ;0,1,2=413,3=0.000000
L 3.62645 2.08621614 3.62606673 2.09034951 1 P 0 ;0,1,2=413,3=0.000000
L 3.62606673 2.09034951 3.62683327 2.09448287 1 P 0 ;0,1,2=413,3=0.000000
L 3.62683327 2.09448287 3.6287502 2.09706663 1 P 0 ;0,1,2=413,3=0.000000
L 3.6287502 2.09706663 3.63143366 2.09913287 1 P 0 ;0,1,2=413,3=0.000000
L 3.63143366 2.09913287 3.63411644 2.09964941 1 P 0 ;0,1,2=413,3=0.000000
L 3.63411644 2.09964941 3.6367999 2.09913287 1 P 0 ;0,1,2=413,3=0.000000
L 3.6367999 2.09913287 3.6402499 2.09706663 1 P 0 ;0,1,2=413,3=0.000000
L 3.6402499 2.09706663 3.6391001 2.1105 1 P 0 ;0,1,2=413,3=0.000000
L 3.6391001 2.1105 3.6287502 2.1105 1 P 0 ;0,1,2=413,3=0.000000
L 3.60350039 2.1105 3.60656713 2.10946683 1 P 0 ;0,1,2=413,3=0.000000
L 3.60656713 2.10946683 3.60886663 2.10688307 1 P 0 ;0,1,2=413,3=0.000000
L 3.60886663 2.10688307 3.6104003 2.10378376 1 P 0 ;0,1,2=413,3=0.000000
L 3.6104003 2.10378376 3.6115501 2.09964941 1 P 0 ;0,1,2=413,3=0.000000
L 3.6115501 2.09964941 3.61193337 2.09499951 1 P 0 ;0,1,2=413,3=0.000000
L 3.61193337 2.09499951 3.6115501 2.09034951 1 P 0 ;0,1,2=413,3=0.000000
L 3.6115501 2.09034951 3.6104003 2.08621614 1 P 0 ;0,1,2=413,3=0.000000
L 3.6104003 2.08621614 3.60886663 2.08311585 1 P 0 ;0,1,2=413,3=0.000000
L 3.60886663 2.08311585 3.60656713 2.08053307 1 P 0 ;0,1,2=413,3=0.000000
L 3.60656713 2.08053307 3.60350039 2.0795 1 P 0 ;0,1,2=413,3=0.000000
L 3.60350039 2.0795 3.60043366 2.08053307 1 P 0 ;0,1,2=413,3=0.000000
L 3.60043366 2.08053307 3.59813346 2.08311585 1 P 0 ;0,1,2=413,3=0.000000
L 3.59813346 2.08311585 3.5965998 2.08621614 1 P 0 ;0,1,2=413,3=0.000000
L 3.5965998 2.08621614 3.59545 2.09034951 1 P 0 ;0,1,2=413,3=0.000000
L 3.59545 2.09034951 3.59506673 2.09499951 1 P 0 ;0,1,2=413,3=0.000000
L 3.59506673 2.09499951 3.59545 2.09964941 1 P 0 ;0,1,2=413,3=0.000000
L 3.59545 2.09964941 3.5965998 2.10378376 1 P 0 ;0,1,2=413,3=0.000000
L 3.5965998 2.10378376 3.59813346 2.10688307 1 P 0 ;0,1,2=413,3=0.000000
L 3.59813346 2.10688307 3.60043366 2.10946683 1 P 0 ;0,1,2=413,3=0.000000
L 3.60043366 2.10946683 3.60350039 2.1105 1 P 0 ;0,1,2=413,3=0.000000
L 2.975 2.027 3.065 2.027 1 P 0 
L 3.065 2.027 3.065 1.983 1 P 0 
L 3.065 1.983 2.975 1.983 1 P 0 
L 2.975 1.983 2.975 2.027 1 P 0 
L 3.16756673 2.02291624 3.16986693 2.02446683 1 P 0 ;0,1,2=414,3=0.000000
L 3.16986693 2.02446683 3.1725497 2.0255 1 P 0 ;0,1,2=414,3=0.000000
L 3.1725497 2.0255 3.17561644 2.0255 1 P 0 ;0,1,2=414,3=0.000000
L 3.17561644 2.0255 3.17906713 2.02394931 1 P 0 ;0,1,2=414,3=0.000000
L 3.17906713 2.02394931 3.1817499 2.02136654 1 P 0 ;0,1,2=414,3=0.000000
L 3.1817499 2.02136654 3.18366683 2.01826624 1 P 0 ;0,1,2=414,3=0.000000
L 3.18366683 2.01826624 3.18520049 2.0130998 1 P 0 ;0,1,2=414,3=0.000000
L 3.18520049 2.0130998 3.18558376 2.0084498 1 P 0 ;0,1,2=414,3=0.000000
L 3.18558376 2.0084498 3.18481663 2.0037999 1 P 0 ;0,1,2=414,3=0.000000
L 3.18481663 2.0037999 3.18366683 2.00069961 1 P 0 ;0,1,2=414,3=0.000000
L 3.18366683 2.00069961 3.18136663 1.99759931 1 P 0 ;0,1,2=414,3=0.000000
L 3.18136663 1.99759931 3.17868317 1.99553307 1 P 0 ;0,1,2=414,3=0.000000
L 3.17868317 1.99553307 3.17600039 1.9945 1 P 0 ;0,1,2=414,3=0.000000
L 3.17600039 1.9945 3.17331693 1.9945 1 P 0 ;0,1,2=414,3=0.000000
L 3.17331693 1.9945 3.17063346 1.99553307 1 P 0 ;0,1,2=414,3=0.000000
L 3.17063346 1.99553307 3.16833327 1.99708278 1 P 0 ;0,1,2=414,3=0.000000
L 3.16833327 1.99708278 3.16641634 1.99914892 1 P 0 ;0,1,2=414,3=0.000000
L 3.15228356 2.00741575 3.1496001 2.01103356 1 P 0 ;0,1,2=414,3=0.000000
L 3.1496001 2.01103356 3.1472999 2.0130998 1 P 0 ;0,1,2=414,3=0.000000
L 3.1472999 2.0130998 3.14423317 2.01413287 1 P 0 ;0,1,2=414,3=0.000000
L 3.14423317 2.01413287 3.1415497 2.0130998 1 P 0 ;0,1,2=414,3=0.000000
L 3.1415497 2.0130998 3.13963346 2.01103356 1 P 0 ;0,1,2=414,3=0.000000
L 3.13963346 2.01103356 3.1380998 2.00793327 1 P 0 ;0,1,2=414,3=0.000000
L 3.1380998 2.00793327 3.13771654 2.00431644 1 P 0 ;0,1,2=414,3=0.000000
L 3.13771654 2.00431644 3.1380998 2.00121614 1 P 0 ;0,1,2=414,3=0.000000
L 3.1380998 2.00121614 3.13963346 1.99811585 1 P 0 ;0,1,2=414,3=0.000000
L 3.13963346 1.99811585 3.14193366 1.99553307 1 P 0 ;0,1,2=414,3=0.000000
L 3.14193366 1.99553307 3.14461644 1.9945 1 P 0 ;0,1,2=414,3=0.000000
L 3.14461644 1.9945 3.14768317 1.99553307 1 P 0 ;0,1,2=414,3=0.000000
L 3.14768317 1.99553307 3.15036663 1.99863238 1 P 0 ;0,1,2=414,3=0.000000
L 3.15036663 1.99863238 3.1519003 2.00328327 1 P 0 ;0,1,2=414,3=0.000000
L 3.1519003 2.00328327 3.15228356 2.0084498 1 P 0 ;0,1,2=414,3=0.000000
L 3.15228356 2.0084498 3.15151713 2.01516594 1 P 0 ;0,1,2=414,3=0.000000
L 3.15151713 2.01516594 3.15036663 2.01878376 1 P 0 ;0,1,2=414,3=0.000000
L 3.15036663 2.01878376 3.14845039 2.0223997 1 P 0 ;0,1,2=414,3=0.000000
L 3.14845039 2.0223997 3.14576693 2.02498337 1 P 0 ;0,1,2=414,3=0.000000
L 3.14576693 2.02498337 3.14308346 2.0255 1 P 0 ;0,1,2=414,3=0.000000
L 3.14308346 2.0255 3.1404 2.02446683 1 P 0 ;0,1,2=414,3=0.000000
L 3.1404 2.02446683 3.13848297 2.02188307 1 P 0 ;0,1,2=414,3=0.000000
L 3.12243337 1.99914892 3.12013386 1.99656614 1 P 0 ;0,1,2=414,3=0.000000
L 3.12013386 1.99656614 3.11745039 1.99501654 1 P 0 ;0,1,2=414,3=0.000000
L 3.11745039 1.99501654 3.11400039 1.9945 1 P 0 ;0,1,2=414,3=0.000000
L 3.11400039 1.9945 3.1105497 1.99553307 1 P 0 ;0,1,2=414,3=0.000000
L 3.1105497 1.99553307 3.10786693 1.99759931 1 P 0 ;0,1,2=414,3=0.000000
L 3.10786693 1.99759931 3.10595 2.00121614 1 P 0 ;0,1,2=414,3=0.000000
L 3.10595 2.00121614 3.10556673 2.00534951 1 P 0 ;0,1,2=414,3=0.000000
L 3.10556673 2.00534951 3.10633327 2.00948287 1 P 0 ;0,1,2=414,3=0.000000
L 3.10633327 2.00948287 3.1082502 2.01206663 1 P 0 ;0,1,2=414,3=0.000000
L 3.1082502 2.01206663 3.11093366 2.01413287 1 P 0 ;0,1,2=414,3=0.000000
L 3.11093366 2.01413287 3.11361644 2.01464941 1 P 0 ;0,1,2=414,3=0.000000
L 3.11361644 2.01464941 3.1162999 2.01413287 1 P 0 ;0,1,2=414,3=0.000000
L 3.1162999 2.01413287 3.1197499 2.01206663 1 P 0 ;0,1,2=414,3=0.000000
L 3.1197499 2.01206663 3.1186001 2.0255 1 P 0 ;0,1,2=414,3=0.000000
L 3.1186001 2.0255 3.1082502 2.0255 1 P 0 ;0,1,2=414,3=0.000000
L 2.975 2.072 3.065 2.072 1 P 0 
L 3.065 2.072 3.065 2.028 1 P 0 
L 3.065 2.028 2.975 2.028 1 P 0 
L 2.975 2.028 2.975 2.072 1 P 0 
L 3.16756673 2.07291624 3.16986693 2.07446683 1 P 0 ;0,1,2=415,3=0.000000
L 3.16986693 2.07446683 3.1725497 2.0755 1 P 0 ;0,1,2=415,3=0.000000
L 3.1725497 2.0755 3.17561644 2.0755 1 P 0 ;0,1,2=415,3=0.000000
L 3.17561644 2.0755 3.17906713 2.07394931 1 P 0 ;0,1,2=415,3=0.000000
L 3.17906713 2.07394931 3.1817499 2.07136654 1 P 0 ;0,1,2=415,3=0.000000
L 3.1817499 2.07136654 3.18366683 2.06826624 1 P 0 ;0,1,2=415,3=0.000000
L 3.18366683 2.06826624 3.18520049 2.0630998 1 P 0 ;0,1,2=415,3=0.000000
L 3.18520049 2.0630998 3.18558376 2.0584498 1 P 0 ;0,1,2=415,3=0.000000
L 3.18558376 2.0584498 3.18481663 2.0537999 1 P 0 ;0,1,2=415,3=0.000000
L 3.18481663 2.0537999 3.18366683 2.05069961 1 P 0 ;0,1,2=415,3=0.000000
L 3.18366683 2.05069961 3.18136663 2.04759931 1 P 0 ;0,1,2=415,3=0.000000
L 3.18136663 2.04759931 3.17868317 2.04553307 1 P 0 ;0,1,2=415,3=0.000000
L 3.17868317 2.04553307 3.17600039 2.0445 1 P 0 ;0,1,2=415,3=0.000000
L 3.17600039 2.0445 3.17331693 2.0445 1 P 0 ;0,1,2=415,3=0.000000
L 3.17331693 2.0445 3.17063346 2.04553307 1 P 0 ;0,1,2=415,3=0.000000
L 3.17063346 2.04553307 3.16833327 2.04708278 1 P 0 ;0,1,2=415,3=0.000000
L 3.16833327 2.04708278 3.16641634 2.04914892 1 P 0 ;0,1,2=415,3=0.000000
L 3.15228356 2.05741575 3.1496001 2.06103356 1 P 0 ;0,1,2=415,3=0.000000
L 3.1496001 2.06103356 3.1472999 2.0630998 1 P 0 ;0,1,2=415,3=0.000000
L 3.1472999 2.0630998 3.14423317 2.06413287 1 P 0 ;0,1,2=415,3=0.000000
L 3.14423317 2.06413287 3.1415497 2.0630998 1 P 0 ;0,1,2=415,3=0.000000
L 3.1415497 2.0630998 3.13963346 2.06103356 1 P 0 ;0,1,2=415,3=0.000000
L 3.13963346 2.06103356 3.1380998 2.05793327 1 P 0 ;0,1,2=415,3=0.000000
L 3.1380998 2.05793327 3.13771654 2.05431644 1 P 0 ;0,1,2=415,3=0.000000
L 3.13771654 2.05431644 3.1380998 2.05121614 1 P 0 ;0,1,2=415,3=0.000000
L 3.1380998 2.05121614 3.13963346 2.04811585 1 P 0 ;0,1,2=415,3=0.000000
L 3.13963346 2.04811585 3.14193366 2.04553307 1 P 0 ;0,1,2=415,3=0.000000
L 3.14193366 2.04553307 3.14461644 2.0445 1 P 0 ;0,1,2=415,3=0.000000
L 3.14461644 2.0445 3.14768317 2.04553307 1 P 0 ;0,1,2=415,3=0.000000
L 3.14768317 2.04553307 3.15036663 2.04863238 1 P 0 ;0,1,2=415,3=0.000000
L 3.15036663 2.04863238 3.1519003 2.05328327 1 P 0 ;0,1,2=415,3=0.000000
L 3.1519003 2.05328327 3.15228356 2.0584498 1 P 0 ;0,1,2=415,3=0.000000
L 3.15228356 2.0584498 3.15151713 2.06516594 1 P 0 ;0,1,2=415,3=0.000000
L 3.15151713 2.06516594 3.15036663 2.06878376 1 P 0 ;0,1,2=415,3=0.000000
L 3.15036663 2.06878376 3.14845039 2.0723997 1 P 0 ;0,1,2=415,3=0.000000
L 3.14845039 2.0723997 3.14576693 2.07498337 1 P 0 ;0,1,2=415,3=0.000000
L 3.14576693 2.07498337 3.14308346 2.0755 1 P 0 ;0,1,2=415,3=0.000000
L 3.14308346 2.0755 3.1404 2.07446683 1 P 0 ;0,1,2=415,3=0.000000
L 3.1404 2.07446683 3.13848297 2.07188307 1 P 0 ;0,1,2=415,3=0.000000
L 3.12128356 2.05741575 3.1186001 2.06103356 1 P 0 ;0,1,2=415,3=0.000000
L 3.1186001 2.06103356 3.1162999 2.0630998 1 P 0 ;0,1,2=415,3=0.000000
L 3.1162999 2.0630998 3.11323317 2.06413287 1 P 0 ;0,1,2=415,3=0.000000
L 3.11323317 2.06413287 3.1105497 2.0630998 1 P 0 ;0,1,2=415,3=0.000000
L 3.1105497 2.0630998 3.10863346 2.06103356 1 P 0 ;0,1,2=415,3=0.000000
L 3.10863346 2.06103356 3.1070998 2.05793327 1 P 0 ;0,1,2=415,3=0.000000
L 3.1070998 2.05793327 3.10671654 2.05431644 1 P 0 ;0,1,2=415,3=0.000000
L 3.10671654 2.05431644 3.1070998 2.05121614 1 P 0 ;0,1,2=415,3=0.000000
L 3.1070998 2.05121614 3.10863346 2.04811585 1 P 0 ;0,1,2=415,3=0.000000
L 3.10863346 2.04811585 3.11093366 2.04553307 1 P 0 ;0,1,2=415,3=0.000000
L 3.11093366 2.04553307 3.11361644 2.0445 1 P 0 ;0,1,2=415,3=0.000000
L 3.11361644 2.0445 3.11668317 2.04553307 1 P 0 ;0,1,2=415,3=0.000000
L 3.11668317 2.04553307 3.11936663 2.04863238 1 P 0 ;0,1,2=415,3=0.000000
L 3.11936663 2.04863238 3.1209003 2.05328327 1 P 0 ;0,1,2=415,3=0.000000
L 3.1209003 2.05328327 3.12128356 2.0584498 1 P 0 ;0,1,2=415,3=0.000000
L 3.12128356 2.0584498 3.12051713 2.06516594 1 P 0 ;0,1,2=415,3=0.000000
L 3.12051713 2.06516594 3.11936663 2.06878376 1 P 0 ;0,1,2=415,3=0.000000
L 3.11936663 2.06878376 3.11745039 2.0723997 1 P 0 ;0,1,2=415,3=0.000000
L 3.11745039 2.0723997 3.11476693 2.07498337 1 P 0 ;0,1,2=415,3=0.000000
L 3.11476693 2.07498337 3.11208346 2.0755 1 P 0 ;0,1,2=415,3=0.000000
L 3.11208346 2.0755 3.1094 2.07446683 1 P 0 ;0,1,2=415,3=0.000000
L 3.1094 2.07446683 3.10748297 2.07188307 1 P 0 ;0,1,2=415,3=0.000000
L 4.265 1.772 4.265 1.728 1 P 0 
L 4.265 1.728 4.175 1.728 1 P 0 
L 4.175 1.728 4.175 1.772 1 P 0 
L 4.175 1.772 4.265 1.772 1 P 0 
L 2.54213337 1.69741634 2.54373356 1.69866683 1 P 0 ;0,1,2=416,3=0.000000
L 2.54373356 1.69866683 2.5455998 1.6995 1 P 0 ;0,1,2=416,3=0.000000
L 2.5455998 1.6995 2.54773317 1.6995 1 P 0 ;0,1,2=416,3=0.000000
L 2.54773317 1.6995 2.55013366 1.69824941 1 P 0 ;0,1,2=416,3=0.000000
L 2.55013366 1.69824941 2.5519999 1.69616654 1 P 0 ;0,1,2=416,3=0.000000
L 2.5519999 1.69616654 2.55333346 1.69366634 1 P 0 ;0,1,2=416,3=0.000000
L 2.55333346 1.69366634 2.55440039 1.6894998 1 P 0 ;0,1,2=416,3=0.000000
L 2.55440039 1.6894998 2.55466703 1.6857498 1 P 0 ;0,1,2=416,3=0.000000
L 2.55466703 1.6857498 2.55413327 1.6819999 1 P 0 ;0,1,2=416,3=0.000000
L 2.55413327 1.6819999 2.55333346 1.67949961 1 P 0 ;0,1,2=416,3=0.000000
L 2.55333346 1.67949961 2.55173337 1.67699941 1 P 0 ;0,1,2=416,3=0.000000
L 2.55173337 1.67699941 2.54986654 1.67533307 1 P 0 ;0,1,2=416,3=0.000000
L 2.54986654 1.67533307 2.5480003 1.6745 1 P 0 ;0,1,2=416,3=0.000000
L 2.5480003 1.6745 2.54613356 1.6745 1 P 0 ;0,1,2=416,3=0.000000
L 2.54613356 1.6745 2.54426673 1.67533307 1 P 0 ;0,1,2=416,3=0.000000
L 2.54426673 1.67533307 2.54266663 1.67658287 1 P 0 ;0,1,2=416,3=0.000000
L 2.54266663 1.67658287 2.54133307 1.67824911 1 P 0 ;0,1,2=416,3=0.000000
L 2.53106683 1.69533337 2.52946673 1.69783287 1 P 0 ;0,1,2=416,3=0.000000
L 2.52946673 1.69783287 2.5276 1.69908337 1 P 0 ;0,1,2=416,3=0.000000
L 2.5276 1.69908337 2.52546663 1.6995 1 P 0 ;0,1,2=416,3=0.000000
L 2.52546663 1.6995 2.5228 1.69866683 1 P 0 ;0,1,2=416,3=0.000000
L 2.5228 1.69866683 2.52093327 1.69658317 1 P 0 ;0,1,2=416,3=0.000000
L 2.52093327 1.69658317 2.5204 1.69408366 1 P 0 ;0,1,2=416,3=0.000000
L 2.5204 1.69408366 2.52066663 1.69158268 1 P 0 ;0,1,2=416,3=0.000000
L 2.52066663 1.69158268 2.52173356 1.6894998 1 P 0 ;0,1,2=416,3=0.000000
L 2.52173356 1.6894998 2.52706673 1.68533327 1 P 0 ;0,1,2=416,3=0.000000
L 2.52706673 1.68533327 2.52946673 1.68241644 1 P 0 ;0,1,2=416,3=0.000000
L 2.52946673 1.68241644 2.53106683 1.67824911 1 P 0 ;0,1,2=416,3=0.000000
L 2.53106683 1.67824911 2.5316001 1.6745 1 P 0 ;0,1,2=416,3=0.000000
L 2.5316001 1.6745 2.5204 1.6745 1 P 0 ;0,1,2=416,3=0.000000
L 2.5040003 1.6745 2.5040003 1.6995 1 P 0 ;0,1,2=416,3=0.000000
L 2.5040003 1.6995 2.5072001 1.6945003 1 P 0 ;0,1,2=416,3=0.000000
L 2.5072001 1.6745 2.50080049 1.6745 1 P 0 ;0,1,2=416,3=0.000000
L 2.48653366 1.67741604 2.48466683 1.67533307 1 P 0 ;0,1,2=416,3=0.000000
L 2.48466683 1.67533307 2.48253346 1.6745 1 P 0 ;0,1,2=416,3=0.000000
L 2.48253346 1.6745 2.4804001 1.67533307 1 P 0 ;0,1,2=416,3=0.000000
L 2.4804001 1.67533307 2.47853337 1.67783258 1 P 0 ;0,1,2=416,3=0.000000
L 2.47853337 1.67783258 2.4771999 1.68158327 1 P 0 ;0,1,2=416,3=0.000000
L 2.4771999 1.68158327 2.47666663 1.68533327 1 P 0 ;0,1,2=416,3=0.000000
L 2.47666663 1.68533327 2.47666663 1.68991634 1 P 0 ;0,1,2=416,3=0.000000
L 2.47666663 1.68991634 2.4771999 1.69366634 1 P 0 ;0,1,2=416,3=0.000000
L 2.4771999 1.69366634 2.47853337 1.6969997 1 P 0 ;0,1,2=416,3=0.000000
L 2.47853337 1.6969997 2.48013356 1.69866683 1 P 0 ;0,1,2=416,3=0.000000
L 2.48013356 1.69866683 2.4820003 1.6995 1 P 0 ;0,1,2=416,3=0.000000
L 2.4820003 1.6995 2.48413366 1.69866683 1 P 0 ;0,1,2=416,3=0.000000
L 2.48413366 1.69866683 2.48573337 1.6969997 1 P 0 ;0,1,2=416,3=0.000000
L 2.48573337 1.6969997 2.4868002 1.6945003 1 P 0 ;0,1,2=416,3=0.000000
L 2.4868002 1.6945003 2.48733346 1.69116614 1 P 0 ;0,1,2=416,3=0.000000
L 2.48733346 1.69116614 2.4868002 1.6882501 1 P 0 ;0,1,2=416,3=0.000000
L 2.4868002 1.6882501 2.48546673 1.68533327 1 P 0 ;0,1,2=416,3=0.000000
L 2.48546673 1.68533327 2.48386654 1.68366614 1 P 0 ;0,1,2=416,3=0.000000
L 2.48386654 1.68366614 2.4820003 1.68324961 1 P 0 ;0,1,2=416,3=0.000000
L 2.4820003 1.68324961 2.47986693 1.68408278 1 P 0 ;0,1,2=416,3=0.000000
L 2.47986693 1.68408278 2.47826673 1.68616644 1 P 0 ;0,1,2=416,3=0.000000
L 2.47826673 1.68616644 2.47666663 1.68991634 1 P 0 ;0,1,2=416,3=0.000000
L 4.164 1.728 4.074 1.728 1 P 0 
L 4.074 1.728 4.074 1.772 1 P 0 
L 4.074 1.772 4.164 1.772 1 P 0 
L 4.164 1.772 4.164 1.728 1 P 0 
L 2.44113337 1.69741634 2.44273356 1.69866683 1 P 0 ;0,1,2=417,3=0.000000
L 2.44273356 1.69866683 2.4445998 1.6995 1 P 0 ;0,1,2=417,3=0.000000
L 2.4445998 1.6995 2.44673317 1.6995 1 P 0 ;0,1,2=417,3=0.000000
L 2.44673317 1.6995 2.44913366 1.69824941 1 P 0 ;0,1,2=417,3=0.000000
L 2.44913366 1.69824941 2.4509999 1.69616654 1 P 0 ;0,1,2=417,3=0.000000
L 2.4509999 1.69616654 2.45233346 1.69366634 1 P 0 ;0,1,2=417,3=0.000000
L 2.45233346 1.69366634 2.45340039 1.6894998 1 P 0 ;0,1,2=417,3=0.000000
L 2.45340039 1.6894998 2.45366703 1.6857498 1 P 0 ;0,1,2=417,3=0.000000
L 2.45366703 1.6857498 2.45313327 1.6819999 1 P 0 ;0,1,2=417,3=0.000000
L 2.45313327 1.6819999 2.45233346 1.67949961 1 P 0 ;0,1,2=417,3=0.000000
L 2.45233346 1.67949961 2.45073337 1.67699941 1 P 0 ;0,1,2=417,3=0.000000
L 2.45073337 1.67699941 2.44886654 1.67533307 1 P 0 ;0,1,2=417,3=0.000000
L 2.44886654 1.67533307 2.4470003 1.6745 1 P 0 ;0,1,2=417,3=0.000000
L 2.4470003 1.6745 2.44513356 1.6745 1 P 0 ;0,1,2=417,3=0.000000
L 2.44513356 1.6745 2.44326673 1.67533307 1 P 0 ;0,1,2=417,3=0.000000
L 2.44326673 1.67533307 2.44166663 1.67658287 1 P 0 ;0,1,2=417,3=0.000000
L 2.44166663 1.67658287 2.44033307 1.67824911 1 P 0 ;0,1,2=417,3=0.000000
L 2.4250003 1.6745 2.4250003 1.6995 1 P 0 ;0,1,2=417,3=0.000000
L 2.4250003 1.6995 2.4282001 1.6945003 1 P 0 ;0,1,2=417,3=0.000000
L 2.4282001 1.6745 2.42180049 1.6745 1 P 0 ;0,1,2=417,3=0.000000
L 2.4030003 1.6745 2.4030003 1.6995 1 P 0 ;0,1,2=417,3=0.000000
L 2.4030003 1.6995 2.4062001 1.6945003 1 P 0 ;0,1,2=417,3=0.000000
L 2.4062001 1.6745 2.39980049 1.6745 1 P 0 ;0,1,2=417,3=0.000000
L 2.38686673 1.67949961 2.38526703 1.67658287 1 P 0 ;0,1,2=417,3=0.000000
L 2.38526703 1.67658287 2.38313366 1.67491654 1 P 0 ;0,1,2=417,3=0.000000
L 2.38313366 1.67491654 2.38073317 1.6745 1 P 0 ;0,1,2=417,3=0.000000
L 2.38073317 1.6745 2.3785998 1.67491654 1 P 0 ;0,1,2=417,3=0.000000
L 2.3785998 1.67491654 2.37646644 1.67699941 1 P 0 ;0,1,2=417,3=0.000000
L 2.37646644 1.67699941 2.37513337 1.67949961 1 P 0 ;0,1,2=417,3=0.000000
L 2.37513337 1.67949961 2.37486683 1.6819999 1 P 0 ;0,1,2=417,3=0.000000
L 2.37486683 1.6819999 2.3754 1.68491594 1 P 0 ;0,1,2=417,3=0.000000
L 2.3754 1.68491594 2.37726673 1.68699961 1 P 0 ;0,1,2=417,3=0.000000
L 2.37726673 1.68699961 2.37913356 1.68783346 1 P 0 ;0,1,2=417,3=0.000000
L 2.37913356 1.68783346 2.38153346 1.68783346 1 P 0 ;0,1,2=417,3=0.000000
L 2.37913356 1.68783346 2.37753337 1.68908327 1 P 0 ;0,1,2=417,3=0.000000
L 2.37753337 1.68908327 2.3761999 1.69116614 1 P 0 ;0,1,2=417,3=0.000000
L 2.3761999 1.69116614 2.37566663 1.69366634 1 P 0 ;0,1,2=417,3=0.000000
L 2.37566663 1.69366634 2.3761999 1.69616654 1 P 0 ;0,1,2=417,3=0.000000
L 2.3761999 1.69616654 2.37753337 1.69824941 1 P 0 ;0,1,2=417,3=0.000000
L 2.37753337 1.69824941 2.37993337 1.6995 1 P 0 ;0,1,2=417,3=0.000000
L 2.37993337 1.6995 2.38233337 1.69908337 1 P 0 ;0,1,2=417,3=0.000000
L 2.38233337 1.69908337 2.38473337 1.69741634 1 P 0 ;0,1,2=417,3=0.000000
L 4.283 1.525 4.283 1.615 1 P 0 
L 4.283 1.615 4.327 1.615 1 P 0 
L 4.327 1.615 4.327 1.525 1 P 0 
L 4.327 1.525 4.283 1.525 1 P 0 
L 2.67741634 1.47786663 2.67866683 1.47626644 1 P 0 ;0,1,2=418,3=90.000000
L 2.67866683 1.47626644 2.6795 1.4744002 1 P 0 ;0,1,2=418,3=90.000000
L 2.6795 1.4744002 2.6795 1.47226683 1 P 0 ;0,1,2=418,3=90.000000
L 2.6795 1.47226683 2.67824941 1.46986634 1 P 0 ;0,1,2=418,3=90.000000
L 2.67824941 1.46986634 2.67616654 1.4680001 1 P 0 ;0,1,2=418,3=90.000000
L 2.67616654 1.4680001 2.67366634 1.46666654 1 P 0 ;0,1,2=418,3=90.000000
L 2.67366634 1.46666654 2.6694998 1.46559961 1 P 0 ;0,1,2=418,3=90.000000
L 2.6694998 1.46559961 2.6657498 1.46533297 1 P 0 ;0,1,2=418,3=90.000000
L 2.6657498 1.46533297 2.6619999 1.46586673 1 P 0 ;0,1,2=418,3=90.000000
L 2.6619999 1.46586673 2.65949961 1.46666654 1 P 0 ;0,1,2=418,3=90.000000
L 2.65949961 1.46666654 2.65699941 1.46826663 1 P 0 ;0,1,2=418,3=90.000000
L 2.65699941 1.46826663 2.65533307 1.47013346 1 P 0 ;0,1,2=418,3=90.000000
L 2.65533307 1.47013346 2.6545 1.4719997 1 P 0 ;0,1,2=418,3=90.000000
L 2.6545 1.4719997 2.6545 1.47386644 1 P 0 ;0,1,2=418,3=90.000000
L 2.6545 1.47386644 2.65533307 1.47573327 1 P 0 ;0,1,2=418,3=90.000000
L 2.65533307 1.47573327 2.65658287 1.47733337 1 P 0 ;0,1,2=418,3=90.000000
L 2.65658287 1.47733337 2.65824911 1.47866693 1 P 0 ;0,1,2=418,3=90.000000
L 2.6545 1.4939997 2.6795 1.4939997 1 P 0 ;0,1,2=418,3=90.000000
L 2.6795 1.4939997 2.6745003 1.4907999 1 P 0 ;0,1,2=418,3=90.000000
L 2.6545 1.4907999 2.6545 1.49719951 1 P 0 ;0,1,2=418,3=90.000000
L 2.65949961 1.51013327 2.65658287 1.51173297 1 P 0 ;0,1,2=418,3=90.000000
L 2.65658287 1.51173297 2.65491654 1.51386634 1 P 0 ;0,1,2=418,3=90.000000
L 2.65491654 1.51386634 2.6545 1.51626683 1 P 0 ;0,1,2=418,3=90.000000
L 2.6545 1.51626683 2.65491654 1.5184002 1 P 0 ;0,1,2=418,3=90.000000
L 2.65491654 1.5184002 2.65699941 1.52053356 1 P 0 ;0,1,2=418,3=90.000000
L 2.65699941 1.52053356 2.65949961 1.52186663 1 P 0 ;0,1,2=418,3=90.000000
L 2.65949961 1.52186663 2.6619999 1.52213317 1 P 0 ;0,1,2=418,3=90.000000
L 2.6619999 1.52213317 2.66491594 1.5216 1 P 0 ;0,1,2=418,3=90.000000
L 2.66491594 1.5216 2.66699961 1.51973327 1 P 0 ;0,1,2=418,3=90.000000
L 2.66699961 1.51973327 2.66783346 1.51786644 1 P 0 ;0,1,2=418,3=90.000000
L 2.66783346 1.51786644 2.66783346 1.51546654 1 P 0 ;0,1,2=418,3=90.000000
L 2.66783346 1.51786644 2.66908327 1.51946663 1 P 0 ;0,1,2=418,3=90.000000
L 2.66908327 1.51946663 2.67116614 1.5208001 1 P 0 ;0,1,2=418,3=90.000000
L 2.67116614 1.5208001 2.67366634 1.52133337 1 P 0 ;0,1,2=418,3=90.000000
L 2.67366634 1.52133337 2.67616654 1.5208001 1 P 0 ;0,1,2=418,3=90.000000
L 2.67616654 1.5208001 2.67824941 1.51946663 1 P 0 ;0,1,2=418,3=90.000000
L 2.67824941 1.51946663 2.6795 1.51706663 1 P 0 ;0,1,2=418,3=90.000000
L 2.6795 1.51706663 2.67908337 1.51466663 1 P 0 ;0,1,2=418,3=90.000000
L 2.67908337 1.51466663 2.67741634 1.51226663 1 P 0 ;0,1,2=418,3=90.000000
L 2.65949961 1.53213327 2.65658287 1.53373297 1 P 0 ;0,1,2=418,3=90.000000
L 2.65658287 1.53373297 2.65491654 1.53586634 1 P 0 ;0,1,2=418,3=90.000000
L 2.65491654 1.53586634 2.6545 1.53826683 1 P 0 ;0,1,2=418,3=90.000000
L 2.6545 1.53826683 2.65491654 1.5404002 1 P 0 ;0,1,2=418,3=90.000000
L 2.65491654 1.5404002 2.65699941 1.54253356 1 P 0 ;0,1,2=418,3=90.000000
L 2.65699941 1.54253356 2.65949961 1.54386663 1 P 0 ;0,1,2=418,3=90.000000
L 2.65949961 1.54386663 2.6619999 1.54413317 1 P 0 ;0,1,2=418,3=90.000000
L 2.6619999 1.54413317 2.66491594 1.5436 1 P 0 ;0,1,2=418,3=90.000000
L 2.66491594 1.5436 2.66699961 1.54173327 1 P 0 ;0,1,2=418,3=90.000000
L 2.66699961 1.54173327 2.66783346 1.53986644 1 P 0 ;0,1,2=418,3=90.000000
L 2.66783346 1.53986644 2.66783346 1.53746654 1 P 0 ;0,1,2=418,3=90.000000
L 2.66783346 1.53986644 2.66908327 1.54146663 1 P 0 ;0,1,2=418,3=90.000000
L 2.66908327 1.54146663 2.67116614 1.5428001 1 P 0 ;0,1,2=418,3=90.000000
L 2.67116614 1.5428001 2.67366634 1.54333337 1 P 0 ;0,1,2=418,3=90.000000
L 2.67366634 1.54333337 2.67616654 1.5428001 1 P 0 ;0,1,2=418,3=90.000000
L 2.67616654 1.5428001 2.67824941 1.54146663 1 P 0 ;0,1,2=418,3=90.000000
L 2.67824941 1.54146663 2.6795 1.53906663 1 P 0 ;0,1,2=418,3=90.000000
L 2.6795 1.53906663 2.67908337 1.53666663 1 P 0 ;0,1,2=418,3=90.000000
L 2.67908337 1.53666663 2.67741634 1.53426663 1 P 0 ;0,1,2=418,3=90.000000
L 2.812 2.23 2.812 2.14 1 P 0 
L 2.768 2.23 2.812 2.23 1 P 0 
L 2.768 2.14 2.768 2.23 1 P 0 
L 2.812 2.14 2.768 2.14 1 P 0 
L 2.81291624 2.07743327 2.81446683 2.07513307 1 P 0 ;0,1,2=419,3=90.000000
L 2.81446683 2.07513307 2.8155 2.0724503 1 P 0 ;0,1,2=419,3=90.000000
L 2.8155 2.0724503 2.8155 2.06938356 1 P 0 ;0,1,2=419,3=90.000000
L 2.8155 2.06938356 2.81394931 2.06593287 1 P 0 ;0,1,2=419,3=90.000000
L 2.81394931 2.06593287 2.81136654 2.0632501 1 P 0 ;0,1,2=419,3=90.000000
L 2.81136654 2.0632501 2.80826624 2.06133317 1 P 0 ;0,1,2=419,3=90.000000
L 2.80826624 2.06133317 2.8030998 2.05979951 1 P 0 ;0,1,2=419,3=90.000000
L 2.8030998 2.05979951 2.7984498 2.05941624 1 P 0 ;0,1,2=419,3=90.000000
L 2.7984498 2.05941624 2.7937999 2.06018337 1 P 0 ;0,1,2=419,3=90.000000
L 2.7937999 2.06018337 2.79069961 2.06133317 1 P 0 ;0,1,2=419,3=90.000000
L 2.79069961 2.06133317 2.78759931 2.06363337 1 P 0 ;0,1,2=419,3=90.000000
L 2.78759931 2.06363337 2.78553307 2.06631683 1 P 0 ;0,1,2=419,3=90.000000
L 2.78553307 2.06631683 2.7845 2.06899961 1 P 0 ;0,1,2=419,3=90.000000
L 2.7845 2.06899961 2.7845 2.07168307 1 P 0 ;0,1,2=419,3=90.000000
L 2.7845 2.07168307 2.78553307 2.07436654 1 P 0 ;0,1,2=419,3=90.000000
L 2.78553307 2.07436654 2.78708278 2.07666673 1 P 0 ;0,1,2=419,3=90.000000
L 2.78708278 2.07666673 2.78914892 2.07858366 1 P 0 ;0,1,2=419,3=90.000000
L 2.7845 2.09923307 2.79121614 2.09999961 1 P 0 ;0,1,2=419,3=90.000000
L 2.79121614 2.09999961 2.79689921 2.1011501 1 P 0 ;0,1,2=419,3=90.000000
L 2.79689921 2.1011501 2.80206663 2.10268307 1 P 0 ;0,1,2=419,3=90.000000
L 2.80206663 2.10268307 2.8077497 2.1046 1 P 0 ;0,1,2=419,3=90.000000
L 2.8077497 2.1046 2.8155 2.10766673 1 P 0 ;0,1,2=419,3=90.000000
L 2.8155 2.10766673 2.8155 2.09233317 1 P 0 ;0,1,2=419,3=90.000000
L 2.7845 2.13099961 2.8155 2.13099961 1 P 0 ;0,1,2=419,3=90.000000
L 2.8155 2.13099961 2.8093003 2.1263999 1 P 0 ;0,1,2=419,3=90.000000
L 2.7845 2.1263999 2.7845 2.13559931 1 P 0 ;0,1,2=419,3=90.000000
L 2.833 2.91 2.877 2.91 1 P 0 
L 2.833 2.82 2.833 2.91 1 P 0 
L 2.877 2.91 2.877 2.82 1 P 0 
L 2.877 2.82 2.833 2.82 1 P 0 
L 2.89291624 2.99243327 2.89446683 2.99013307 1 P 0 ;0,1,2=420,3=90.000000
L 2.89446683 2.99013307 2.8955 2.9874503 1 P 0 ;0,1,2=420,3=90.000000
L 2.8955 2.9874503 2.8955 2.98438356 1 P 0 ;0,1,2=420,3=90.000000
L 2.8955 2.98438356 2.89394931 2.98093287 1 P 0 ;0,1,2=420,3=90.000000
L 2.89394931 2.98093287 2.89136654 2.9782501 1 P 0 ;0,1,2=420,3=90.000000
L 2.89136654 2.9782501 2.88826624 2.97633317 1 P 0 ;0,1,2=420,3=90.000000
L 2.88826624 2.97633317 2.8830998 2.97479951 1 P 0 ;0,1,2=420,3=90.000000
L 2.8830998 2.97479951 2.8784498 2.97441624 1 P 0 ;0,1,2=420,3=90.000000
L 2.8784498 2.97441624 2.8737999 2.97518337 1 P 0 ;0,1,2=420,3=90.000000
L 2.8737999 2.97518337 2.87069961 2.97633317 1 P 0 ;0,1,2=420,3=90.000000
L 2.87069961 2.97633317 2.86759931 2.97863337 1 P 0 ;0,1,2=420,3=90.000000
L 2.86759931 2.97863337 2.86553307 2.98131683 1 P 0 ;0,1,2=420,3=90.000000
L 2.86553307 2.98131683 2.8645 2.98399961 1 P 0 ;0,1,2=420,3=90.000000
L 2.8645 2.98399961 2.8645 2.98668307 1 P 0 ;0,1,2=420,3=90.000000
L 2.8645 2.98668307 2.86553307 2.98936654 1 P 0 ;0,1,2=420,3=90.000000
L 2.86553307 2.98936654 2.86708278 2.99166673 1 P 0 ;0,1,2=420,3=90.000000
L 2.86708278 2.99166673 2.86914892 2.99358366 1 P 0 ;0,1,2=420,3=90.000000
L 2.86914892 3.00656663 2.86656614 3.00886614 1 P 0 ;0,1,2=420,3=90.000000
L 2.86656614 3.00886614 2.86501654 3.01154961 1 P 0 ;0,1,2=420,3=90.000000
L 2.86501654 3.01154961 2.8645 3.01499961 1 P 0 ;0,1,2=420,3=90.000000
L 2.8645 3.01499961 2.86553307 3.0184503 1 P 0 ;0,1,2=420,3=90.000000
L 2.86553307 3.0184503 2.86759931 3.02113307 1 P 0 ;0,1,2=420,3=90.000000
L 2.86759931 3.02113307 2.87121614 3.02305 1 P 0 ;0,1,2=420,3=90.000000
L 2.87121614 3.02305 2.87534951 3.02343327 1 P 0 ;0,1,2=420,3=90.000000
L 2.87534951 3.02343327 2.87948287 3.02266673 1 P 0 ;0,1,2=420,3=90.000000
L 2.87948287 3.02266673 2.88206663 3.0207498 1 P 0 ;0,1,2=420,3=90.000000
L 2.88206663 3.0207498 2.88413287 3.01806634 1 P 0 ;0,1,2=420,3=90.000000
L 2.88413287 3.01806634 2.88464941 3.01538356 1 P 0 ;0,1,2=420,3=90.000000
L 2.88464941 3.01538356 2.88413287 3.0127001 1 P 0 ;0,1,2=420,3=90.000000
L 2.88413287 3.0127001 2.88206663 3.0092501 1 P 0 ;0,1,2=420,3=90.000000
L 2.88206663 3.0092501 2.8955 3.0103999 1 P 0 ;0,1,2=420,3=90.000000
L 2.8955 3.0103999 2.8955 3.0207498 1 P 0 ;0,1,2=420,3=90.000000
L 2.86811585 3.03948287 2.86553307 3.04216634 1 P 0 ;0,1,2=420,3=90.000000
L 2.86553307 3.04216634 2.8645 3.04523307 1 P 0 ;0,1,2=420,3=90.000000
L 2.8645 3.04523307 2.86553307 3.0482998 1 P 0 ;0,1,2=420,3=90.000000
L 2.86553307 3.0482998 2.86863238 3.05098327 1 P 0 ;0,1,2=420,3=90.000000
L 2.86863238 3.05098327 2.87328327 3.0529002 1 P 0 ;0,1,2=420,3=90.000000
L 2.87328327 3.0529002 2.87793327 3.05366673 1 P 0 ;0,1,2=420,3=90.000000
L 2.87793327 3.05366673 2.88361634 3.05366673 1 P 0 ;0,1,2=420,3=90.000000
L 2.88361634 3.05366673 2.88826624 3.0529002 1 P 0 ;0,1,2=420,3=90.000000
L 2.88826624 3.0529002 2.8923997 3.05098327 1 P 0 ;0,1,2=420,3=90.000000
L 2.8923997 3.05098327 2.89446683 3.04868307 1 P 0 ;0,1,2=420,3=90.000000
L 2.89446683 3.04868307 2.8955 3.04599961 1 P 0 ;0,1,2=420,3=90.000000
L 2.8955 3.04599961 2.89446683 3.04293287 1 P 0 ;0,1,2=420,3=90.000000
L 2.89446683 3.04293287 2.8923997 3.04063337 1 P 0 ;0,1,2=420,3=90.000000
L 2.8923997 3.04063337 2.8893003 3.0390997 1 P 0 ;0,1,2=420,3=90.000000
L 2.8893003 3.0390997 2.88516594 3.03833317 1 P 0 ;0,1,2=420,3=90.000000
L 2.88516594 3.03833317 2.8815501 3.0390997 1 P 0 ;0,1,2=420,3=90.000000
L 2.8815501 3.0390997 2.87793327 3.04101663 1 P 0 ;0,1,2=420,3=90.000000
L 2.87793327 3.04101663 2.87586604 3.04331683 1 P 0 ;0,1,2=420,3=90.000000
L 2.87586604 3.04331683 2.87534951 3.04599961 1 P 0 ;0,1,2=420,3=90.000000
L 2.87534951 3.04599961 2.87638268 3.04906634 1 P 0 ;0,1,2=420,3=90.000000
L 2.87638268 3.04906634 2.87896634 3.05136654 1 P 0 ;0,1,2=420,3=90.000000
L 2.87896634 3.05136654 2.88361634 3.05366673 1 P 0 ;0,1,2=420,3=90.000000
L 2.812 2.362 2.812 2.272 1 P 0 
L 2.768 2.362 2.812 2.362 1 P 0 
L 2.812 2.272 2.768 2.272 1 P 0 
L 2.768 2.272 2.768 2.362 1 P 0 
L 3.10791624 2.39743327 3.10946683 2.39513307 1 P 0 ;0,1,2=421,3=90.000000
L 3.10946683 2.39513307 3.1105 2.3924503 1 P 0 ;0,1,2=421,3=90.000000
L 3.1105 2.3924503 3.1105 2.38938356 1 P 0 ;0,1,2=421,3=90.000000
L 3.1105 2.38938356 3.10894931 2.38593287 1 P 0 ;0,1,2=421,3=90.000000
L 3.10894931 2.38593287 3.10636654 2.3832501 1 P 0 ;0,1,2=421,3=90.000000
L 3.10636654 2.3832501 3.10326624 2.38133317 1 P 0 ;0,1,2=421,3=90.000000
L 3.10326624 2.38133317 3.0980998 2.37979951 1 P 0 ;0,1,2=421,3=90.000000
L 3.0980998 2.37979951 3.0934498 2.37941624 1 P 0 ;0,1,2=421,3=90.000000
L 3.0934498 2.37941624 3.0887999 2.38018337 1 P 0 ;0,1,2=421,3=90.000000
L 3.0887999 2.38018337 3.08569961 2.38133317 1 P 0 ;0,1,2=421,3=90.000000
L 3.08569961 2.38133317 3.08259931 2.38363337 1 P 0 ;0,1,2=421,3=90.000000
L 3.08259931 2.38363337 3.08053307 2.38631683 1 P 0 ;0,1,2=421,3=90.000000
L 3.08053307 2.38631683 3.0795 2.38899961 1 P 0 ;0,1,2=421,3=90.000000
L 3.0795 2.38899961 3.0795 2.39168307 1 P 0 ;0,1,2=421,3=90.000000
L 3.0795 2.39168307 3.08053307 2.39436654 1 P 0 ;0,1,2=421,3=90.000000
L 3.08053307 2.39436654 3.08208278 2.39666673 1 P 0 ;0,1,2=421,3=90.000000
L 3.08208278 2.39666673 3.08414892 2.39858366 1 P 0 ;0,1,2=421,3=90.000000
L 3.0795 2.41923307 3.08621614 2.41999961 1 P 0 ;0,1,2=421,3=90.000000
L 3.08621614 2.41999961 3.09189921 2.4211501 1 P 0 ;0,1,2=421,3=90.000000
L 3.09189921 2.4211501 3.09706663 2.42268307 1 P 0 ;0,1,2=421,3=90.000000
L 3.09706663 2.42268307 3.1027497 2.4246 1 P 0 ;0,1,2=421,3=90.000000
L 3.1027497 2.4246 3.1105 2.42766673 1 P 0 ;0,1,2=421,3=90.000000
L 3.1105 2.42766673 3.1105 2.41233317 1 P 0 ;0,1,2=421,3=90.000000
L 3.1105 2.45099961 3.10946683 2.44793287 1 P 0 ;0,1,2=421,3=90.000000
L 3.10946683 2.44793287 3.10688307 2.44563337 1 P 0 ;0,1,2=421,3=90.000000
L 3.10688307 2.44563337 3.10378376 2.4440997 1 P 0 ;0,1,2=421,3=90.000000
L 3.10378376 2.4440997 3.09964941 2.4429499 1 P 0 ;0,1,2=421,3=90.000000
L 3.09964941 2.4429499 3.09499951 2.44256663 1 P 0 ;0,1,2=421,3=90.000000
L 3.09499951 2.44256663 3.09034951 2.4429499 1 P 0 ;0,1,2=421,3=90.000000
L 3.09034951 2.4429499 3.08621614 2.4440997 1 P 0 ;0,1,2=421,3=90.000000
L 3.08621614 2.4440997 3.08311585 2.44563337 1 P 0 ;0,1,2=421,3=90.000000
L 3.08311585 2.44563337 3.08053307 2.44793287 1 P 0 ;0,1,2=421,3=90.000000
L 3.08053307 2.44793287 3.0795 2.45099961 1 P 0 ;0,1,2=421,3=90.000000
L 3.0795 2.45099961 3.08053307 2.45406634 1 P 0 ;0,1,2=421,3=90.000000
L 3.08053307 2.45406634 3.08311585 2.45636654 1 P 0 ;0,1,2=421,3=90.000000
L 3.08311585 2.45636654 3.08621614 2.4579002 1 P 0 ;0,1,2=421,3=90.000000
L 3.08621614 2.4579002 3.09034951 2.45905 1 P 0 ;0,1,2=421,3=90.000000
L 3.09034951 2.45905 3.09499951 2.45943327 1 P 0 ;0,1,2=421,3=90.000000
L 3.09499951 2.45943327 3.09964941 2.45905 1 P 0 ;0,1,2=421,3=90.000000
L 3.09964941 2.45905 3.10378376 2.4579002 1 P 0 ;0,1,2=421,3=90.000000
L 3.10378376 2.4579002 3.10688307 2.45636654 1 P 0 ;0,1,2=421,3=90.000000
L 3.10688307 2.45636654 3.10946683 2.45406634 1 P 0 ;0,1,2=421,3=90.000000
L 3.10946683 2.45406634 3.1105 2.45099961 1 P 0 ;0,1,2=421,3=90.000000
L 2.612 2.33 2.612 2.24 1 P 0 
L 2.568 2.33 2.612 2.33 1 P 0 
L 2.612 2.24 2.568 2.24 1 P 0 
L 2.568 2.24 2.568 2.33 1 P 0 
L 2.60291624 2.15243327 2.60446683 2.15013307 1 P 0 ;0,1,2=422,3=90.000000
L 2.60446683 2.15013307 2.6055 2.1474503 1 P 0 ;0,1,2=422,3=90.000000
L 2.6055 2.1474503 2.6055 2.14438356 1 P 0 ;0,1,2=422,3=90.000000
L 2.6055 2.14438356 2.60394931 2.14093287 1 P 0 ;0,1,2=422,3=90.000000
L 2.60394931 2.14093287 2.60136654 2.1382501 1 P 0 ;0,1,2=422,3=90.000000
L 2.60136654 2.1382501 2.59826624 2.13633317 1 P 0 ;0,1,2=422,3=90.000000
L 2.59826624 2.13633317 2.5930998 2.13479951 1 P 0 ;0,1,2=422,3=90.000000
L 2.5930998 2.13479951 2.5884498 2.13441624 1 P 0 ;0,1,2=422,3=90.000000
L 2.5884498 2.13441624 2.5837999 2.13518337 1 P 0 ;0,1,2=422,3=90.000000
L 2.5837999 2.13518337 2.58069961 2.13633317 1 P 0 ;0,1,2=422,3=90.000000
L 2.58069961 2.13633317 2.57759931 2.13863337 1 P 0 ;0,1,2=422,3=90.000000
L 2.57759931 2.13863337 2.57553307 2.14131683 1 P 0 ;0,1,2=422,3=90.000000
L 2.57553307 2.14131683 2.5745 2.14399961 1 P 0 ;0,1,2=422,3=90.000000
L 2.5745 2.14399961 2.5745 2.14668307 1 P 0 ;0,1,2=422,3=90.000000
L 2.5745 2.14668307 2.57553307 2.14936654 1 P 0 ;0,1,2=422,3=90.000000
L 2.57553307 2.14936654 2.57708278 2.15166673 1 P 0 ;0,1,2=422,3=90.000000
L 2.57708278 2.15166673 2.57914892 2.15358366 1 P 0 ;0,1,2=422,3=90.000000
L 2.58741575 2.16771644 2.59103356 2.1703999 1 P 0 ;0,1,2=422,3=90.000000
L 2.59103356 2.1703999 2.5930998 2.1727001 1 P 0 ;0,1,2=422,3=90.000000
L 2.5930998 2.1727001 2.59413287 2.17576683 1 P 0 ;0,1,2=422,3=90.000000
L 2.59413287 2.17576683 2.5930998 2.1784503 1 P 0 ;0,1,2=422,3=90.000000
L 2.5930998 2.1784503 2.59103356 2.18036654 1 P 0 ;0,1,2=422,3=90.000000
L 2.59103356 2.18036654 2.58793327 2.1819002 1 P 0 ;0,1,2=422,3=90.000000
L 2.58793327 2.1819002 2.58431644 2.18228346 1 P 0 ;0,1,2=422,3=90.000000
L 2.58431644 2.18228346 2.58121614 2.1819002 1 P 0 ;0,1,2=422,3=90.000000
L 2.58121614 2.1819002 2.57811585 2.18036654 1 P 0 ;0,1,2=422,3=90.000000
L 2.57811585 2.18036654 2.57553307 2.17806634 1 P 0 ;0,1,2=422,3=90.000000
L 2.57553307 2.17806634 2.5745 2.17538356 1 P 0 ;0,1,2=422,3=90.000000
L 2.5745 2.17538356 2.57553307 2.17231683 1 P 0 ;0,1,2=422,3=90.000000
L 2.57553307 2.17231683 2.57863238 2.16963337 1 P 0 ;0,1,2=422,3=90.000000
L 2.57863238 2.16963337 2.58328327 2.1680997 1 P 0 ;0,1,2=422,3=90.000000
L 2.58328327 2.1680997 2.5884498 2.16771644 1 P 0 ;0,1,2=422,3=90.000000
L 2.5884498 2.16771644 2.59516594 2.16848287 1 P 0 ;0,1,2=422,3=90.000000
L 2.59516594 2.16848287 2.59878376 2.16963337 1 P 0 ;0,1,2=422,3=90.000000
L 2.59878376 2.16963337 2.6023997 2.17154961 1 P 0 ;0,1,2=422,3=90.000000
L 2.6023997 2.17154961 2.60498337 2.17423307 1 P 0 ;0,1,2=422,3=90.000000
L 2.60498337 2.17423307 2.6055 2.17691654 1 P 0 ;0,1,2=422,3=90.000000
L 2.6055 2.17691654 2.60446683 2.1796 1 P 0 ;0,1,2=422,3=90.000000
L 2.60446683 2.1796 2.60188307 2.18151703 1 P 0 ;0,1,2=422,3=90.000000
L 2.57811585 2.19948287 2.57553307 2.20216634 1 P 0 ;0,1,2=422,3=90.000000
L 2.57553307 2.20216634 2.5745 2.20523307 1 P 0 ;0,1,2=422,3=90.000000
L 2.5745 2.20523307 2.57553307 2.2082998 1 P 0 ;0,1,2=422,3=90.000000
L 2.57553307 2.2082998 2.57863238 2.21098327 1 P 0 ;0,1,2=422,3=90.000000
L 2.57863238 2.21098327 2.58328327 2.2129002 1 P 0 ;0,1,2=422,3=90.000000
L 2.58328327 2.2129002 2.58793327 2.21366673 1 P 0 ;0,1,2=422,3=90.000000
L 2.58793327 2.21366673 2.59361634 2.21366673 1 P 0 ;0,1,2=422,3=90.000000
L 2.59361634 2.21366673 2.59826624 2.2129002 1 P 0 ;0,1,2=422,3=90.000000
L 2.59826624 2.2129002 2.6023997 2.21098327 1 P 0 ;0,1,2=422,3=90.000000
L 2.6023997 2.21098327 2.60446683 2.20868307 1 P 0 ;0,1,2=422,3=90.000000
L 2.60446683 2.20868307 2.6055 2.20599961 1 P 0 ;0,1,2=422,3=90.000000
L 2.6055 2.20599961 2.60446683 2.20293287 1 P 0 ;0,1,2=422,3=90.000000
L 2.60446683 2.20293287 2.6023997 2.20063337 1 P 0 ;0,1,2=422,3=90.000000
L 2.6023997 2.20063337 2.5993003 2.1990997 1 P 0 ;0,1,2=422,3=90.000000
L 2.5993003 2.1990997 2.59516594 2.19833317 1 P 0 ;0,1,2=422,3=90.000000
L 2.59516594 2.19833317 2.5915501 2.1990997 1 P 0 ;0,1,2=422,3=90.000000
L 2.5915501 2.1990997 2.58793327 2.20101663 1 P 0 ;0,1,2=422,3=90.000000
L 2.58793327 2.20101663 2.58586604 2.20331683 1 P 0 ;0,1,2=422,3=90.000000
L 2.58586604 2.20331683 2.58534951 2.20599961 1 P 0 ;0,1,2=422,3=90.000000
L 2.58534951 2.20599961 2.58638268 2.20906634 1 P 0 ;0,1,2=422,3=90.000000
L 2.58638268 2.20906634 2.58896634 2.21136654 1 P 0 ;0,1,2=422,3=90.000000
L 2.58896634 2.21136654 2.59361634 2.21366673 1 P 0 ;0,1,2=422,3=90.000000
L 3.223 2.925 3.267 2.925 1 P 0 
L 3.267 2.925 3.267 2.835 1 P 0 
L 3.267 2.835 3.223 2.835 1 P 0 
L 3.223 2.835 3.223 2.925 1 P 0 
L 3.30791624 2.83743327 3.30946683 2.83513307 1 P 0 ;0,1,2=423,3=90.000000
L 3.30946683 2.83513307 3.3105 2.8324503 1 P 0 ;0,1,2=423,3=90.000000
L 3.3105 2.8324503 3.3105 2.82938356 1 P 0 ;0,1,2=423,3=90.000000
L 3.3105 2.82938356 3.30894931 2.82593287 1 P 0 ;0,1,2=423,3=90.000000
L 3.30894931 2.82593287 3.30636654 2.8232501 1 P 0 ;0,1,2=423,3=90.000000
L 3.30636654 2.8232501 3.30326624 2.82133317 1 P 0 ;0,1,2=423,3=90.000000
L 3.30326624 2.82133317 3.2980998 2.81979951 1 P 0 ;0,1,2=423,3=90.000000
L 3.2980998 2.81979951 3.2934498 2.81941624 1 P 0 ;0,1,2=423,3=90.000000
L 3.2934498 2.81941624 3.2887999 2.82018337 1 P 0 ;0,1,2=423,3=90.000000
L 3.2887999 2.82018337 3.28569961 2.82133317 1 P 0 ;0,1,2=423,3=90.000000
L 3.28569961 2.82133317 3.28259931 2.82363337 1 P 0 ;0,1,2=423,3=90.000000
L 3.28259931 2.82363337 3.28053307 2.82631683 1 P 0 ;0,1,2=423,3=90.000000
L 3.28053307 2.82631683 3.2795 2.82899961 1 P 0 ;0,1,2=423,3=90.000000
L 3.2795 2.82899961 3.2795 2.83168307 1 P 0 ;0,1,2=423,3=90.000000
L 3.2795 2.83168307 3.28053307 2.83436654 1 P 0 ;0,1,2=423,3=90.000000
L 3.28053307 2.83436654 3.28208278 2.83666673 1 P 0 ;0,1,2=423,3=90.000000
L 3.28208278 2.83666673 3.28414892 2.83858366 1 P 0 ;0,1,2=423,3=90.000000
L 3.29241575 2.85271644 3.29603356 2.8553999 1 P 0 ;0,1,2=423,3=90.000000
L 3.29603356 2.8553999 3.2980998 2.8577001 1 P 0 ;0,1,2=423,3=90.000000
L 3.2980998 2.8577001 3.29913287 2.86076683 1 P 0 ;0,1,2=423,3=90.000000
L 3.29913287 2.86076683 3.2980998 2.8634503 1 P 0 ;0,1,2=423,3=90.000000
L 3.2980998 2.8634503 3.29603356 2.86536654 1 P 0 ;0,1,2=423,3=90.000000
L 3.29603356 2.86536654 3.29293327 2.8669002 1 P 0 ;0,1,2=423,3=90.000000
L 3.29293327 2.8669002 3.28931644 2.86728346 1 P 0 ;0,1,2=423,3=90.000000
L 3.28931644 2.86728346 3.28621614 2.8669002 1 P 0 ;0,1,2=423,3=90.000000
L 3.28621614 2.8669002 3.28311585 2.86536654 1 P 0 ;0,1,2=423,3=90.000000
L 3.28311585 2.86536654 3.28053307 2.86306634 1 P 0 ;0,1,2=423,3=90.000000
L 3.28053307 2.86306634 3.2795 2.86038356 1 P 0 ;0,1,2=423,3=90.000000
L 3.2795 2.86038356 3.28053307 2.85731683 1 P 0 ;0,1,2=423,3=90.000000
L 3.28053307 2.85731683 3.28363238 2.85463337 1 P 0 ;0,1,2=423,3=90.000000
L 3.28363238 2.85463337 3.28828327 2.8530997 1 P 0 ;0,1,2=423,3=90.000000
L 3.28828327 2.8530997 3.2934498 2.85271644 1 P 0 ;0,1,2=423,3=90.000000
L 3.2934498 2.85271644 3.30016594 2.85348287 1 P 0 ;0,1,2=423,3=90.000000
L 3.30016594 2.85348287 3.30378376 2.85463337 1 P 0 ;0,1,2=423,3=90.000000
L 3.30378376 2.85463337 3.3073997 2.85654961 1 P 0 ;0,1,2=423,3=90.000000
L 3.3073997 2.85654961 3.30998337 2.85923307 1 P 0 ;0,1,2=423,3=90.000000
L 3.30998337 2.85923307 3.3105 2.86191654 1 P 0 ;0,1,2=423,3=90.000000
L 3.3105 2.86191654 3.30946683 2.8646 1 P 0 ;0,1,2=423,3=90.000000
L 3.30946683 2.8646 3.30688307 2.86651703 1 P 0 ;0,1,2=423,3=90.000000
L 3.30533346 2.88371644 3.30843278 2.88601663 1 P 0 ;0,1,2=423,3=90.000000
L 3.30843278 2.88601663 3.30998337 2.8887001 1 P 0 ;0,1,2=423,3=90.000000
L 3.30998337 2.8887001 3.3105 2.89176683 1 P 0 ;0,1,2=423,3=90.000000
L 3.3105 2.89176683 3.30946683 2.8956 1 P 0 ;0,1,2=423,3=90.000000
L 3.30946683 2.8956 3.30688307 2.89828346 1 P 0 ;0,1,2=423,3=90.000000
L 3.30688307 2.89828346 3.30378376 2.89905 1 P 0 ;0,1,2=423,3=90.000000
L 3.30378376 2.89905 3.30068258 2.89866673 1 P 0 ;0,1,2=423,3=90.000000
L 3.30068258 2.89866673 3.2980998 2.89713307 1 P 0 ;0,1,2=423,3=90.000000
L 3.2980998 2.89713307 3.29293327 2.88946663 1 P 0 ;0,1,2=423,3=90.000000
L 3.29293327 2.88946663 3.28931644 2.88601663 1 P 0 ;0,1,2=423,3=90.000000
L 3.28931644 2.88601663 3.28414892 2.88371644 1 P 0 ;0,1,2=423,3=90.000000
L 3.28414892 2.88371644 3.2795 2.8829499 1 P 0 ;0,1,2=423,3=90.000000
L 3.2795 2.8829499 3.2795 2.89905 1 P 0 ;0,1,2=423,3=90.000000
L 2.878 2.91 2.922 2.91 1 P 0 
L 2.878 2.82 2.878 2.91 1 P 0 
L 2.922 2.91 2.922 2.82 1 P 0 
L 2.922 2.82 2.878 2.82 1 P 0 
L 2.93791624 2.99243327 2.93946683 2.99013307 1 P 0 ;0,1,2=424,3=90.000000
L 2.93946683 2.99013307 2.9405 2.9874503 1 P 0 ;0,1,2=424,3=90.000000
L 2.9405 2.9874503 2.9405 2.98438356 1 P 0 ;0,1,2=424,3=90.000000
L 2.9405 2.98438356 2.93894931 2.98093287 1 P 0 ;0,1,2=424,3=90.000000
L 2.93894931 2.98093287 2.93636654 2.9782501 1 P 0 ;0,1,2=424,3=90.000000
L 2.93636654 2.9782501 2.93326624 2.97633317 1 P 0 ;0,1,2=424,3=90.000000
L 2.93326624 2.97633317 2.9280998 2.97479951 1 P 0 ;0,1,2=424,3=90.000000
L 2.9280998 2.97479951 2.9234498 2.97441624 1 P 0 ;0,1,2=424,3=90.000000
L 2.9234498 2.97441624 2.9187999 2.97518337 1 P 0 ;0,1,2=424,3=90.000000
L 2.9187999 2.97518337 2.91569961 2.97633317 1 P 0 ;0,1,2=424,3=90.000000
L 2.91569961 2.97633317 2.91259931 2.97863337 1 P 0 ;0,1,2=424,3=90.000000
L 2.91259931 2.97863337 2.91053307 2.98131683 1 P 0 ;0,1,2=424,3=90.000000
L 2.91053307 2.98131683 2.9095 2.98399961 1 P 0 ;0,1,2=424,3=90.000000
L 2.9095 2.98399961 2.9095 2.98668307 1 P 0 ;0,1,2=424,3=90.000000
L 2.9095 2.98668307 2.91053307 2.98936654 1 P 0 ;0,1,2=424,3=90.000000
L 2.91053307 2.98936654 2.91208278 2.99166673 1 P 0 ;0,1,2=424,3=90.000000
L 2.91208278 2.99166673 2.91414892 2.99358366 1 P 0 ;0,1,2=424,3=90.000000
L 2.92241575 3.00771644 2.92603356 3.0103999 1 P 0 ;0,1,2=424,3=90.000000
L 2.92603356 3.0103999 2.9280998 3.0127001 1 P 0 ;0,1,2=424,3=90.000000
L 2.9280998 3.0127001 2.92913287 3.01576683 1 P 0 ;0,1,2=424,3=90.000000
L 2.92913287 3.01576683 2.9280998 3.0184503 1 P 0 ;0,1,2=424,3=90.000000
L 2.9280998 3.0184503 2.92603356 3.02036654 1 P 0 ;0,1,2=424,3=90.000000
L 2.92603356 3.02036654 2.92293327 3.0219002 1 P 0 ;0,1,2=424,3=90.000000
L 2.92293327 3.0219002 2.91931644 3.02228346 1 P 0 ;0,1,2=424,3=90.000000
L 2.91931644 3.02228346 2.91621614 3.0219002 1 P 0 ;0,1,2=424,3=90.000000
L 2.91621614 3.0219002 2.91311585 3.02036654 1 P 0 ;0,1,2=424,3=90.000000
L 2.91311585 3.02036654 2.91053307 3.01806634 1 P 0 ;0,1,2=424,3=90.000000
L 2.91053307 3.01806634 2.9095 3.01538356 1 P 0 ;0,1,2=424,3=90.000000
L 2.9095 3.01538356 2.91053307 3.01231683 1 P 0 ;0,1,2=424,3=90.000000
L 2.91053307 3.01231683 2.91363238 3.00963337 1 P 0 ;0,1,2=424,3=90.000000
L 2.91363238 3.00963337 2.91828327 3.0080997 1 P 0 ;0,1,2=424,3=90.000000
L 2.91828327 3.0080997 2.9234498 3.00771644 1 P 0 ;0,1,2=424,3=90.000000
L 2.9234498 3.00771644 2.93016594 3.00848287 1 P 0 ;0,1,2=424,3=90.000000
L 2.93016594 3.00848287 2.93378376 3.00963337 1 P 0 ;0,1,2=424,3=90.000000
L 2.93378376 3.00963337 2.9373997 3.01154961 1 P 0 ;0,1,2=424,3=90.000000
L 2.9373997 3.01154961 2.93998337 3.01423307 1 P 0 ;0,1,2=424,3=90.000000
L 2.93998337 3.01423307 2.9405 3.01691654 1 P 0 ;0,1,2=424,3=90.000000
L 2.9405 3.01691654 2.93946683 3.0196 1 P 0 ;0,1,2=424,3=90.000000
L 2.93946683 3.0196 2.93688307 3.02151703 1 P 0 ;0,1,2=424,3=90.000000
L 2.9405 3.04599961 2.93946683 3.04293287 1 P 0 ;0,1,2=424,3=90.000000
L 2.93946683 3.04293287 2.93688307 3.04063337 1 P 0 ;0,1,2=424,3=90.000000
L 2.93688307 3.04063337 2.93378376 3.0390997 1 P 0 ;0,1,2=424,3=90.000000
L 2.93378376 3.0390997 2.92964941 3.0379499 1 P 0 ;0,1,2=424,3=90.000000
L 2.92964941 3.0379499 2.92499951 3.03756663 1 P 0 ;0,1,2=424,3=90.000000
L 2.92499951 3.03756663 2.92034951 3.0379499 1 P 0 ;0,1,2=424,3=90.000000
L 2.92034951 3.0379499 2.91621614 3.0390997 1 P 0 ;0,1,2=424,3=90.000000
L 2.91621614 3.0390997 2.91311585 3.04063337 1 P 0 ;0,1,2=424,3=90.000000
L 2.91311585 3.04063337 2.91053307 3.04293287 1 P 0 ;0,1,2=424,3=90.000000
L 2.91053307 3.04293287 2.9095 3.04599961 1 P 0 ;0,1,2=424,3=90.000000
L 2.9095 3.04599961 2.91053307 3.04906634 1 P 0 ;0,1,2=424,3=90.000000
L 2.91053307 3.04906634 2.91311585 3.05136654 1 P 0 ;0,1,2=424,3=90.000000
L 2.91311585 3.05136654 2.91621614 3.0529002 1 P 0 ;0,1,2=424,3=90.000000
L 2.91621614 3.0529002 2.92034951 3.05405 1 P 0 ;0,1,2=424,3=90.000000
L 2.92034951 3.05405 2.92499951 3.05443327 1 P 0 ;0,1,2=424,3=90.000000
L 2.92499951 3.05443327 2.92964941 3.05405 1 P 0 ;0,1,2=424,3=90.000000
L 2.92964941 3.05405 2.93378376 3.0529002 1 P 0 ;0,1,2=424,3=90.000000
L 2.93378376 3.0529002 2.93688307 3.05136654 1 P 0 ;0,1,2=424,3=90.000000
L 2.93688307 3.05136654 2.93946683 3.04906634 1 P 0 ;0,1,2=424,3=90.000000
L 2.93946683 3.04906634 2.9405 3.04599961 1 P 0 ;0,1,2=424,3=90.000000
L 2.485 2.377 2.485 2.333 1 P 0 
L 2.485 2.333 2.395 2.333 1 P 0 
L 2.395 2.333 2.395 2.377 1 P 0 
L 2.395 2.377 2.485 2.377 1 P 0 
L 2.36256673 2.36791624 2.36486693 2.36946683 1 P 0 ;0,1,2=425,3=0.000000
L 2.36486693 2.36946683 2.3675497 2.3705 1 P 0 ;0,1,2=425,3=0.000000
L 2.3675497 2.3705 2.37061644 2.3705 1 P 0 ;0,1,2=425,3=0.000000
L 2.37061644 2.3705 2.37406713 2.36894931 1 P 0 ;0,1,2=425,3=0.000000
L 2.37406713 2.36894931 2.3767499 2.36636654 1 P 0 ;0,1,2=425,3=0.000000
L 2.3767499 2.36636654 2.37866683 2.36326624 1 P 0 ;0,1,2=425,3=0.000000
L 2.37866683 2.36326624 2.38020049 2.3580998 1 P 0 ;0,1,2=425,3=0.000000
L 2.38020049 2.3580998 2.38058376 2.3534498 1 P 0 ;0,1,2=425,3=0.000000
L 2.38058376 2.3534498 2.37981663 2.3487999 1 P 0 ;0,1,2=425,3=0.000000
L 2.37981663 2.3487999 2.37866683 2.34569961 1 P 0 ;0,1,2=425,3=0.000000
L 2.37866683 2.34569961 2.37636663 2.34259931 1 P 0 ;0,1,2=425,3=0.000000
L 2.37636663 2.34259931 2.37368317 2.34053307 1 P 0 ;0,1,2=425,3=0.000000
L 2.37368317 2.34053307 2.37100039 2.3395 1 P 0 ;0,1,2=425,3=0.000000
L 2.37100039 2.3395 2.36831693 2.3395 1 P 0 ;0,1,2=425,3=0.000000
L 2.36831693 2.3395 2.36563346 2.34053307 1 P 0 ;0,1,2=425,3=0.000000
L 2.36563346 2.34053307 2.36333327 2.34208278 1 P 0 ;0,1,2=425,3=0.000000
L 2.36333327 2.34208278 2.36141634 2.34414892 1 P 0 ;0,1,2=425,3=0.000000
L 2.34728356 2.35241575 2.3446001 2.35603356 1 P 0 ;0,1,2=425,3=0.000000
L 2.3446001 2.35603356 2.3422999 2.3580998 1 P 0 ;0,1,2=425,3=0.000000
L 2.3422999 2.3580998 2.33923317 2.35913287 1 P 0 ;0,1,2=425,3=0.000000
L 2.33923317 2.35913287 2.3365497 2.3580998 1 P 0 ;0,1,2=425,3=0.000000
L 2.3365497 2.3580998 2.33463346 2.35603356 1 P 0 ;0,1,2=425,3=0.000000
L 2.33463346 2.35603356 2.3330998 2.35293327 1 P 0 ;0,1,2=425,3=0.000000
L 2.3330998 2.35293327 2.33271654 2.34931644 1 P 0 ;0,1,2=425,3=0.000000
L 2.33271654 2.34931644 2.3330998 2.34621614 1 P 0 ;0,1,2=425,3=0.000000
L 2.3330998 2.34621614 2.33463346 2.34311585 1 P 0 ;0,1,2=425,3=0.000000
L 2.33463346 2.34311585 2.33693366 2.34053307 1 P 0 ;0,1,2=425,3=0.000000
L 2.33693366 2.34053307 2.33961644 2.3395 1 P 0 ;0,1,2=425,3=0.000000
L 2.33961644 2.3395 2.34268317 2.34053307 1 P 0 ;0,1,2=425,3=0.000000
L 2.34268317 2.34053307 2.34536663 2.34363238 1 P 0 ;0,1,2=425,3=0.000000
L 2.34536663 2.34363238 2.3469003 2.34828327 1 P 0 ;0,1,2=425,3=0.000000
L 2.3469003 2.34828327 2.34728356 2.3534498 1 P 0 ;0,1,2=425,3=0.000000
L 2.34728356 2.3534498 2.34651713 2.36016594 1 P 0 ;0,1,2=425,3=0.000000
L 2.34651713 2.36016594 2.34536663 2.36378376 1 P 0 ;0,1,2=425,3=0.000000
L 2.34536663 2.36378376 2.34345039 2.3673997 1 P 0 ;0,1,2=425,3=0.000000
L 2.34345039 2.3673997 2.34076693 2.36998337 1 P 0 ;0,1,2=425,3=0.000000
L 2.34076693 2.36998337 2.33808346 2.3705 1 P 0 ;0,1,2=425,3=0.000000
L 2.33808346 2.3705 2.3354 2.36946683 1 P 0 ;0,1,2=425,3=0.000000
L 2.3354 2.36946683 2.33348297 2.36688307 1 P 0 ;0,1,2=425,3=0.000000
L 2.30900039 2.3395 2.30631693 2.34001654 1 P 0 ;0,1,2=425,3=0.000000
L 2.30631693 2.34001654 2.3032502 2.34156614 1 P 0 ;0,1,2=425,3=0.000000
L 2.3032502 2.34156614 2.30133327 2.34414892 1 P 0 ;0,1,2=425,3=0.000000
L 2.30133327 2.34414892 2.30056673 2.34776673 1 P 0 ;0,1,2=425,3=0.000000
L 2.30056673 2.34776673 2.30133327 2.35138268 1 P 0 ;0,1,2=425,3=0.000000
L 2.30133327 2.35138268 2.30363346 2.35448287 1 P 0 ;0,1,2=425,3=0.000000
L 2.30363346 2.35448287 2.30708346 2.35603356 1 P 0 ;0,1,2=425,3=0.000000
L 2.30708346 2.35603356 2.31091663 2.35603356 1 P 0 ;0,1,2=425,3=0.000000
L 2.31091663 2.35603356 2.31321683 2.35706663 1 P 0 ;0,1,2=425,3=0.000000
L 2.31321683 2.35706663 2.31513386 2.35964941 1 P 0 ;0,1,2=425,3=0.000000
L 2.31513386 2.35964941 2.3159003 2.36326624 1 P 0 ;0,1,2=425,3=0.000000
L 2.3159003 2.36326624 2.3147499 2.36688307 1 P 0 ;0,1,2=425,3=0.000000
L 2.3147499 2.36688307 2.31206713 2.36946683 1 P 0 ;0,1,2=425,3=0.000000
L 2.31206713 2.36946683 2.30900039 2.3705 1 P 0 ;0,1,2=425,3=0.000000
L 2.30900039 2.3705 2.30593366 2.36946683 1 P 0 ;0,1,2=425,3=0.000000
L 2.30593366 2.36946683 2.3032502 2.36688307 1 P 0 ;0,1,2=425,3=0.000000
L 2.3032502 2.36688307 2.3020998 2.36326624 1 P 0 ;0,1,2=425,3=0.000000
L 2.3020998 2.36326624 2.30286693 2.35964941 1 P 0 ;0,1,2=425,3=0.000000
L 2.30286693 2.35964941 2.30478327 2.35706663 1 P 0 ;0,1,2=425,3=0.000000
L 2.30478327 2.35706663 2.30708346 2.35603356 1 P 0 ;0,1,2=425,3=0.000000
L 2.30708346 2.35603356 2.31091663 2.35603356 1 P 0 ;0,1,2=425,3=0.000000
L 2.31091663 2.35603356 2.31436663 2.35448287 1 P 0 ;0,1,2=425,3=0.000000
L 2.31436663 2.35448287 2.31666683 2.35138268 1 P 0 ;0,1,2=425,3=0.000000
L 2.31666683 2.35138268 2.31743337 2.34776673 1 P 0 ;0,1,2=425,3=0.000000
L 2.31743337 2.34776673 2.31666683 2.34414892 1 P 0 ;0,1,2=425,3=0.000000
L 2.31666683 2.34414892 2.3147499 2.34156614 1 P 0 ;0,1,2=425,3=0.000000
L 2.3147499 2.34156614 2.31168317 2.34001654 1 P 0 ;0,1,2=425,3=0.000000
L 2.31168317 2.34001654 2.30900039 2.3395 1 P 0 ;0,1,2=425,3=0.000000
L 5.803 0.82 5.847 0.82 1 P 0 
L 5.803 0.73 5.803 0.82 1 P 0 
L 5.847 0.82 5.847 0.73 1 P 0 
L 5.847 0.73 5.803 0.73 1 P 0 
L 5.83791624 0.84693327 5.83946683 0.84463307 1 P 0 ;0,1,2=426,3=90.000000
L 5.83946683 0.84463307 5.8405 0.8419503 1 P 0 ;0,1,2=426,3=90.000000
L 5.8405 0.8419503 5.8405 0.83888356 1 P 0 ;0,1,2=426,3=90.000000
L 5.8405 0.83888356 5.83894931 0.83543287 1 P 0 ;0,1,2=426,3=90.000000
L 5.83894931 0.83543287 5.83636654 0.8327501 1 P 0 ;0,1,2=426,3=90.000000
L 5.83636654 0.8327501 5.83326624 0.83083317 1 P 0 ;0,1,2=426,3=90.000000
L 5.83326624 0.83083317 5.8280998 0.82929951 1 P 0 ;0,1,2=426,3=90.000000
L 5.8280998 0.82929951 5.8234498 0.82891624 1 P 0 ;0,1,2=426,3=90.000000
L 5.8234498 0.82891624 5.8187999 0.82968337 1 P 0 ;0,1,2=426,3=90.000000
L 5.8187999 0.82968337 5.81569961 0.83083317 1 P 0 ;0,1,2=426,3=90.000000
L 5.81569961 0.83083317 5.81259931 0.83313337 1 P 0 ;0,1,2=426,3=90.000000
L 5.81259931 0.83313337 5.81053307 0.83581683 1 P 0 ;0,1,2=426,3=90.000000
L 5.81053307 0.83581683 5.8095 0.83849961 1 P 0 ;0,1,2=426,3=90.000000
L 5.8095 0.83849961 5.8095 0.84118307 1 P 0 ;0,1,2=426,3=90.000000
L 5.8095 0.84118307 5.81053307 0.84386654 1 P 0 ;0,1,2=426,3=90.000000
L 5.81053307 0.84386654 5.81208278 0.84616673 1 P 0 ;0,1,2=426,3=90.000000
L 5.81208278 0.84616673 5.81414892 0.84808366 1 P 0 ;0,1,2=426,3=90.000000
L 5.83533346 0.86221644 5.83843278 0.86451663 1 P 0 ;0,1,2=426,3=90.000000
L 5.83843278 0.86451663 5.83998337 0.8672001 1 P 0 ;0,1,2=426,3=90.000000
L 5.83998337 0.8672001 5.8405 0.87026683 1 P 0 ;0,1,2=426,3=90.000000
L 5.8405 0.87026683 5.83946683 0.8741 1 P 0 ;0,1,2=426,3=90.000000
L 5.83946683 0.8741 5.83688307 0.87678346 1 P 0 ;0,1,2=426,3=90.000000
L 5.83688307 0.87678346 5.83378376 0.87755 1 P 0 ;0,1,2=426,3=90.000000
L 5.83378376 0.87755 5.83068258 0.87716673 1 P 0 ;0,1,2=426,3=90.000000
L 5.83068258 0.87716673 5.8280998 0.87563307 1 P 0 ;0,1,2=426,3=90.000000
L 5.8280998 0.87563307 5.82293327 0.86796663 1 P 0 ;0,1,2=426,3=90.000000
L 5.82293327 0.86796663 5.81931644 0.86451663 1 P 0 ;0,1,2=426,3=90.000000
L 5.81931644 0.86451663 5.81414892 0.86221644 1 P 0 ;0,1,2=426,3=90.000000
L 5.81414892 0.86221644 5.8095 0.8614499 1 P 0 ;0,1,2=426,3=90.000000
L 5.8095 0.8614499 5.8095 0.87755 1 P 0 ;0,1,2=426,3=90.000000
L 5.81311585 0.89398287 5.81053307 0.89666634 1 P 0 ;0,1,2=426,3=90.000000
L 5.81053307 0.89666634 5.8095 0.89973307 1 P 0 ;0,1,2=426,3=90.000000
L 5.8095 0.89973307 5.81053307 0.9027998 1 P 0 ;0,1,2=426,3=90.000000
L 5.81053307 0.9027998 5.81363238 0.90548327 1 P 0 ;0,1,2=426,3=90.000000
L 5.81363238 0.90548327 5.81828327 0.9074002 1 P 0 ;0,1,2=426,3=90.000000
L 5.81828327 0.9074002 5.82293327 0.90816673 1 P 0 ;0,1,2=426,3=90.000000
L 5.82293327 0.90816673 5.82861634 0.90816673 1 P 0 ;0,1,2=426,3=90.000000
L 5.82861634 0.90816673 5.83326624 0.9074002 1 P 0 ;0,1,2=426,3=90.000000
L 5.83326624 0.9074002 5.8373997 0.90548327 1 P 0 ;0,1,2=426,3=90.000000
L 5.8373997 0.90548327 5.83946683 0.90318307 1 P 0 ;0,1,2=426,3=90.000000
L 5.83946683 0.90318307 5.8405 0.90049961 1 P 0 ;0,1,2=426,3=90.000000
L 5.8405 0.90049961 5.83946683 0.89743287 1 P 0 ;0,1,2=426,3=90.000000
L 5.83946683 0.89743287 5.8373997 0.89513337 1 P 0 ;0,1,2=426,3=90.000000
L 5.8373997 0.89513337 5.8343003 0.8935997 1 P 0 ;0,1,2=426,3=90.000000
L 5.8343003 0.8935997 5.83016594 0.89283317 1 P 0 ;0,1,2=426,3=90.000000
L 5.83016594 0.89283317 5.8265501 0.8935997 1 P 0 ;0,1,2=426,3=90.000000
L 5.8265501 0.8935997 5.82293327 0.89551663 1 P 0 ;0,1,2=426,3=90.000000
L 5.82293327 0.89551663 5.82086604 0.89781683 1 P 0 ;0,1,2=426,3=90.000000
L 5.82086604 0.89781683 5.82034951 0.90049961 1 P 0 ;0,1,2=426,3=90.000000
L 5.82034951 0.90049961 5.82138268 0.90356634 1 P 0 ;0,1,2=426,3=90.000000
L 5.82138268 0.90356634 5.82396634 0.90586654 1 P 0 ;0,1,2=426,3=90.000000
L 5.82396634 0.90586654 5.82861634 0.90816673 1 P 0 ;0,1,2=426,3=90.000000
L 5.81569961 0.92306663 5.81208278 0.92536614 1 P 0 ;0,1,2=426,3=90.000000
L 5.81208278 0.92536614 5.81001654 0.92843287 1 P 0 ;0,1,2=426,3=90.000000
L 5.81001654 0.92843287 5.8095 0.93188356 1 P 0 ;0,1,2=426,3=90.000000
L 5.8095 0.93188356 5.81001654 0.9349503 1 P 0 ;0,1,2=426,3=90.000000
L 5.81001654 0.9349503 5.81259931 0.93801703 1 P 0 ;0,1,2=426,3=90.000000
L 5.81259931 0.93801703 5.81569961 0.93993327 1 P 0 ;0,1,2=426,3=90.000000
L 5.81569961 0.93993327 5.8187999 0.94031654 1 P 0 ;0,1,2=426,3=90.000000
L 5.8187999 0.94031654 5.82241575 0.93955 1 P 0 ;0,1,2=426,3=90.000000
L 5.82241575 0.93955 5.82499951 0.93686654 1 P 0 ;0,1,2=426,3=90.000000
L 5.82499951 0.93686654 5.82603356 0.93418307 1 P 0 ;0,1,2=426,3=90.000000
L 5.82603356 0.93418307 5.82603356 0.93073307 1 P 0 ;0,1,2=426,3=90.000000
L 5.82603356 0.93418307 5.82758317 0.93648327 1 P 0 ;0,1,2=426,3=90.000000
L 5.82758317 0.93648327 5.83016594 0.9384002 1 P 0 ;0,1,2=426,3=90.000000
L 5.83016594 0.9384002 5.83326624 0.93916673 1 P 0 ;0,1,2=426,3=90.000000
L 5.83326624 0.93916673 5.83636654 0.9384002 1 P 0 ;0,1,2=426,3=90.000000
L 5.83636654 0.9384002 5.83894931 0.93648327 1 P 0 ;0,1,2=426,3=90.000000
L 5.83894931 0.93648327 5.8405 0.93303327 1 P 0 ;0,1,2=426,3=90.000000
L 5.8405 0.93303327 5.83998337 0.92958337 1 P 0 ;0,1,2=426,3=90.000000
L 5.83998337 0.92958337 5.83791624 0.92613337 1 P 0 ;0,1,2=426,3=90.000000
L 4.278 2.053 4.322 2.053 1 P 0 
L 4.278 1.963 4.278 2.053 1 P 0 
L 4.322 2.053 4.322 1.963 1 P 0 
L 4.322 1.963 4.278 1.963 1 P 0 
L 4.35041634 2.01786663 4.35166683 2.01626644 1 P 0 ;0,1,2=427,3=90.000000
L 4.35166683 2.01626644 4.3525 2.0144002 1 P 0 ;0,1,2=427,3=90.000000
L 4.3525 2.0144002 4.3525 2.01226683 1 P 0 ;0,1,2=427,3=90.000000
L 4.3525 2.01226683 4.35124941 2.00986634 1 P 0 ;0,1,2=427,3=90.000000
L 4.35124941 2.00986634 4.34916654 2.0080001 1 P 0 ;0,1,2=427,3=90.000000
L 4.34916654 2.0080001 4.34666634 2.00666654 1 P 0 ;0,1,2=427,3=90.000000
L 4.34666634 2.00666654 4.3424998 2.00559961 1 P 0 ;0,1,2=427,3=90.000000
L 4.3424998 2.00559961 4.3387498 2.00533297 1 P 0 ;0,1,2=427,3=90.000000
L 4.3387498 2.00533297 4.3349999 2.00586673 1 P 0 ;0,1,2=427,3=90.000000
L 4.3349999 2.00586673 4.33249961 2.00666654 1 P 0 ;0,1,2=427,3=90.000000
L 4.33249961 2.00666654 4.32999941 2.00826663 1 P 0 ;0,1,2=427,3=90.000000
L 4.32999941 2.00826663 4.32833307 2.01013346 1 P 0 ;0,1,2=427,3=90.000000
L 4.32833307 2.01013346 4.3275 2.0119997 1 P 0 ;0,1,2=427,3=90.000000
L 4.3275 2.0119997 4.3275 2.01386644 1 P 0 ;0,1,2=427,3=90.000000
L 4.3275 2.01386644 4.32833307 2.01573327 1 P 0 ;0,1,2=427,3=90.000000
L 4.32833307 2.01573327 4.32958287 2.01733337 1 P 0 ;0,1,2=427,3=90.000000
L 4.32958287 2.01733337 4.33124911 2.01866693 1 P 0 ;0,1,2=427,3=90.000000
L 4.3275 2.0339997 4.3525 2.0339997 1 P 0 ;0,1,2=427,3=90.000000
L 4.3525 2.0339997 4.3475003 2.0307999 1 P 0 ;0,1,2=427,3=90.000000
L 4.3275 2.0307999 4.3275 2.03719951 1 P 0 ;0,1,2=427,3=90.000000
L 4.3275 2.0592 4.3525 2.0592 1 P 0 ;0,1,2=427,3=90.000000
L 4.3525 2.0592 4.33458327 2.04933297 1 P 0 ;0,1,2=427,3=90.000000
L 4.33458327 2.04933297 4.33458327 2.06266693 1 P 0 ;0,1,2=427,3=90.000000
L 4.33041604 2.07346634 4.32833307 2.07533317 1 P 0 ;0,1,2=427,3=90.000000
L 4.32833307 2.07533317 4.3275 2.07746654 1 P 0 ;0,1,2=427,3=90.000000
L 4.3275 2.07746654 4.32833307 2.0795999 1 P 0 ;0,1,2=427,3=90.000000
L 4.32833307 2.0795999 4.33083258 2.08146663 1 P 0 ;0,1,2=427,3=90.000000
L 4.33083258 2.08146663 4.33458327 2.0828001 1 P 0 ;0,1,2=427,3=90.000000
L 4.33458327 2.0828001 4.33833327 2.08333337 1 P 0 ;0,1,2=427,3=90.000000
L 4.33833327 2.08333337 4.34291634 2.08333337 1 P 0 ;0,1,2=427,3=90.000000
L 4.34291634 2.08333337 4.34666634 2.0828001 1 P 0 ;0,1,2=427,3=90.000000
L 4.34666634 2.0828001 4.3499997 2.08146663 1 P 0 ;0,1,2=427,3=90.000000
L 4.3499997 2.08146663 4.35166683 2.07986644 1 P 0 ;0,1,2=427,3=90.000000
L 4.35166683 2.07986644 4.3525 2.0779997 1 P 0 ;0,1,2=427,3=90.000000
L 4.3525 2.0779997 4.35166683 2.07586634 1 P 0 ;0,1,2=427,3=90.000000
L 4.35166683 2.07586634 4.3499997 2.07426663 1 P 0 ;0,1,2=427,3=90.000000
L 4.3499997 2.07426663 4.3475003 2.0731998 1 P 0 ;0,1,2=427,3=90.000000
L 4.3475003 2.0731998 4.34416614 2.07266654 1 P 0 ;0,1,2=427,3=90.000000
L 4.34416614 2.07266654 4.3412501 2.0731998 1 P 0 ;0,1,2=427,3=90.000000
L 4.3412501 2.0731998 4.33833327 2.07453327 1 P 0 ;0,1,2=427,3=90.000000
L 4.33833327 2.07453327 4.33666614 2.07613346 1 P 0 ;0,1,2=427,3=90.000000
L 4.33666614 2.07613346 4.33624961 2.0779997 1 P 0 ;0,1,2=427,3=90.000000
L 4.33624961 2.0779997 4.33708278 2.08013307 1 P 0 ;0,1,2=427,3=90.000000
L 4.33708278 2.08013307 4.33916644 2.08173327 1 P 0 ;0,1,2=427,3=90.000000
L 4.33916644 2.08173327 4.34291634 2.08333337 1 P 0 ;0,1,2=427,3=90.000000
L 4.284 1.861 4.328 1.861 1 P 0 
L 4.328 1.861 4.328 1.771 1 P 0 
L 4.328 1.771 4.284 1.771 1 P 0 
L 4.284 1.771 4.284 1.861 1 P 0 
L 2.62541634 1.72286663 2.62666683 1.72126644 1 P 0 ;0,1,2=428,3=90.000000
L 2.62666683 1.72126644 2.6275 1.7194002 1 P 0 ;0,1,2=428,3=90.000000
L 2.6275 1.7194002 2.6275 1.71726683 1 P 0 ;0,1,2=428,3=90.000000
L 2.6275 1.71726683 2.62624941 1.71486634 1 P 0 ;0,1,2=428,3=90.000000
L 2.62624941 1.71486634 2.62416654 1.7130001 1 P 0 ;0,1,2=428,3=90.000000
L 2.62416654 1.7130001 2.62166634 1.71166654 1 P 0 ;0,1,2=428,3=90.000000
L 2.62166634 1.71166654 2.6174998 1.71059961 1 P 0 ;0,1,2=428,3=90.000000
L 2.6174998 1.71059961 2.6137498 1.71033297 1 P 0 ;0,1,2=428,3=90.000000
L 2.6137498 1.71033297 2.6099999 1.71086673 1 P 0 ;0,1,2=428,3=90.000000
L 2.6099999 1.71086673 2.60749961 1.71166654 1 P 0 ;0,1,2=428,3=90.000000
L 2.60749961 1.71166654 2.60499941 1.71326663 1 P 0 ;0,1,2=428,3=90.000000
L 2.60499941 1.71326663 2.60333307 1.71513346 1 P 0 ;0,1,2=428,3=90.000000
L 2.60333307 1.71513346 2.6025 1.7169997 1 P 0 ;0,1,2=428,3=90.000000
L 2.6025 1.7169997 2.6025 1.71886644 1 P 0 ;0,1,2=428,3=90.000000
L 2.6025 1.71886644 2.60333307 1.72073327 1 P 0 ;0,1,2=428,3=90.000000
L 2.60333307 1.72073327 2.60458287 1.72233337 1 P 0 ;0,1,2=428,3=90.000000
L 2.60458287 1.72233337 2.60624911 1.72366693 1 P 0 ;0,1,2=428,3=90.000000
L 2.6025 1.7389997 2.6275 1.7389997 1 P 0 ;0,1,2=428,3=90.000000
L 2.6275 1.7389997 2.6225003 1.7357999 1 P 0 ;0,1,2=428,3=90.000000
L 2.6025 1.7357999 2.6025 1.74219951 1 P 0 ;0,1,2=428,3=90.000000
L 2.6025 1.7609997 2.6275 1.7609997 1 P 0 ;0,1,2=428,3=90.000000
L 2.6275 1.7609997 2.6225003 1.7577999 1 P 0 ;0,1,2=428,3=90.000000
L 2.6025 1.7577999 2.6025 1.76419951 1 P 0 ;0,1,2=428,3=90.000000
L 2.60624911 1.77713327 2.60416624 1.77873297 1 P 0 ;0,1,2=428,3=90.000000
L 2.60416624 1.77873297 2.60291654 1.7805997 1 P 0 ;0,1,2=428,3=90.000000
L 2.60291654 1.7805997 2.6025 1.7829997 1 P 0 ;0,1,2=428,3=90.000000
L 2.6025 1.7829997 2.60333307 1.7854002 1 P 0 ;0,1,2=428,3=90.000000
L 2.60333307 1.7854002 2.60499941 1.78726644 1 P 0 ;0,1,2=428,3=90.000000
L 2.60499941 1.78726644 2.60791624 1.7886 1 P 0 ;0,1,2=428,3=90.000000
L 2.60791624 1.7886 2.61124961 1.78886663 1 P 0 ;0,1,2=428,3=90.000000
L 2.61124961 1.78886663 2.61458297 1.78833337 1 P 0 ;0,1,2=428,3=90.000000
L 2.61458297 1.78833337 2.61666663 1.7869998 1 P 0 ;0,1,2=428,3=90.000000
L 2.61666663 1.7869998 2.61833297 1.78513307 1 P 0 ;0,1,2=428,3=90.000000
L 2.61833297 1.78513307 2.61874951 1.78326683 1 P 0 ;0,1,2=428,3=90.000000
L 2.61874951 1.78326683 2.61833297 1.7814 1 P 0 ;0,1,2=428,3=90.000000
L 2.61833297 1.7814 2.61666663 1.7790001 1 P 0 ;0,1,2=428,3=90.000000
L 2.61666663 1.7790001 2.6275 1.7797999 1 P 0 ;0,1,2=428,3=90.000000
L 2.6275 1.7797999 2.6275 1.7869998 1 P 0 ;0,1,2=428,3=90.000000
L 4.389 1.763 4.389 1.719 1 P 0 
L 4.389 1.719 4.299 1.719 1 P 0 
L 4.299 1.719 4.299 1.763 1 P 0 
L 4.299 1.763 4.389 1.763 1 P 0 
L 2.66213337 1.69541634 2.66373356 1.69666683 1 P 0 ;0,1,2=429,3=0.000000
L 2.66373356 1.69666683 2.6655998 1.6975 1 P 0 ;0,1,2=429,3=0.000000
L 2.6655998 1.6975 2.66773317 1.6975 1 P 0 ;0,1,2=429,3=0.000000
L 2.66773317 1.6975 2.67013366 1.69624941 1 P 0 ;0,1,2=429,3=0.000000
L 2.67013366 1.69624941 2.6719999 1.69416654 1 P 0 ;0,1,2=429,3=0.000000
L 2.6719999 1.69416654 2.67333346 1.69166634 1 P 0 ;0,1,2=429,3=0.000000
L 2.67333346 1.69166634 2.67440039 1.6874998 1 P 0 ;0,1,2=429,3=0.000000
L 2.67440039 1.6874998 2.67466703 1.6837498 1 P 0 ;0,1,2=429,3=0.000000
L 2.67466703 1.6837498 2.67413327 1.6799999 1 P 0 ;0,1,2=429,3=0.000000
L 2.67413327 1.6799999 2.67333346 1.67749961 1 P 0 ;0,1,2=429,3=0.000000
L 2.67333346 1.67749961 2.67173337 1.67499941 1 P 0 ;0,1,2=429,3=0.000000
L 2.67173337 1.67499941 2.66986654 1.67333307 1 P 0 ;0,1,2=429,3=0.000000
L 2.66986654 1.67333307 2.6680003 1.6725 1 P 0 ;0,1,2=429,3=0.000000
L 2.6680003 1.6725 2.66613356 1.6725 1 P 0 ;0,1,2=429,3=0.000000
L 2.66613356 1.6725 2.66426673 1.67333307 1 P 0 ;0,1,2=429,3=0.000000
L 2.66426673 1.67333307 2.66266663 1.67458287 1 P 0 ;0,1,2=429,3=0.000000
L 2.66266663 1.67458287 2.66133307 1.67624911 1 P 0 ;0,1,2=429,3=0.000000
L 2.65106683 1.69333337 2.64946673 1.69583287 1 P 0 ;0,1,2=429,3=0.000000
L 2.64946673 1.69583287 2.6476 1.69708337 1 P 0 ;0,1,2=429,3=0.000000
L 2.6476 1.69708337 2.64546663 1.6975 1 P 0 ;0,1,2=429,3=0.000000
L 2.64546663 1.6975 2.6428 1.69666683 1 P 0 ;0,1,2=429,3=0.000000
L 2.6428 1.69666683 2.64093327 1.69458317 1 P 0 ;0,1,2=429,3=0.000000
L 2.64093327 1.69458317 2.6404 1.69208366 1 P 0 ;0,1,2=429,3=0.000000
L 2.6404 1.69208366 2.64066663 1.68958268 1 P 0 ;0,1,2=429,3=0.000000
L 2.64066663 1.68958268 2.64173356 1.6874998 1 P 0 ;0,1,2=429,3=0.000000
L 2.64173356 1.6874998 2.64706673 1.68333327 1 P 0 ;0,1,2=429,3=0.000000
L 2.64706673 1.68333327 2.64946673 1.68041644 1 P 0 ;0,1,2=429,3=0.000000
L 2.64946673 1.68041644 2.65106683 1.67624911 1 P 0 ;0,1,2=429,3=0.000000
L 2.65106683 1.67624911 2.6516001 1.6725 1 P 0 ;0,1,2=429,3=0.000000
L 2.6516001 1.6725 2.6404 1.6725 1 P 0 ;0,1,2=429,3=0.000000
L 2.6240003 1.6725 2.6240003 1.6975 1 P 0 ;0,1,2=429,3=0.000000
L 2.6240003 1.6975 2.6272001 1.6925003 1 P 0 ;0,1,2=429,3=0.000000
L 2.6272001 1.6725 2.62080049 1.6725 1 P 0 ;0,1,2=429,3=0.000000
L 2.60706683 1.69333337 2.60546673 1.69583287 1 P 0 ;0,1,2=429,3=0.000000
L 2.60546673 1.69583287 2.6036 1.69708337 1 P 0 ;0,1,2=429,3=0.000000
L 2.6036 1.69708337 2.60146663 1.6975 1 P 0 ;0,1,2=429,3=0.000000
L 2.60146663 1.6975 2.5988 1.69666683 1 P 0 ;0,1,2=429,3=0.000000
L 2.5988 1.69666683 2.59693327 1.69458317 1 P 0 ;0,1,2=429,3=0.000000
L 2.59693327 1.69458317 2.5964 1.69208366 1 P 0 ;0,1,2=429,3=0.000000
L 2.5964 1.69208366 2.59666663 1.68958268 1 P 0 ;0,1,2=429,3=0.000000
L 2.59666663 1.68958268 2.59773356 1.6874998 1 P 0 ;0,1,2=429,3=0.000000
L 2.59773356 1.6874998 2.60306673 1.68333327 1 P 0 ;0,1,2=429,3=0.000000
L 2.60306673 1.68333327 2.60546673 1.68041644 1 P 0 ;0,1,2=429,3=0.000000
L 2.60546673 1.68041644 2.60706683 1.67624911 1 P 0 ;0,1,2=429,3=0.000000
L 2.60706683 1.67624911 2.6076001 1.6725 1 P 0 ;0,1,2=429,3=0.000000
L 2.6076001 1.6725 2.5964 1.6725 1 P 0 ;0,1,2=429,3=0.000000
L 4.283 1.715 4.327 1.715 1 P 0 
L 4.327 1.715 4.327 1.625 1 P 0 
L 4.327 1.625 4.283 1.625 1 P 0 
L 4.283 1.625 4.283 1.715 1 P 0 
L 2.68041634 1.56786663 2.68166683 1.56626644 1 P 0 ;0,1,2=430,3=90.000000
L 2.68166683 1.56626644 2.6825 1.5644002 1 P 0 ;0,1,2=430,3=90.000000
L 2.6825 1.5644002 2.6825 1.56226683 1 P 0 ;0,1,2=430,3=90.000000
L 2.6825 1.56226683 2.68124941 1.55986634 1 P 0 ;0,1,2=430,3=90.000000
L 2.68124941 1.55986634 2.67916654 1.5580001 1 P 0 ;0,1,2=430,3=90.000000
L 2.67916654 1.5580001 2.67666634 1.55666654 1 P 0 ;0,1,2=430,3=90.000000
L 2.67666634 1.55666654 2.6724998 1.55559961 1 P 0 ;0,1,2=430,3=90.000000
L 2.6724998 1.55559961 2.6687498 1.55533297 1 P 0 ;0,1,2=430,3=90.000000
L 2.6687498 1.55533297 2.6649999 1.55586673 1 P 0 ;0,1,2=430,3=90.000000
L 2.6649999 1.55586673 2.66249961 1.55666654 1 P 0 ;0,1,2=430,3=90.000000
L 2.66249961 1.55666654 2.65999941 1.55826663 1 P 0 ;0,1,2=430,3=90.000000
L 2.65999941 1.55826663 2.65833307 1.56013346 1 P 0 ;0,1,2=430,3=90.000000
L 2.65833307 1.56013346 2.6575 1.5619997 1 P 0 ;0,1,2=430,3=90.000000
L 2.6575 1.5619997 2.6575 1.56386644 1 P 0 ;0,1,2=430,3=90.000000
L 2.6575 1.56386644 2.65833307 1.56573327 1 P 0 ;0,1,2=430,3=90.000000
L 2.65833307 1.56573327 2.65958287 1.56733337 1 P 0 ;0,1,2=430,3=90.000000
L 2.65958287 1.56733337 2.66124911 1.56866693 1 P 0 ;0,1,2=430,3=90.000000
L 2.6575 1.5839997 2.6825 1.5839997 1 P 0 ;0,1,2=430,3=90.000000
L 2.6825 1.5839997 2.6775003 1.5807999 1 P 0 ;0,1,2=430,3=90.000000
L 2.6575 1.5807999 2.6575 1.58719951 1 P 0 ;0,1,2=430,3=90.000000
L 2.6575 1.6059997 2.6825 1.6059997 1 P 0 ;0,1,2=430,3=90.000000
L 2.6825 1.6059997 2.6775003 1.6027999 1 P 0 ;0,1,2=430,3=90.000000
L 2.6575 1.6027999 2.6575 1.60919951 1 P 0 ;0,1,2=430,3=90.000000
L 2.6575 1.6312 2.6825 1.6312 1 P 0 ;0,1,2=430,3=90.000000
L 2.6825 1.6312 2.66458327 1.62133297 1 P 0 ;0,1,2=430,3=90.000000
L 2.66458327 1.62133297 2.66458327 1.63466693 1 P 0 ;0,1,2=430,3=90.000000
L 4.57911004 1.777 4.57911004 1.733 1 P 0 
L 4.48911004 1.777 4.57911004 1.777 1 P 0 
L 4.57911004 1.733 4.48911004 1.733 1 P 0 
L 4.48911004 1.733 4.48911004 1.777 1 P 0 
L 2.86713337 1.69041634 2.86873356 1.69166683 1 P 0 ;0,1,2=431,3=0.000000
L 2.86873356 1.69166683 2.8705998 1.6925 1 P 0 ;0,1,2=431,3=0.000000
L 2.8705998 1.6925 2.87273317 1.6925 1 P 0 ;0,1,2=431,3=0.000000
L 2.87273317 1.6925 2.87513366 1.69124941 1 P 0 ;0,1,2=431,3=0.000000
L 2.87513366 1.69124941 2.8769999 1.68916654 1 P 0 ;0,1,2=431,3=0.000000
L 2.8769999 1.68916654 2.87833346 1.68666634 1 P 0 ;0,1,2=431,3=0.000000
L 2.87833346 1.68666634 2.87940039 1.6824998 1 P 0 ;0,1,2=431,3=0.000000
L 2.87940039 1.6824998 2.87966703 1.6787498 1 P 0 ;0,1,2=431,3=0.000000
L 2.87966703 1.6787498 2.87913327 1.6749999 1 P 0 ;0,1,2=431,3=0.000000
L 2.87913327 1.6749999 2.87833346 1.67249961 1 P 0 ;0,1,2=431,3=0.000000
L 2.87833346 1.67249961 2.87673337 1.66999941 1 P 0 ;0,1,2=431,3=0.000000
L 2.87673337 1.66999941 2.87486654 1.66833307 1 P 0 ;0,1,2=431,3=0.000000
L 2.87486654 1.66833307 2.8730003 1.6675 1 P 0 ;0,1,2=431,3=0.000000
L 2.8730003 1.6675 2.87113356 1.6675 1 P 0 ;0,1,2=431,3=0.000000
L 2.87113356 1.6675 2.86926673 1.66833307 1 P 0 ;0,1,2=431,3=0.000000
L 2.86926673 1.66833307 2.86766663 1.66958287 1 P 0 ;0,1,2=431,3=0.000000
L 2.86766663 1.66958287 2.86633307 1.67124911 1 P 0 ;0,1,2=431,3=0.000000
L 2.8510003 1.6675 2.8510003 1.6925 1 P 0 ;0,1,2=431,3=0.000000
L 2.8510003 1.6925 2.8542001 1.6875003 1 P 0 ;0,1,2=431,3=0.000000
L 2.8542001 1.6675 2.84780049 1.6675 1 P 0 ;0,1,2=431,3=0.000000
L 2.83406683 1.67791594 2.8322001 1.68083346 1 P 0 ;0,1,2=431,3=0.000000
L 2.8322001 1.68083346 2.8306 1.6824998 1 P 0 ;0,1,2=431,3=0.000000
L 2.8306 1.6824998 2.82846663 1.68333297 1 P 0 ;0,1,2=431,3=0.000000
L 2.82846663 1.68333297 2.8265998 1.6824998 1 P 0 ;0,1,2=431,3=0.000000
L 2.8265998 1.6824998 2.82526673 1.68083346 1 P 0 ;0,1,2=431,3=0.000000
L 2.82526673 1.68083346 2.8241999 1.67833327 1 P 0 ;0,1,2=431,3=0.000000
L 2.8241999 1.67833327 2.82393327 1.67541644 1 P 0 ;0,1,2=431,3=0.000000
L 2.82393327 1.67541644 2.8241999 1.67291624 1 P 0 ;0,1,2=431,3=0.000000
L 2.8241999 1.67291624 2.82526673 1.67041604 1 P 0 ;0,1,2=431,3=0.000000
L 2.82526673 1.67041604 2.82686693 1.66833307 1 P 0 ;0,1,2=431,3=0.000000
L 2.82686693 1.66833307 2.82873317 1.6675 1 P 0 ;0,1,2=431,3=0.000000
L 2.82873317 1.6675 2.83086654 1.66833307 1 P 0 ;0,1,2=431,3=0.000000
L 2.83086654 1.66833307 2.83273337 1.67083258 1 P 0 ;0,1,2=431,3=0.000000
L 2.83273337 1.67083258 2.8338002 1.67458327 1 P 0 ;0,1,2=431,3=0.000000
L 2.8338002 1.67458327 2.83406683 1.6787498 1 P 0 ;0,1,2=431,3=0.000000
L 2.83406683 1.6787498 2.83353366 1.68416614 1 P 0 ;0,1,2=431,3=0.000000
L 2.83353366 1.68416614 2.83273337 1.68708366 1 P 0 ;0,1,2=431,3=0.000000
L 2.83273337 1.68708366 2.8314003 1.6899997 1 P 0 ;0,1,2=431,3=0.000000
L 2.8314003 1.6899997 2.82953346 1.69208337 1 P 0 ;0,1,2=431,3=0.000000
L 2.82953346 1.69208337 2.82766673 1.6925 1 P 0 ;0,1,2=431,3=0.000000
L 2.82766673 1.6925 2.8258 1.69166683 1 P 0 ;0,1,2=431,3=0.000000
L 2.8258 1.69166683 2.82446644 1.68958317 1 P 0 ;0,1,2=431,3=0.000000
L 2.81286673 1.67124911 2.81126703 1.66916624 1 P 0 ;0,1,2=431,3=0.000000
L 2.81126703 1.66916624 2.8094003 1.66791654 1 P 0 ;0,1,2=431,3=0.000000
L 2.8094003 1.66791654 2.8070003 1.6675 1 P 0 ;0,1,2=431,3=0.000000
L 2.8070003 1.6675 2.8045998 1.66833307 1 P 0 ;0,1,2=431,3=0.000000
L 2.8045998 1.66833307 2.80273356 1.66999941 1 P 0 ;0,1,2=431,3=0.000000
L 2.80273356 1.66999941 2.8014 1.67291624 1 P 0 ;0,1,2=431,3=0.000000
L 2.8014 1.67291624 2.80113337 1.67624961 1 P 0 ;0,1,2=431,3=0.000000
L 2.80113337 1.67624961 2.80166663 1.67958297 1 P 0 ;0,1,2=431,3=0.000000
L 2.80166663 1.67958297 2.8030002 1.68166663 1 P 0 ;0,1,2=431,3=0.000000
L 2.8030002 1.68166663 2.80486693 1.68333297 1 P 0 ;0,1,2=431,3=0.000000
L 2.80486693 1.68333297 2.80673317 1.68374951 1 P 0 ;0,1,2=431,3=0.000000
L 2.80673317 1.68374951 2.8086 1.68333297 1 P 0 ;0,1,2=431,3=0.000000
L 2.8086 1.68333297 2.8109999 1.68166663 1 P 0 ;0,1,2=431,3=0.000000
L 2.8109999 1.68166663 2.8102001 1.6925 1 P 0 ;0,1,2=431,3=0.000000
L 2.8102001 1.6925 2.8030002 1.6925 1 P 0 ;0,1,2=431,3=0.000000
L 4.245 0.752 4.335 0.752 1 P 0 
L 4.335 0.752 4.335 0.708 1 P 0 
L 4.335 0.708 4.245 0.708 1 P 0 
L 4.245 0.708 4.245 0.752 1 P 0 
L 4.32806673 0.69291624 4.33036693 0.69446683 1 P 0 ;0,1,2=432,3=0.000000
L 4.33036693 0.69446683 4.3330497 0.6955 1 P 0 ;0,1,2=432,3=0.000000
L 4.3330497 0.6955 4.33611644 0.6955 1 P 0 ;0,1,2=432,3=0.000000
L 4.33611644 0.6955 4.33956713 0.69394931 1 P 0 ;0,1,2=432,3=0.000000
L 4.33956713 0.69394931 4.3422499 0.69136654 1 P 0 ;0,1,2=432,3=0.000000
L 4.3422499 0.69136654 4.34416683 0.68826624 1 P 0 ;0,1,2=432,3=0.000000
L 4.34416683 0.68826624 4.34570049 0.6830998 1 P 0 ;0,1,2=432,3=0.000000
L 4.34570049 0.6830998 4.34608376 0.6784498 1 P 0 ;0,1,2=432,3=0.000000
L 4.34608376 0.6784498 4.34531663 0.6737999 1 P 0 ;0,1,2=432,3=0.000000
L 4.34531663 0.6737999 4.34416683 0.67069961 1 P 0 ;0,1,2=432,3=0.000000
L 4.34416683 0.67069961 4.34186663 0.66759931 1 P 0 ;0,1,2=432,3=0.000000
L 4.34186663 0.66759931 4.33918317 0.66553307 1 P 0 ;0,1,2=432,3=0.000000
L 4.33918317 0.66553307 4.33650039 0.6645 1 P 0 ;0,1,2=432,3=0.000000
L 4.33650039 0.6645 4.33381693 0.6645 1 P 0 ;0,1,2=432,3=0.000000
L 4.33381693 0.6645 4.33113346 0.66553307 1 P 0 ;0,1,2=432,3=0.000000
L 4.33113346 0.66553307 4.32883327 0.66708278 1 P 0 ;0,1,2=432,3=0.000000
L 4.32883327 0.66708278 4.32691634 0.66914892 1 P 0 ;0,1,2=432,3=0.000000
L 4.31278356 0.69033346 4.31048337 0.69343278 1 P 0 ;0,1,2=432,3=0.000000
L 4.31048337 0.69343278 4.3077999 0.69498337 1 P 0 ;0,1,2=432,3=0.000000
L 4.3077999 0.69498337 4.30473317 0.6955 1 P 0 ;0,1,2=432,3=0.000000
L 4.30473317 0.6955 4.3009 0.69446683 1 P 0 ;0,1,2=432,3=0.000000
L 4.3009 0.69446683 4.29821654 0.69188307 1 P 0 ;0,1,2=432,3=0.000000
L 4.29821654 0.69188307 4.29745 0.68878376 1 P 0 ;0,1,2=432,3=0.000000
L 4.29745 0.68878376 4.29783327 0.68568258 1 P 0 ;0,1,2=432,3=0.000000
L 4.29783327 0.68568258 4.29936693 0.6830998 1 P 0 ;0,1,2=432,3=0.000000
L 4.29936693 0.6830998 4.30703337 0.67793327 1 P 0 ;0,1,2=432,3=0.000000
L 4.30703337 0.67793327 4.31048337 0.67431644 1 P 0 ;0,1,2=432,3=0.000000
L 4.31048337 0.67431644 4.31278356 0.66914892 1 P 0 ;0,1,2=432,3=0.000000
L 4.31278356 0.66914892 4.3135501 0.6645 1 P 0 ;0,1,2=432,3=0.000000
L 4.3135501 0.6645 4.29745 0.6645 1 P 0 ;0,1,2=432,3=0.000000
L 4.2699 0.6645 4.2699 0.6955 1 P 0 ;0,1,2=432,3=0.000000
L 4.2699 0.6955 4.28408376 0.67328327 1 P 0 ;0,1,2=432,3=0.000000
L 4.28408376 0.67328327 4.26491634 0.67328327 1 P 0 ;0,1,2=432,3=0.000000
L 4.2389 0.6645 4.2389 0.6955 1 P 0 ;0,1,2=432,3=0.000000
L 4.2389 0.6955 4.25308376 0.67328327 1 P 0 ;0,1,2=432,3=0.000000
L 4.25308376 0.67328327 4.23391634 0.67328327 1 P 0 ;0,1,2=432,3=0.000000
L 4.253 0.985 4.297 0.985 1 P 0 
L 4.253 0.895 4.253 0.985 1 P 0 
L 4.297 0.985 4.297 0.895 1 P 0 
L 4.297 0.895 4.253 0.895 1 P 0 
L 4.17291624 0.90693327 4.17446683 0.90463307 1 P 0 ;0,1,2=433,3=90.000000
L 4.17446683 0.90463307 4.1755 0.9019503 1 P 0 ;0,1,2=433,3=90.000000
L 4.1755 0.9019503 4.1755 0.89888356 1 P 0 ;0,1,2=433,3=90.000000
L 4.1755 0.89888356 4.17394931 0.89543287 1 P 0 ;0,1,2=433,3=90.000000
L 4.17394931 0.89543287 4.17136654 0.8927501 1 P 0 ;0,1,2=433,3=90.000000
L 4.17136654 0.8927501 4.16826624 0.89083317 1 P 0 ;0,1,2=433,3=90.000000
L 4.16826624 0.89083317 4.1630998 0.88929951 1 P 0 ;0,1,2=433,3=90.000000
L 4.1630998 0.88929951 4.1584498 0.88891624 1 P 0 ;0,1,2=433,3=90.000000
L 4.1584498 0.88891624 4.1537999 0.88968337 1 P 0 ;0,1,2=433,3=90.000000
L 4.1537999 0.88968337 4.15069961 0.89083317 1 P 0 ;0,1,2=433,3=90.000000
L 4.15069961 0.89083317 4.14759931 0.89313337 1 P 0 ;0,1,2=433,3=90.000000
L 4.14759931 0.89313337 4.14553307 0.89581683 1 P 0 ;0,1,2=433,3=90.000000
L 4.14553307 0.89581683 4.1445 0.89849961 1 P 0 ;0,1,2=433,3=90.000000
L 4.1445 0.89849961 4.1445 0.90118307 1 P 0 ;0,1,2=433,3=90.000000
L 4.1445 0.90118307 4.14553307 0.90386654 1 P 0 ;0,1,2=433,3=90.000000
L 4.14553307 0.90386654 4.14708278 0.90616673 1 P 0 ;0,1,2=433,3=90.000000
L 4.14708278 0.90616673 4.14914892 0.90808366 1 P 0 ;0,1,2=433,3=90.000000
L 4.17033346 0.92221644 4.17343278 0.92451663 1 P 0 ;0,1,2=433,3=90.000000
L 4.17343278 0.92451663 4.17498337 0.9272001 1 P 0 ;0,1,2=433,3=90.000000
L 4.17498337 0.9272001 4.1755 0.93026683 1 P 0 ;0,1,2=433,3=90.000000
L 4.1755 0.93026683 4.17446683 0.9341 1 P 0 ;0,1,2=433,3=90.000000
L 4.17446683 0.9341 4.17188307 0.93678346 1 P 0 ;0,1,2=433,3=90.000000
L 4.17188307 0.93678346 4.16878376 0.93755 1 P 0 ;0,1,2=433,3=90.000000
L 4.16878376 0.93755 4.16568258 0.93716673 1 P 0 ;0,1,2=433,3=90.000000
L 4.16568258 0.93716673 4.1630998 0.93563307 1 P 0 ;0,1,2=433,3=90.000000
L 4.1630998 0.93563307 4.15793327 0.92796663 1 P 0 ;0,1,2=433,3=90.000000
L 4.15793327 0.92796663 4.15431644 0.92451663 1 P 0 ;0,1,2=433,3=90.000000
L 4.15431644 0.92451663 4.14914892 0.92221644 1 P 0 ;0,1,2=433,3=90.000000
L 4.14914892 0.92221644 4.1445 0.9214499 1 P 0 ;0,1,2=433,3=90.000000
L 4.1445 0.9214499 4.1445 0.93755 1 P 0 ;0,1,2=433,3=90.000000
L 4.1445 0.9651 4.1755 0.9651 1 P 0 ;0,1,2=433,3=90.000000
L 4.1755 0.9651 4.15328327 0.95091624 1 P 0 ;0,1,2=433,3=90.000000
L 4.15328327 0.95091624 4.15328327 0.97008366 1 P 0 ;0,1,2=433,3=90.000000
L 4.15741575 0.98421644 4.16103356 0.9868999 1 P 0 ;0,1,2=433,3=90.000000
L 4.16103356 0.9868999 4.1630998 0.9892001 1 P 0 ;0,1,2=433,3=90.000000
L 4.1630998 0.9892001 4.16413287 0.99226683 1 P 0 ;0,1,2=433,3=90.000000
L 4.16413287 0.99226683 4.1630998 0.9949503 1 P 0 ;0,1,2=433,3=90.000000
L 4.1630998 0.9949503 4.16103356 0.99686654 1 P 0 ;0,1,2=433,3=90.000000
L 4.16103356 0.99686654 4.15793327 0.9984002 1 P 0 ;0,1,2=433,3=90.000000
L 4.15793327 0.9984002 4.15431644 0.99878346 1 P 0 ;0,1,2=433,3=90.000000
L 4.15431644 0.99878346 4.15121614 0.9984002 1 P 0 ;0,1,2=433,3=90.000000
L 4.15121614 0.9984002 4.14811585 0.99686654 1 P 0 ;0,1,2=433,3=90.000000
L 4.14811585 0.99686654 4.14553307 0.99456634 1 P 0 ;0,1,2=433,3=90.000000
L 4.14553307 0.99456634 4.1445 0.99188356 1 P 0 ;0,1,2=433,3=90.000000
L 4.1445 0.99188356 4.14553307 0.98881683 1 P 0 ;0,1,2=433,3=90.000000
L 4.14553307 0.98881683 4.14863238 0.98613337 1 P 0 ;0,1,2=433,3=90.000000
L 4.14863238 0.98613337 4.15328327 0.9845997 1 P 0 ;0,1,2=433,3=90.000000
L 4.15328327 0.9845997 4.1584498 0.98421644 1 P 0 ;0,1,2=433,3=90.000000
L 4.1584498 0.98421644 4.16516594 0.98498287 1 P 0 ;0,1,2=433,3=90.000000
L 4.16516594 0.98498287 4.16878376 0.98613337 1 P 0 ;0,1,2=433,3=90.000000
L 4.16878376 0.98613337 4.1723997 0.98804961 1 P 0 ;0,1,2=433,3=90.000000
L 4.1723997 0.98804961 4.17498337 0.99073307 1 P 0 ;0,1,2=433,3=90.000000
L 4.17498337 0.99073307 4.1755 0.99341654 1 P 0 ;0,1,2=433,3=90.000000
L 4.1755 0.99341654 4.17446683 0.9961 1 P 0 ;0,1,2=433,3=90.000000
L 4.17446683 0.9961 4.17188307 0.99801703 1 P 0 ;0,1,2=433,3=90.000000
L 4.298 0.985 4.342 0.985 1 P 0 
L 4.298 0.895 4.298 0.985 1 P 0 
L 4.342 0.985 4.342 0.895 1 P 0 
L 4.342 0.895 4.298 0.895 1 P 0 
L 4.21791624 0.90693327 4.21946683 0.90463307 1 P 0 ;0,1,2=434,3=90.000000
L 4.21946683 0.90463307 4.2205 0.9019503 1 P 0 ;0,1,2=434,3=90.000000
L 4.2205 0.9019503 4.2205 0.89888356 1 P 0 ;0,1,2=434,3=90.000000
L 4.2205 0.89888356 4.21894931 0.89543287 1 P 0 ;0,1,2=434,3=90.000000
L 4.21894931 0.89543287 4.21636654 0.8927501 1 P 0 ;0,1,2=434,3=90.000000
L 4.21636654 0.8927501 4.21326624 0.89083317 1 P 0 ;0,1,2=434,3=90.000000
L 4.21326624 0.89083317 4.2080998 0.88929951 1 P 0 ;0,1,2=434,3=90.000000
L 4.2080998 0.88929951 4.2034498 0.88891624 1 P 0 ;0,1,2=434,3=90.000000
L 4.2034498 0.88891624 4.1987999 0.88968337 1 P 0 ;0,1,2=434,3=90.000000
L 4.1987999 0.88968337 4.19569961 0.89083317 1 P 0 ;0,1,2=434,3=90.000000
L 4.19569961 0.89083317 4.19259931 0.89313337 1 P 0 ;0,1,2=434,3=90.000000
L 4.19259931 0.89313337 4.19053307 0.89581683 1 P 0 ;0,1,2=434,3=90.000000
L 4.19053307 0.89581683 4.1895 0.89849961 1 P 0 ;0,1,2=434,3=90.000000
L 4.1895 0.89849961 4.1895 0.90118307 1 P 0 ;0,1,2=434,3=90.000000
L 4.1895 0.90118307 4.19053307 0.90386654 1 P 0 ;0,1,2=434,3=90.000000
L 4.19053307 0.90386654 4.19208278 0.90616673 1 P 0 ;0,1,2=434,3=90.000000
L 4.19208278 0.90616673 4.19414892 0.90808366 1 P 0 ;0,1,2=434,3=90.000000
L 4.21533346 0.92221644 4.21843278 0.92451663 1 P 0 ;0,1,2=434,3=90.000000
L 4.21843278 0.92451663 4.21998337 0.9272001 1 P 0 ;0,1,2=434,3=90.000000
L 4.21998337 0.9272001 4.2205 0.93026683 1 P 0 ;0,1,2=434,3=90.000000
L 4.2205 0.93026683 4.21946683 0.9341 1 P 0 ;0,1,2=434,3=90.000000
L 4.21946683 0.9341 4.21688307 0.93678346 1 P 0 ;0,1,2=434,3=90.000000
L 4.21688307 0.93678346 4.21378376 0.93755 1 P 0 ;0,1,2=434,3=90.000000
L 4.21378376 0.93755 4.21068258 0.93716673 1 P 0 ;0,1,2=434,3=90.000000
L 4.21068258 0.93716673 4.2080998 0.93563307 1 P 0 ;0,1,2=434,3=90.000000
L 4.2080998 0.93563307 4.20293327 0.92796663 1 P 0 ;0,1,2=434,3=90.000000
L 4.20293327 0.92796663 4.19931644 0.92451663 1 P 0 ;0,1,2=434,3=90.000000
L 4.19931644 0.92451663 4.19414892 0.92221644 1 P 0 ;0,1,2=434,3=90.000000
L 4.19414892 0.92221644 4.1895 0.9214499 1 P 0 ;0,1,2=434,3=90.000000
L 4.1895 0.9214499 4.1895 0.93755 1 P 0 ;0,1,2=434,3=90.000000
L 4.1895 0.9651 4.2205 0.9651 1 P 0 ;0,1,2=434,3=90.000000
L 4.2205 0.9651 4.19828327 0.95091624 1 P 0 ;0,1,2=434,3=90.000000
L 4.19828327 0.95091624 4.19828327 0.97008366 1 P 0 ;0,1,2=434,3=90.000000
L 4.1895 0.99149961 4.19001654 0.99418307 1 P 0 ;0,1,2=434,3=90.000000
L 4.19001654 0.99418307 4.19156614 0.9972498 1 P 0 ;0,1,2=434,3=90.000000
L 4.19156614 0.9972498 4.19414892 0.99916673 1 P 0 ;0,1,2=434,3=90.000000
L 4.19414892 0.99916673 4.19776673 0.99993327 1 P 0 ;0,1,2=434,3=90.000000
L 4.19776673 0.99993327 4.20138268 0.99916673 1 P 0 ;0,1,2=434,3=90.000000
L 4.20138268 0.99916673 4.20448287 0.99686654 1 P 0 ;0,1,2=434,3=90.000000
L 4.20448287 0.99686654 4.20603356 0.99341654 1 P 0 ;0,1,2=434,3=90.000000
L 4.20603356 0.99341654 4.20603356 0.98958337 1 P 0 ;0,1,2=434,3=90.000000
L 4.20603356 0.98958337 4.20706663 0.98728317 1 P 0 ;0,1,2=434,3=90.000000
L 4.20706663 0.98728317 4.20964941 0.98536614 1 P 0 ;0,1,2=434,3=90.000000
L 4.20964941 0.98536614 4.21326624 0.9845997 1 P 0 ;0,1,2=434,3=90.000000
L 4.21326624 0.9845997 4.21688307 0.9857501 1 P 0 ;0,1,2=434,3=90.000000
L 4.21688307 0.9857501 4.21946683 0.98843287 1 P 0 ;0,1,2=434,3=90.000000
L 4.21946683 0.98843287 4.2205 0.99149961 1 P 0 ;0,1,2=434,3=90.000000
L 4.2205 0.99149961 4.21946683 0.99456634 1 P 0 ;0,1,2=434,3=90.000000
L 4.21946683 0.99456634 4.21688307 0.9972498 1 P 0 ;0,1,2=434,3=90.000000
L 4.21688307 0.9972498 4.21326624 0.9984002 1 P 0 ;0,1,2=434,3=90.000000
L 4.21326624 0.9984002 4.20964941 0.99763307 1 P 0 ;0,1,2=434,3=90.000000
L 4.20964941 0.99763307 4.20706663 0.99571673 1 P 0 ;0,1,2=434,3=90.000000
L 4.20706663 0.99571673 4.20603356 0.99341654 1 P 0 ;0,1,2=434,3=90.000000
L 4.20603356 0.99341654 4.20603356 0.98958337 1 P 0 ;0,1,2=434,3=90.000000
L 4.20603356 0.98958337 4.20448287 0.98613337 1 P 0 ;0,1,2=434,3=90.000000
L 4.20448287 0.98613337 4.20138268 0.98383317 1 P 0 ;0,1,2=434,3=90.000000
L 4.20138268 0.98383317 4.19776673 0.98306663 1 P 0 ;0,1,2=434,3=90.000000
L 4.19776673 0.98306663 4.19414892 0.98383317 1 P 0 ;0,1,2=434,3=90.000000
L 4.19414892 0.98383317 4.19156614 0.9857501 1 P 0 ;0,1,2=434,3=90.000000
L 4.19156614 0.9857501 4.19001654 0.98881683 1 P 0 ;0,1,2=434,3=90.000000
L 4.19001654 0.98881683 4.1895 0.99149961 1 P 0 ;0,1,2=434,3=90.000000
L 3.163 3.945 3.207 3.945 1 P 0 
L 3.207 3.945 3.207 3.855 1 P 0 
L 3.207 3.855 3.163 3.855 1 P 0 
L 3.163 3.855 3.163 3.945 1 P 0 
L 3.14291624 3.88243327 3.14446683 3.88013307 1 P 0 ;0,1,2=435,3=90.000000
L 3.14446683 3.88013307 3.1455 3.8774503 1 P 0 ;0,1,2=435,3=90.000000
L 3.1455 3.8774503 3.1455 3.87438356 1 P 0 ;0,1,2=435,3=90.000000
L 3.1455 3.87438356 3.14394931 3.87093287 1 P 0 ;0,1,2=435,3=90.000000
L 3.14394931 3.87093287 3.14136654 3.8682501 1 P 0 ;0,1,2=435,3=90.000000
L 3.14136654 3.8682501 3.13826624 3.86633317 1 P 0 ;0,1,2=435,3=90.000000
L 3.13826624 3.86633317 3.1330998 3.86479951 1 P 0 ;0,1,2=435,3=90.000000
L 3.1330998 3.86479951 3.1284498 3.86441624 1 P 0 ;0,1,2=435,3=90.000000
L 3.1284498 3.86441624 3.1237999 3.86518337 1 P 0 ;0,1,2=435,3=90.000000
L 3.1237999 3.86518337 3.12069961 3.86633317 1 P 0 ;0,1,2=435,3=90.000000
L 3.12069961 3.86633317 3.11759931 3.86863337 1 P 0 ;0,1,2=435,3=90.000000
L 3.11759931 3.86863337 3.11553307 3.87131683 1 P 0 ;0,1,2=435,3=90.000000
L 3.11553307 3.87131683 3.1145 3.87399961 1 P 0 ;0,1,2=435,3=90.000000
L 3.1145 3.87399961 3.1145 3.87668307 1 P 0 ;0,1,2=435,3=90.000000
L 3.1145 3.87668307 3.11553307 3.87936654 1 P 0 ;0,1,2=435,3=90.000000
L 3.11553307 3.87936654 3.11708278 3.88166673 1 P 0 ;0,1,2=435,3=90.000000
L 3.11708278 3.88166673 3.11914892 3.88358366 1 P 0 ;0,1,2=435,3=90.000000
L 3.11914892 3.89656663 3.11656614 3.89886614 1 P 0 ;0,1,2=435,3=90.000000
L 3.11656614 3.89886614 3.11501654 3.90154961 1 P 0 ;0,1,2=435,3=90.000000
L 3.11501654 3.90154961 3.1145 3.90499961 1 P 0 ;0,1,2=435,3=90.000000
L 3.1145 3.90499961 3.11553307 3.9084503 1 P 0 ;0,1,2=435,3=90.000000
L 3.11553307 3.9084503 3.11759931 3.91113307 1 P 0 ;0,1,2=435,3=90.000000
L 3.11759931 3.91113307 3.12121614 3.91305 1 P 0 ;0,1,2=435,3=90.000000
L 3.12121614 3.91305 3.12534951 3.91343327 1 P 0 ;0,1,2=435,3=90.000000
L 3.12534951 3.91343327 3.12948287 3.91266673 1 P 0 ;0,1,2=435,3=90.000000
L 3.12948287 3.91266673 3.13206663 3.9107498 1 P 0 ;0,1,2=435,3=90.000000
L 3.13206663 3.9107498 3.13413287 3.90806634 1 P 0 ;0,1,2=435,3=90.000000
L 3.13413287 3.90806634 3.13464941 3.90538356 1 P 0 ;0,1,2=435,3=90.000000
L 3.13464941 3.90538356 3.13413287 3.9027001 1 P 0 ;0,1,2=435,3=90.000000
L 3.13413287 3.9027001 3.13206663 3.8992501 1 P 0 ;0,1,2=435,3=90.000000
L 3.13206663 3.8992501 3.1455 3.9003999 1 P 0 ;0,1,2=435,3=90.000000
L 3.1455 3.9003999 3.1455 3.9107498 1 P 0 ;0,1,2=435,3=90.000000
L 3.1145 3.93523307 3.12121614 3.93599961 1 P 0 ;0,1,2=435,3=90.000000
L 3.12121614 3.93599961 3.12689921 3.9371501 1 P 0 ;0,1,2=435,3=90.000000
L 3.12689921 3.9371501 3.13206663 3.93868307 1 P 0 ;0,1,2=435,3=90.000000
L 3.13206663 3.93868307 3.1377497 3.9406 1 P 0 ;0,1,2=435,3=90.000000
L 3.1377497 3.9406 3.1455 3.94366673 1 P 0 ;0,1,2=435,3=90.000000
L 3.1455 3.94366673 3.1455 3.92833317 1 P 0 ;0,1,2=435,3=90.000000
L 4.59 2.917 4.59 2.873 1 P 0 
L 4.5 2.917 4.59 2.917 1 P 0 
L 4.59 2.873 4.5 2.873 1 P 0 
L 4.5 2.873 4.5 2.917 1 P 0 
L 4.57806673 3.00291624 4.58036693 3.00446683 1 P 0 ;0,1,2=436,3=0.000000
L 4.58036693 3.00446683 4.5830497 3.0055 1 P 0 ;0,1,2=436,3=0.000000
L 4.5830497 3.0055 4.58611644 3.0055 1 P 0 ;0,1,2=436,3=0.000000
L 4.58611644 3.0055 4.58956713 3.00394931 1 P 0 ;0,1,2=436,3=0.000000
L 4.58956713 3.00394931 4.5922499 3.00136654 1 P 0 ;0,1,2=436,3=0.000000
L 4.5922499 3.00136654 4.59416683 2.99826624 1 P 0 ;0,1,2=436,3=0.000000
L 4.59416683 2.99826624 4.59570049 2.9930998 1 P 0 ;0,1,2=436,3=0.000000
L 4.59570049 2.9930998 4.59608376 2.9884498 1 P 0 ;0,1,2=436,3=0.000000
L 4.59608376 2.9884498 4.59531663 2.9837999 1 P 0 ;0,1,2=436,3=0.000000
L 4.59531663 2.9837999 4.59416683 2.98069961 1 P 0 ;0,1,2=436,3=0.000000
L 4.59416683 2.98069961 4.59186663 2.97759931 1 P 0 ;0,1,2=436,3=0.000000
L 4.59186663 2.97759931 4.58918317 2.97553307 1 P 0 ;0,1,2=436,3=0.000000
L 4.58918317 2.97553307 4.58650039 2.9745 1 P 0 ;0,1,2=436,3=0.000000
L 4.58650039 2.9745 4.58381693 2.9745 1 P 0 ;0,1,2=436,3=0.000000
L 4.58381693 2.9745 4.58113346 2.97553307 1 P 0 ;0,1,2=436,3=0.000000
L 4.58113346 2.97553307 4.57883327 2.97708278 1 P 0 ;0,1,2=436,3=0.000000
L 4.57883327 2.97708278 4.57691634 2.97914892 1 P 0 ;0,1,2=436,3=0.000000
L 4.56278356 3.00033346 4.56048337 3.00343278 1 P 0 ;0,1,2=436,3=0.000000
L 4.56048337 3.00343278 4.5577999 3.00498337 1 P 0 ;0,1,2=436,3=0.000000
L 4.5577999 3.00498337 4.55473317 3.0055 1 P 0 ;0,1,2=436,3=0.000000
L 4.55473317 3.0055 4.5509 3.00446683 1 P 0 ;0,1,2=436,3=0.000000
L 4.5509 3.00446683 4.54821654 3.00188307 1 P 0 ;0,1,2=436,3=0.000000
L 4.54821654 3.00188307 4.54745 2.99878376 1 P 0 ;0,1,2=436,3=0.000000
L 4.54745 2.99878376 4.54783327 2.99568258 1 P 0 ;0,1,2=436,3=0.000000
L 4.54783327 2.99568258 4.54936693 2.9930998 1 P 0 ;0,1,2=436,3=0.000000
L 4.54936693 2.9930998 4.55703337 2.98793327 1 P 0 ;0,1,2=436,3=0.000000
L 4.55703337 2.98793327 4.56048337 2.98431644 1 P 0 ;0,1,2=436,3=0.000000
L 4.56048337 2.98431644 4.56278356 2.97914892 1 P 0 ;0,1,2=436,3=0.000000
L 4.56278356 2.97914892 4.5635501 2.9745 1 P 0 ;0,1,2=436,3=0.000000
L 4.5635501 2.9745 4.54745 2.9745 1 P 0 ;0,1,2=436,3=0.000000
L 4.53101713 2.97811585 4.52833366 2.97553307 1 P 0 ;0,1,2=436,3=0.000000
L 4.52833366 2.97553307 4.52526693 2.9745 1 P 0 ;0,1,2=436,3=0.000000
L 4.52526693 2.9745 4.5222002 2.97553307 1 P 0 ;0,1,2=436,3=0.000000
L 4.5222002 2.97553307 4.51951673 2.97863238 1 P 0 ;0,1,2=436,3=0.000000
L 4.51951673 2.97863238 4.5175998 2.98328327 1 P 0 ;0,1,2=436,3=0.000000
L 4.5175998 2.98328327 4.51683327 2.98793327 1 P 0 ;0,1,2=436,3=0.000000
L 4.51683327 2.98793327 4.51683327 2.99361634 1 P 0 ;0,1,2=436,3=0.000000
L 4.51683327 2.99361634 4.5175998 2.99826624 1 P 0 ;0,1,2=436,3=0.000000
L 4.5175998 2.99826624 4.51951673 3.0023997 1 P 0 ;0,1,2=436,3=0.000000
L 4.51951673 3.0023997 4.52181693 3.00446683 1 P 0 ;0,1,2=436,3=0.000000
L 4.52181693 3.00446683 4.52450039 3.0055 1 P 0 ;0,1,2=436,3=0.000000
L 4.52450039 3.0055 4.52756713 3.00446683 1 P 0 ;0,1,2=436,3=0.000000
L 4.52756713 3.00446683 4.52986663 3.0023997 1 P 0 ;0,1,2=436,3=0.000000
L 4.52986663 3.0023997 4.5314003 2.9993003 1 P 0 ;0,1,2=436,3=0.000000
L 4.5314003 2.9993003 4.53216683 2.99516594 1 P 0 ;0,1,2=436,3=0.000000
L 4.53216683 2.99516594 4.5314003 2.9915501 1 P 0 ;0,1,2=436,3=0.000000
L 4.5314003 2.9915501 4.52948337 2.98793327 1 P 0 ;0,1,2=436,3=0.000000
L 4.52948337 2.98793327 4.52718317 2.98586604 1 P 0 ;0,1,2=436,3=0.000000
L 4.52718317 2.98586604 4.52450039 2.98534951 1 P 0 ;0,1,2=436,3=0.000000
L 4.52450039 2.98534951 4.52143366 2.98638268 1 P 0 ;0,1,2=436,3=0.000000
L 4.52143366 2.98638268 4.51913346 2.98896634 1 P 0 ;0,1,2=436,3=0.000000
L 4.51913346 2.98896634 4.51683327 2.99361634 1 P 0 ;0,1,2=436,3=0.000000
L 4.4889 2.9745 4.4889 3.0055 1 P 0 ;0,1,2=436,3=0.000000
L 4.4889 3.0055 4.50308376 2.98328327 1 P 0 ;0,1,2=436,3=0.000000
L 4.50308376 2.98328327 4.48391634 2.98328327 1 P 0 ;0,1,2=436,3=0.000000
L 4.59 2.867 4.59 2.823 1 P 0 
L 4.5 2.867 4.59 2.867 1 P 0 
L 4.59 2.823 4.5 2.823 1 P 0 
L 4.5 2.823 4.5 2.867 1 P 0 
L 4.57806673 2.76291624 4.58036693 2.76446683 1 P 0 ;0,1,2=437,3=0.000000
L 4.58036693 2.76446683 4.5830497 2.7655 1 P 0 ;0,1,2=437,3=0.000000
L 4.5830497 2.7655 4.58611644 2.7655 1 P 0 ;0,1,2=437,3=0.000000
L 4.58611644 2.7655 4.58956713 2.76394931 1 P 0 ;0,1,2=437,3=0.000000
L 4.58956713 2.76394931 4.5922499 2.76136654 1 P 0 ;0,1,2=437,3=0.000000
L 4.5922499 2.76136654 4.59416683 2.75826624 1 P 0 ;0,1,2=437,3=0.000000
L 4.59416683 2.75826624 4.59570049 2.7530998 1 P 0 ;0,1,2=437,3=0.000000
L 4.59570049 2.7530998 4.59608376 2.7484498 1 P 0 ;0,1,2=437,3=0.000000
L 4.59608376 2.7484498 4.59531663 2.7437999 1 P 0 ;0,1,2=437,3=0.000000
L 4.59531663 2.7437999 4.59416683 2.74069961 1 P 0 ;0,1,2=437,3=0.000000
L 4.59416683 2.74069961 4.59186663 2.73759931 1 P 0 ;0,1,2=437,3=0.000000
L 4.59186663 2.73759931 4.58918317 2.73553307 1 P 0 ;0,1,2=437,3=0.000000
L 4.58918317 2.73553307 4.58650039 2.7345 1 P 0 ;0,1,2=437,3=0.000000
L 4.58650039 2.7345 4.58381693 2.7345 1 P 0 ;0,1,2=437,3=0.000000
L 4.58381693 2.7345 4.58113346 2.73553307 1 P 0 ;0,1,2=437,3=0.000000
L 4.58113346 2.73553307 4.57883327 2.73708278 1 P 0 ;0,1,2=437,3=0.000000
L 4.57883327 2.73708278 4.57691634 2.73914892 1 P 0 ;0,1,2=437,3=0.000000
L 4.56278356 2.76033346 4.56048337 2.76343278 1 P 0 ;0,1,2=437,3=0.000000
L 4.56048337 2.76343278 4.5577999 2.76498337 1 P 0 ;0,1,2=437,3=0.000000
L 4.5577999 2.76498337 4.55473317 2.7655 1 P 0 ;0,1,2=437,3=0.000000
L 4.55473317 2.7655 4.5509 2.76446683 1 P 0 ;0,1,2=437,3=0.000000
L 4.5509 2.76446683 4.54821654 2.76188307 1 P 0 ;0,1,2=437,3=0.000000
L 4.54821654 2.76188307 4.54745 2.75878376 1 P 0 ;0,1,2=437,3=0.000000
L 4.54745 2.75878376 4.54783327 2.75568258 1 P 0 ;0,1,2=437,3=0.000000
L 4.54783327 2.75568258 4.54936693 2.7530998 1 P 0 ;0,1,2=437,3=0.000000
L 4.54936693 2.7530998 4.55703337 2.74793327 1 P 0 ;0,1,2=437,3=0.000000
L 4.55703337 2.74793327 4.56048337 2.74431644 1 P 0 ;0,1,2=437,3=0.000000
L 4.56048337 2.74431644 4.56278356 2.73914892 1 P 0 ;0,1,2=437,3=0.000000
L 4.56278356 2.73914892 4.5635501 2.7345 1 P 0 ;0,1,2=437,3=0.000000
L 4.5635501 2.7345 4.54745 2.7345 1 P 0 ;0,1,2=437,3=0.000000
L 4.53178356 2.76033346 4.52948337 2.76343278 1 P 0 ;0,1,2=437,3=0.000000
L 4.52948337 2.76343278 4.5267999 2.76498337 1 P 0 ;0,1,2=437,3=0.000000
L 4.5267999 2.76498337 4.52373317 2.7655 1 P 0 ;0,1,2=437,3=0.000000
L 4.52373317 2.7655 4.5199 2.76446683 1 P 0 ;0,1,2=437,3=0.000000
L 4.5199 2.76446683 4.51721654 2.76188307 1 P 0 ;0,1,2=437,3=0.000000
L 4.51721654 2.76188307 4.51645 2.75878376 1 P 0 ;0,1,2=437,3=0.000000
L 4.51645 2.75878376 4.51683327 2.75568258 1 P 0 ;0,1,2=437,3=0.000000
L 4.51683327 2.75568258 4.51836693 2.7530998 1 P 0 ;0,1,2=437,3=0.000000
L 4.51836693 2.7530998 4.52603337 2.74793327 1 P 0 ;0,1,2=437,3=0.000000
L 4.52603337 2.74793327 4.52948337 2.74431644 1 P 0 ;0,1,2=437,3=0.000000
L 4.52948337 2.74431644 4.53178356 2.73914892 1 P 0 ;0,1,2=437,3=0.000000
L 4.53178356 2.73914892 4.5325501 2.7345 1 P 0 ;0,1,2=437,3=0.000000
L 4.5325501 2.7345 4.51645 2.7345 1 P 0 ;0,1,2=437,3=0.000000
L 4.50001713 2.73811585 4.49733366 2.73553307 1 P 0 ;0,1,2=437,3=0.000000
L 4.49733366 2.73553307 4.49426693 2.7345 1 P 0 ;0,1,2=437,3=0.000000
L 4.49426693 2.7345 4.4912002 2.73553307 1 P 0 ;0,1,2=437,3=0.000000
L 4.4912002 2.73553307 4.48851673 2.73863238 1 P 0 ;0,1,2=437,3=0.000000
L 4.48851673 2.73863238 4.4865998 2.74328327 1 P 0 ;0,1,2=437,3=0.000000
L 4.4865998 2.74328327 4.48583327 2.74793327 1 P 0 ;0,1,2=437,3=0.000000
L 4.48583327 2.74793327 4.48583327 2.75361634 1 P 0 ;0,1,2=437,3=0.000000
L 4.48583327 2.75361634 4.4865998 2.75826624 1 P 0 ;0,1,2=437,3=0.000000
L 4.4865998 2.75826624 4.48851673 2.7623997 1 P 0 ;0,1,2=437,3=0.000000
L 4.48851673 2.7623997 4.49081693 2.76446683 1 P 0 ;0,1,2=437,3=0.000000
L 4.49081693 2.76446683 4.49350039 2.7655 1 P 0 ;0,1,2=437,3=0.000000
L 4.49350039 2.7655 4.49656713 2.76446683 1 P 0 ;0,1,2=437,3=0.000000
L 4.49656713 2.76446683 4.49886663 2.7623997 1 P 0 ;0,1,2=437,3=0.000000
L 4.49886663 2.7623997 4.5004003 2.7593003 1 P 0 ;0,1,2=437,3=0.000000
L 4.5004003 2.7593003 4.50116683 2.75516594 1 P 0 ;0,1,2=437,3=0.000000
L 4.50116683 2.75516594 4.5004003 2.7515501 1 P 0 ;0,1,2=437,3=0.000000
L 4.5004003 2.7515501 4.49848337 2.74793327 1 P 0 ;0,1,2=437,3=0.000000
L 4.49848337 2.74793327 4.49618317 2.74586604 1 P 0 ;0,1,2=437,3=0.000000
L 4.49618317 2.74586604 4.49350039 2.74534951 1 P 0 ;0,1,2=437,3=0.000000
L 4.49350039 2.74534951 4.49043366 2.74638268 1 P 0 ;0,1,2=437,3=0.000000
L 4.49043366 2.74638268 4.48813346 2.74896634 1 P 0 ;0,1,2=437,3=0.000000
L 4.48813346 2.74896634 4.48583327 2.75361634 1 P 0 ;0,1,2=437,3=0.000000
L 5.057 3.92 5.057 3.83 1 P 0 
L 5.013 3.92 5.057 3.92 1 P 0 
L 5.057 3.83 5.013 3.83 1 P 0 
L 5.013 3.83 5.013 3.92 1 P 0 
L 5.03291624 3.74243327 5.03446683 3.74013307 1 P 0 ;0,1,2=438,3=90.000000
L 5.03446683 3.74013307 5.0355 3.7374503 1 P 0 ;0,1,2=438,3=90.000000
L 5.0355 3.7374503 5.0355 3.73438356 1 P 0 ;0,1,2=438,3=90.000000
L 5.0355 3.73438356 5.03394931 3.73093287 1 P 0 ;0,1,2=438,3=90.000000
L 5.03394931 3.73093287 5.03136654 3.7282501 1 P 0 ;0,1,2=438,3=90.000000
L 5.03136654 3.7282501 5.02826624 3.72633317 1 P 0 ;0,1,2=438,3=90.000000
L 5.02826624 3.72633317 5.0230998 3.72479951 1 P 0 ;0,1,2=438,3=90.000000
L 5.0230998 3.72479951 5.0184498 3.72441624 1 P 0 ;0,1,2=438,3=90.000000
L 5.0184498 3.72441624 5.0137999 3.72518337 1 P 0 ;0,1,2=438,3=90.000000
L 5.0137999 3.72518337 5.01069961 3.72633317 1 P 0 ;0,1,2=438,3=90.000000
L 5.01069961 3.72633317 5.00759931 3.72863337 1 P 0 ;0,1,2=438,3=90.000000
L 5.00759931 3.72863337 5.00553307 3.73131683 1 P 0 ;0,1,2=438,3=90.000000
L 5.00553307 3.73131683 5.0045 3.73399961 1 P 0 ;0,1,2=438,3=90.000000
L 5.0045 3.73399961 5.0045 3.73668307 1 P 0 ;0,1,2=438,3=90.000000
L 5.0045 3.73668307 5.00553307 3.73936654 1 P 0 ;0,1,2=438,3=90.000000
L 5.00553307 3.73936654 5.00708278 3.74166673 1 P 0 ;0,1,2=438,3=90.000000
L 5.00708278 3.74166673 5.00914892 3.74358366 1 P 0 ;0,1,2=438,3=90.000000
L 5.0045 3.76423307 5.01121614 3.76499961 1 P 0 ;0,1,2=438,3=90.000000
L 5.01121614 3.76499961 5.01689921 3.7661501 1 P 0 ;0,1,2=438,3=90.000000
L 5.01689921 3.7661501 5.02206663 3.76768307 1 P 0 ;0,1,2=438,3=90.000000
L 5.02206663 3.76768307 5.0277497 3.7696 1 P 0 ;0,1,2=438,3=90.000000
L 5.0277497 3.7696 5.0355 3.77266673 1 P 0 ;0,1,2=438,3=90.000000
L 5.0355 3.77266673 5.0355 3.75733317 1 P 0 ;0,1,2=438,3=90.000000
L 5.0045 3.79599961 5.00501654 3.79868307 1 P 0 ;0,1,2=438,3=90.000000
L 5.00501654 3.79868307 5.00656614 3.8017498 1 P 0 ;0,1,2=438,3=90.000000
L 5.00656614 3.8017498 5.00914892 3.80366673 1 P 0 ;0,1,2=438,3=90.000000
L 5.00914892 3.80366673 5.01276673 3.80443327 1 P 0 ;0,1,2=438,3=90.000000
L 5.01276673 3.80443327 5.01638268 3.80366673 1 P 0 ;0,1,2=438,3=90.000000
L 5.01638268 3.80366673 5.01948287 3.80136654 1 P 0 ;0,1,2=438,3=90.000000
L 5.01948287 3.80136654 5.02103356 3.79791654 1 P 0 ;0,1,2=438,3=90.000000
L 5.02103356 3.79791654 5.02103356 3.79408337 1 P 0 ;0,1,2=438,3=90.000000
L 5.02103356 3.79408337 5.02206663 3.79178317 1 P 0 ;0,1,2=438,3=90.000000
L 5.02206663 3.79178317 5.02464941 3.78986614 1 P 0 ;0,1,2=438,3=90.000000
L 5.02464941 3.78986614 5.02826624 3.7890997 1 P 0 ;0,1,2=438,3=90.000000
L 5.02826624 3.7890997 5.03188307 3.7902501 1 P 0 ;0,1,2=438,3=90.000000
L 5.03188307 3.7902501 5.03446683 3.79293287 1 P 0 ;0,1,2=438,3=90.000000
L 5.03446683 3.79293287 5.0355 3.79599961 1 P 0 ;0,1,2=438,3=90.000000
L 5.0355 3.79599961 5.03446683 3.79906634 1 P 0 ;0,1,2=438,3=90.000000
L 5.03446683 3.79906634 5.03188307 3.8017498 1 P 0 ;0,1,2=438,3=90.000000
L 5.03188307 3.8017498 5.02826624 3.8029002 1 P 0 ;0,1,2=438,3=90.000000
L 5.02826624 3.8029002 5.02464941 3.80213307 1 P 0 ;0,1,2=438,3=90.000000
L 5.02464941 3.80213307 5.02206663 3.80021673 1 P 0 ;0,1,2=438,3=90.000000
L 5.02206663 3.80021673 5.02103356 3.79791654 1 P 0 ;0,1,2=438,3=90.000000
L 5.02103356 3.79791654 5.02103356 3.79408337 1 P 0 ;0,1,2=438,3=90.000000
L 5.02103356 3.79408337 5.01948287 3.79063337 1 P 0 ;0,1,2=438,3=90.000000
L 5.01948287 3.79063337 5.01638268 3.78833317 1 P 0 ;0,1,2=438,3=90.000000
L 5.01638268 3.78833317 5.01276673 3.78756663 1 P 0 ;0,1,2=438,3=90.000000
L 5.01276673 3.78756663 5.00914892 3.78833317 1 P 0 ;0,1,2=438,3=90.000000
L 5.00914892 3.78833317 5.00656614 3.7902501 1 P 0 ;0,1,2=438,3=90.000000
L 5.00656614 3.7902501 5.00501654 3.79331683 1 P 0 ;0,1,2=438,3=90.000000
L 5.00501654 3.79331683 5.0045 3.79599961 1 P 0 ;0,1,2=438,3=90.000000
L 5.063 3.92 5.107 3.92 1 P 0 
L 5.107 3.92 5.107 3.83 1 P 0 
L 5.107 3.83 5.063 3.83 1 P 0 
L 5.063 3.83 5.063 3.92 1 P 0 
L 5.10291624 3.74743327 5.10446683 3.74513307 1 P 0 ;0,1,2=439,3=90.000000
L 5.10446683 3.74513307 5.1055 3.7424503 1 P 0 ;0,1,2=439,3=90.000000
L 5.1055 3.7424503 5.1055 3.73938356 1 P 0 ;0,1,2=439,3=90.000000
L 5.1055 3.73938356 5.10394931 3.73593287 1 P 0 ;0,1,2=439,3=90.000000
L 5.10394931 3.73593287 5.10136654 3.7332501 1 P 0 ;0,1,2=439,3=90.000000
L 5.10136654 3.7332501 5.09826624 3.73133317 1 P 0 ;0,1,2=439,3=90.000000
L 5.09826624 3.73133317 5.0930998 3.72979951 1 P 0 ;0,1,2=439,3=90.000000
L 5.0930998 3.72979951 5.0884498 3.72941624 1 P 0 ;0,1,2=439,3=90.000000
L 5.0884498 3.72941624 5.0837999 3.73018337 1 P 0 ;0,1,2=439,3=90.000000
L 5.0837999 3.73018337 5.08069961 3.73133317 1 P 0 ;0,1,2=439,3=90.000000
L 5.08069961 3.73133317 5.07759931 3.73363337 1 P 0 ;0,1,2=439,3=90.000000
L 5.07759931 3.73363337 5.07553307 3.73631683 1 P 0 ;0,1,2=439,3=90.000000
L 5.07553307 3.73631683 5.0745 3.73899961 1 P 0 ;0,1,2=439,3=90.000000
L 5.0745 3.73899961 5.0745 3.74168307 1 P 0 ;0,1,2=439,3=90.000000
L 5.0745 3.74168307 5.07553307 3.74436654 1 P 0 ;0,1,2=439,3=90.000000
L 5.07553307 3.74436654 5.07708278 3.74666673 1 P 0 ;0,1,2=439,3=90.000000
L 5.07708278 3.74666673 5.07914892 3.74858366 1 P 0 ;0,1,2=439,3=90.000000
L 5.0745 3.76923307 5.08121614 3.76999961 1 P 0 ;0,1,2=439,3=90.000000
L 5.08121614 3.76999961 5.08689921 3.7711501 1 P 0 ;0,1,2=439,3=90.000000
L 5.08689921 3.7711501 5.09206663 3.77268307 1 P 0 ;0,1,2=439,3=90.000000
L 5.09206663 3.77268307 5.0977497 3.7746 1 P 0 ;0,1,2=439,3=90.000000
L 5.0977497 3.7746 5.1055 3.77766673 1 P 0 ;0,1,2=439,3=90.000000
L 5.1055 3.77766673 5.1055 3.76233317 1 P 0 ;0,1,2=439,3=90.000000
L 5.08069961 3.79256663 5.07708278 3.79486614 1 P 0 ;0,1,2=439,3=90.000000
L 5.07708278 3.79486614 5.07501654 3.79793287 1 P 0 ;0,1,2=439,3=90.000000
L 5.07501654 3.79793287 5.0745 3.80138356 1 P 0 ;0,1,2=439,3=90.000000
L 5.0745 3.80138356 5.07501654 3.8044503 1 P 0 ;0,1,2=439,3=90.000000
L 5.07501654 3.8044503 5.07759931 3.80751703 1 P 0 ;0,1,2=439,3=90.000000
L 5.07759931 3.80751703 5.08069961 3.80943327 1 P 0 ;0,1,2=439,3=90.000000
L 5.08069961 3.80943327 5.0837999 3.80981654 1 P 0 ;0,1,2=439,3=90.000000
L 5.0837999 3.80981654 5.08741575 3.80905 1 P 0 ;0,1,2=439,3=90.000000
L 5.08741575 3.80905 5.08999951 3.80636654 1 P 0 ;0,1,2=439,3=90.000000
L 5.08999951 3.80636654 5.09103356 3.80368307 1 P 0 ;0,1,2=439,3=90.000000
L 5.09103356 3.80368307 5.09103356 3.80023307 1 P 0 ;0,1,2=439,3=90.000000
L 5.09103356 3.80368307 5.09258317 3.80598327 1 P 0 ;0,1,2=439,3=90.000000
L 5.09258317 3.80598327 5.09516594 3.8079002 1 P 0 ;0,1,2=439,3=90.000000
L 5.09516594 3.8079002 5.09826624 3.80866673 1 P 0 ;0,1,2=439,3=90.000000
L 5.09826624 3.80866673 5.10136654 3.8079002 1 P 0 ;0,1,2=439,3=90.000000
L 5.10136654 3.8079002 5.10394931 3.80598327 1 P 0 ;0,1,2=439,3=90.000000
L 5.10394931 3.80598327 5.1055 3.80253327 1 P 0 ;0,1,2=439,3=90.000000
L 5.1055 3.80253327 5.10498337 3.79908337 1 P 0 ;0,1,2=439,3=90.000000
L 5.10498337 3.79908337 5.10291624 3.79563337 1 P 0 ;0,1,2=439,3=90.000000
L 4.218 3.917 4.218 4.007 1 P 0 
L 4.218 4.007 4.262 4.007 1 P 0 
L 4.262 4.007 4.262 3.917 1 P 0 
L 4.262 3.917 4.218 3.917 1 P 0 
L 4.21291624 3.83693327 4.21446683 3.83463307 1 P 0 ;0,1,2=440,3=90.000000
L 4.21446683 3.83463307 4.2155 3.8319503 1 P 0 ;0,1,2=440,3=90.000000
L 4.2155 3.8319503 4.2155 3.82888356 1 P 0 ;0,1,2=440,3=90.000000
L 4.2155 3.82888356 4.21394931 3.82543287 1 P 0 ;0,1,2=440,3=90.000000
L 4.21394931 3.82543287 4.21136654 3.8227501 1 P 0 ;0,1,2=440,3=90.000000
L 4.21136654 3.8227501 4.20826624 3.82083317 1 P 0 ;0,1,2=440,3=90.000000
L 4.20826624 3.82083317 4.2030998 3.81929951 1 P 0 ;0,1,2=440,3=90.000000
L 4.2030998 3.81929951 4.1984498 3.81891624 1 P 0 ;0,1,2=440,3=90.000000
L 4.1984498 3.81891624 4.1937999 3.81968337 1 P 0 ;0,1,2=440,3=90.000000
L 4.1937999 3.81968337 4.19069961 3.82083317 1 P 0 ;0,1,2=440,3=90.000000
L 4.19069961 3.82083317 4.18759931 3.82313337 1 P 0 ;0,1,2=440,3=90.000000
L 4.18759931 3.82313337 4.18553307 3.82581683 1 P 0 ;0,1,2=440,3=90.000000
L 4.18553307 3.82581683 4.1845 3.82849961 1 P 0 ;0,1,2=440,3=90.000000
L 4.1845 3.82849961 4.1845 3.83118307 1 P 0 ;0,1,2=440,3=90.000000
L 4.1845 3.83118307 4.18553307 3.83386654 1 P 0 ;0,1,2=440,3=90.000000
L 4.18553307 3.83386654 4.18708278 3.83616673 1 P 0 ;0,1,2=440,3=90.000000
L 4.18708278 3.83616673 4.18914892 3.83808366 1 P 0 ;0,1,2=440,3=90.000000
L 4.19069961 3.85106663 4.18708278 3.85336614 1 P 0 ;0,1,2=440,3=90.000000
L 4.18708278 3.85336614 4.18501654 3.85643287 1 P 0 ;0,1,2=440,3=90.000000
L 4.18501654 3.85643287 4.1845 3.85988356 1 P 0 ;0,1,2=440,3=90.000000
L 4.1845 3.85988356 4.18501654 3.8629503 1 P 0 ;0,1,2=440,3=90.000000
L 4.18501654 3.8629503 4.18759931 3.86601703 1 P 0 ;0,1,2=440,3=90.000000
L 4.18759931 3.86601703 4.19069961 3.86793327 1 P 0 ;0,1,2=440,3=90.000000
L 4.19069961 3.86793327 4.1937999 3.86831654 1 P 0 ;0,1,2=440,3=90.000000
L 4.1937999 3.86831654 4.19741575 3.86755 1 P 0 ;0,1,2=440,3=90.000000
L 4.19741575 3.86755 4.19999951 3.86486654 1 P 0 ;0,1,2=440,3=90.000000
L 4.19999951 3.86486654 4.20103356 3.86218307 1 P 0 ;0,1,2=440,3=90.000000
L 4.20103356 3.86218307 4.20103356 3.85873307 1 P 0 ;0,1,2=440,3=90.000000
L 4.20103356 3.86218307 4.20258317 3.86448327 1 P 0 ;0,1,2=440,3=90.000000
L 4.20258317 3.86448327 4.20516594 3.8664002 1 P 0 ;0,1,2=440,3=90.000000
L 4.20516594 3.8664002 4.20826624 3.86716673 1 P 0 ;0,1,2=440,3=90.000000
L 4.20826624 3.86716673 4.21136654 3.8664002 1 P 0 ;0,1,2=440,3=90.000000
L 4.21136654 3.8664002 4.21394931 3.86448327 1 P 0 ;0,1,2=440,3=90.000000
L 4.21394931 3.86448327 4.2155 3.86103327 1 P 0 ;0,1,2=440,3=90.000000
L 4.2155 3.86103327 4.21498337 3.85758337 1 P 0 ;0,1,2=440,3=90.000000
L 4.21498337 3.85758337 4.21291624 3.85413337 1 P 0 ;0,1,2=440,3=90.000000
L 4.1845 3.89049961 4.2155 3.89049961 1 P 0 ;0,1,2=440,3=90.000000
L 4.2155 3.89049961 4.2093003 3.8858999 1 P 0 ;0,1,2=440,3=90.000000
L 4.1845 3.8858999 4.1845 3.89509931 1 P 0 ;0,1,2=440,3=90.000000
L 4.19741575 3.91421644 4.20103356 3.9168999 1 P 0 ;0,1,2=440,3=90.000000
L 4.20103356 3.9168999 4.2030998 3.9192001 1 P 0 ;0,1,2=440,3=90.000000
L 4.2030998 3.9192001 4.20413287 3.92226683 1 P 0 ;0,1,2=440,3=90.000000
L 4.20413287 3.92226683 4.2030998 3.9249503 1 P 0 ;0,1,2=440,3=90.000000
L 4.2030998 3.9249503 4.20103356 3.92686654 1 P 0 ;0,1,2=440,3=90.000000
L 4.20103356 3.92686654 4.19793327 3.9284002 1 P 0 ;0,1,2=440,3=90.000000
L 4.19793327 3.9284002 4.19431644 3.92878346 1 P 0 ;0,1,2=440,3=90.000000
L 4.19431644 3.92878346 4.19121614 3.9284002 1 P 0 ;0,1,2=440,3=90.000000
L 4.19121614 3.9284002 4.18811585 3.92686654 1 P 0 ;0,1,2=440,3=90.000000
L 4.18811585 3.92686654 4.18553307 3.92456634 1 P 0 ;0,1,2=440,3=90.000000
L 4.18553307 3.92456634 4.1845 3.92188356 1 P 0 ;0,1,2=440,3=90.000000
L 4.1845 3.92188356 4.18553307 3.91881683 1 P 0 ;0,1,2=440,3=90.000000
L 4.18553307 3.91881683 4.18863238 3.91613337 1 P 0 ;0,1,2=440,3=90.000000
L 4.18863238 3.91613337 4.19328327 3.9145997 1 P 0 ;0,1,2=440,3=90.000000
L 4.19328327 3.9145997 4.1984498 3.91421644 1 P 0 ;0,1,2=440,3=90.000000
L 4.1984498 3.91421644 4.20516594 3.91498287 1 P 0 ;0,1,2=440,3=90.000000
L 4.20516594 3.91498287 4.20878376 3.91613337 1 P 0 ;0,1,2=440,3=90.000000
L 4.20878376 3.91613337 4.2123997 3.91804961 1 P 0 ;0,1,2=440,3=90.000000
L 4.2123997 3.91804961 4.21498337 3.92073307 1 P 0 ;0,1,2=440,3=90.000000
L 4.21498337 3.92073307 4.2155 3.92341654 1 P 0 ;0,1,2=440,3=90.000000
L 4.2155 3.92341654 4.21446683 3.9261 1 P 0 ;0,1,2=440,3=90.000000
L 4.21446683 3.9261 4.21188307 3.92801703 1 P 0 ;0,1,2=440,3=90.000000
L 3.498 4.054 3.588 4.054 1 P 0 
L 3.588 4.054 3.588 4.01 1 P 0 
L 3.588 4.01 3.498 4.01 1 P 0 
L 3.498 4.01 3.498 4.054 1 P 0 
L 3.71306673 4.04291624 3.71536693 4.04446683 1 P 0 ;0,1,2=441,3=0.000000
L 3.71536693 4.04446683 3.7180497 4.0455 1 P 0 ;0,1,2=441,3=0.000000
L 3.7180497 4.0455 3.72111644 4.0455 1 P 0 ;0,1,2=441,3=0.000000
L 3.72111644 4.0455 3.72456713 4.04394931 1 P 0 ;0,1,2=441,3=0.000000
L 3.72456713 4.04394931 3.7272499 4.04136654 1 P 0 ;0,1,2=441,3=0.000000
L 3.7272499 4.04136654 3.72916683 4.03826624 1 P 0 ;0,1,2=441,3=0.000000
L 3.72916683 4.03826624 3.73070049 4.0330998 1 P 0 ;0,1,2=441,3=0.000000
L 3.73070049 4.0330998 3.73108376 4.0284498 1 P 0 ;0,1,2=441,3=0.000000
L 3.73108376 4.0284498 3.73031663 4.0237999 1 P 0 ;0,1,2=441,3=0.000000
L 3.73031663 4.0237999 3.72916683 4.02069961 1 P 0 ;0,1,2=441,3=0.000000
L 3.72916683 4.02069961 3.72686663 4.01759931 1 P 0 ;0,1,2=441,3=0.000000
L 3.72686663 4.01759931 3.72418317 4.01553307 1 P 0 ;0,1,2=441,3=0.000000
L 3.72418317 4.01553307 3.72150039 4.0145 1 P 0 ;0,1,2=441,3=0.000000
L 3.72150039 4.0145 3.71881693 4.0145 1 P 0 ;0,1,2=441,3=0.000000
L 3.71881693 4.0145 3.71613346 4.01553307 1 P 0 ;0,1,2=441,3=0.000000
L 3.71613346 4.01553307 3.71383327 4.01708278 1 P 0 ;0,1,2=441,3=0.000000
L 3.71383327 4.01708278 3.71191634 4.01914892 1 P 0 ;0,1,2=441,3=0.000000
L 3.69778356 4.04033346 3.69548337 4.04343278 1 P 0 ;0,1,2=441,3=0.000000
L 3.69548337 4.04343278 3.6927999 4.04498337 1 P 0 ;0,1,2=441,3=0.000000
L 3.6927999 4.04498337 3.68973317 4.0455 1 P 0 ;0,1,2=441,3=0.000000
L 3.68973317 4.0455 3.6859 4.04446683 1 P 0 ;0,1,2=441,3=0.000000
L 3.6859 4.04446683 3.68321654 4.04188307 1 P 0 ;0,1,2=441,3=0.000000
L 3.68321654 4.04188307 3.68245 4.03878376 1 P 0 ;0,1,2=441,3=0.000000
L 3.68245 4.03878376 3.68283327 4.03568258 1 P 0 ;0,1,2=441,3=0.000000
L 3.68283327 4.03568258 3.68436693 4.0330998 1 P 0 ;0,1,2=441,3=0.000000
L 3.68436693 4.0330998 3.69203337 4.02793327 1 P 0 ;0,1,2=441,3=0.000000
L 3.69203337 4.02793327 3.69548337 4.02431644 1 P 0 ;0,1,2=441,3=0.000000
L 3.69548337 4.02431644 3.69778356 4.01914892 1 P 0 ;0,1,2=441,3=0.000000
L 3.69778356 4.01914892 3.6985501 4.0145 1 P 0 ;0,1,2=441,3=0.000000
L 3.6985501 4.0145 3.68245 4.0145 1 P 0 ;0,1,2=441,3=0.000000
L 3.65950039 4.0145 3.65681693 4.01501654 1 P 0 ;0,1,2=441,3=0.000000
L 3.65681693 4.01501654 3.6537502 4.01656614 1 P 0 ;0,1,2=441,3=0.000000
L 3.6537502 4.01656614 3.65183327 4.01914892 1 P 0 ;0,1,2=441,3=0.000000
L 3.65183327 4.01914892 3.65106673 4.02276673 1 P 0 ;0,1,2=441,3=0.000000
L 3.65106673 4.02276673 3.65183327 4.02638268 1 P 0 ;0,1,2=441,3=0.000000
L 3.65183327 4.02638268 3.65413346 4.02948287 1 P 0 ;0,1,2=441,3=0.000000
L 3.65413346 4.02948287 3.65758346 4.03103356 1 P 0 ;0,1,2=441,3=0.000000
L 3.65758346 4.03103356 3.66141663 4.03103356 1 P 0 ;0,1,2=441,3=0.000000
L 3.66141663 4.03103356 3.66371683 4.03206663 1 P 0 ;0,1,2=441,3=0.000000
L 3.66371683 4.03206663 3.66563386 4.03464941 1 P 0 ;0,1,2=441,3=0.000000
L 3.66563386 4.03464941 3.6664003 4.03826624 1 P 0 ;0,1,2=441,3=0.000000
L 3.6664003 4.03826624 3.6652499 4.04188307 1 P 0 ;0,1,2=441,3=0.000000
L 3.6652499 4.04188307 3.66256713 4.04446683 1 P 0 ;0,1,2=441,3=0.000000
L 3.66256713 4.04446683 3.65950039 4.0455 1 P 0 ;0,1,2=441,3=0.000000
L 3.65950039 4.0455 3.65643366 4.04446683 1 P 0 ;0,1,2=441,3=0.000000
L 3.65643366 4.04446683 3.6537502 4.04188307 1 P 0 ;0,1,2=441,3=0.000000
L 3.6537502 4.04188307 3.6525998 4.03826624 1 P 0 ;0,1,2=441,3=0.000000
L 3.6525998 4.03826624 3.65336693 4.03464941 1 P 0 ;0,1,2=441,3=0.000000
L 3.65336693 4.03464941 3.65528327 4.03206663 1 P 0 ;0,1,2=441,3=0.000000
L 3.65528327 4.03206663 3.65758346 4.03103356 1 P 0 ;0,1,2=441,3=0.000000
L 3.65758346 4.03103356 3.66141663 4.03103356 1 P 0 ;0,1,2=441,3=0.000000
L 3.66141663 4.03103356 3.66486663 4.02948287 1 P 0 ;0,1,2=441,3=0.000000
L 3.66486663 4.02948287 3.66716683 4.02638268 1 P 0 ;0,1,2=441,3=0.000000
L 3.66716683 4.02638268 3.66793337 4.02276673 1 P 0 ;0,1,2=441,3=0.000000
L 3.66793337 4.02276673 3.66716683 4.01914892 1 P 0 ;0,1,2=441,3=0.000000
L 3.66716683 4.01914892 3.6652499 4.01656614 1 P 0 ;0,1,2=441,3=0.000000
L 3.6652499 4.01656614 3.66218317 4.01501654 1 P 0 ;0,1,2=441,3=0.000000
L 3.66218317 4.01501654 3.65950039 4.0145 1 P 0 ;0,1,2=441,3=0.000000
L 3.63578356 4.02741575 3.6331001 4.03103356 1 P 0 ;0,1,2=441,3=0.000000
L 3.6331001 4.03103356 3.6307999 4.0330998 1 P 0 ;0,1,2=441,3=0.000000
L 3.6307999 4.0330998 3.62773317 4.03413287 1 P 0 ;0,1,2=441,3=0.000000
L 3.62773317 4.03413287 3.6250497 4.0330998 1 P 0 ;0,1,2=441,3=0.000000
L 3.6250497 4.0330998 3.62313346 4.03103356 1 P 0 ;0,1,2=441,3=0.000000
L 3.62313346 4.03103356 3.6215998 4.02793327 1 P 0 ;0,1,2=441,3=0.000000
L 3.6215998 4.02793327 3.62121654 4.02431644 1 P 0 ;0,1,2=441,3=0.000000
L 3.62121654 4.02431644 3.6215998 4.02121614 1 P 0 ;0,1,2=441,3=0.000000
L 3.6215998 4.02121614 3.62313346 4.01811585 1 P 0 ;0,1,2=441,3=0.000000
L 3.62313346 4.01811585 3.62543366 4.01553307 1 P 0 ;0,1,2=441,3=0.000000
L 3.62543366 4.01553307 3.62811644 4.0145 1 P 0 ;0,1,2=441,3=0.000000
L 3.62811644 4.0145 3.63118317 4.01553307 1 P 0 ;0,1,2=441,3=0.000000
L 3.63118317 4.01553307 3.63386663 4.01863238 1 P 0 ;0,1,2=441,3=0.000000
L 3.63386663 4.01863238 3.6354003 4.02328327 1 P 0 ;0,1,2=441,3=0.000000
L 3.6354003 4.02328327 3.63578356 4.0284498 1 P 0 ;0,1,2=441,3=0.000000
L 3.63578356 4.0284498 3.63501713 4.03516594 1 P 0 ;0,1,2=441,3=0.000000
L 3.63501713 4.03516594 3.63386663 4.03878376 1 P 0 ;0,1,2=441,3=0.000000
L 3.63386663 4.03878376 3.63195039 4.0423997 1 P 0 ;0,1,2=441,3=0.000000
L 3.63195039 4.0423997 3.62926693 4.04498337 1 P 0 ;0,1,2=441,3=0.000000
L 3.62926693 4.04498337 3.62658346 4.0455 1 P 0 ;0,1,2=441,3=0.000000
L 3.62658346 4.0455 3.6239 4.04446683 1 P 0 ;0,1,2=441,3=0.000000
L 3.6239 4.04446683 3.62198297 4.04188307 1 P 0 ;0,1,2=441,3=0.000000
L 3.588 3.92 3.498 3.92 1 P 0 
L 3.498 3.92 3.498 3.964 1 P 0 
L 3.498 3.964 3.588 3.964 1 P 0 
L 3.588 3.964 3.588 3.92 1 P 0 
L 3.71056673 3.95491624 3.71286693 3.95646683 1 P 0 ;0,1,2=442,3=0.000000
L 3.71286693 3.95646683 3.7155497 3.9575 1 P 0 ;0,1,2=442,3=0.000000
L 3.7155497 3.9575 3.71861644 3.9575 1 P 0 ;0,1,2=442,3=0.000000
L 3.71861644 3.9575 3.72206713 3.95594931 1 P 0 ;0,1,2=442,3=0.000000
L 3.72206713 3.95594931 3.7247499 3.95336654 1 P 0 ;0,1,2=442,3=0.000000
L 3.7247499 3.95336654 3.72666683 3.95026624 1 P 0 ;0,1,2=442,3=0.000000
L 3.72666683 3.95026624 3.72820049 3.9450998 1 P 0 ;0,1,2=442,3=0.000000
L 3.72820049 3.9450998 3.72858376 3.9404498 1 P 0 ;0,1,2=442,3=0.000000
L 3.72858376 3.9404498 3.72781663 3.9357999 1 P 0 ;0,1,2=442,3=0.000000
L 3.72781663 3.9357999 3.72666683 3.93269961 1 P 0 ;0,1,2=442,3=0.000000
L 3.72666683 3.93269961 3.72436663 3.92959931 1 P 0 ;0,1,2=442,3=0.000000
L 3.72436663 3.92959931 3.72168317 3.92753307 1 P 0 ;0,1,2=442,3=0.000000
L 3.72168317 3.92753307 3.71900039 3.9265 1 P 0 ;0,1,2=442,3=0.000000
L 3.71900039 3.9265 3.71631693 3.9265 1 P 0 ;0,1,2=442,3=0.000000
L 3.71631693 3.9265 3.71363346 3.92753307 1 P 0 ;0,1,2=442,3=0.000000
L 3.71363346 3.92753307 3.71133327 3.92908278 1 P 0 ;0,1,2=442,3=0.000000
L 3.71133327 3.92908278 3.70941634 3.93114892 1 P 0 ;0,1,2=442,3=0.000000
L 3.69643337 3.93114892 3.69413386 3.92856614 1 P 0 ;0,1,2=442,3=0.000000
L 3.69413386 3.92856614 3.69145039 3.92701654 1 P 0 ;0,1,2=442,3=0.000000
L 3.69145039 3.92701654 3.68800039 3.9265 1 P 0 ;0,1,2=442,3=0.000000
L 3.68800039 3.9265 3.6845497 3.92753307 1 P 0 ;0,1,2=442,3=0.000000
L 3.6845497 3.92753307 3.68186693 3.92959931 1 P 0 ;0,1,2=442,3=0.000000
L 3.68186693 3.92959931 3.67995 3.93321614 1 P 0 ;0,1,2=442,3=0.000000
L 3.67995 3.93321614 3.67956673 3.93734951 1 P 0 ;0,1,2=442,3=0.000000
L 3.67956673 3.93734951 3.68033327 3.94148287 1 P 0 ;0,1,2=442,3=0.000000
L 3.68033327 3.94148287 3.6822502 3.94406663 1 P 0 ;0,1,2=442,3=0.000000
L 3.6822502 3.94406663 3.68493366 3.94613287 1 P 0 ;0,1,2=442,3=0.000000
L 3.68493366 3.94613287 3.68761644 3.94664941 1 P 0 ;0,1,2=442,3=0.000000
L 3.68761644 3.94664941 3.6902999 3.94613287 1 P 0 ;0,1,2=442,3=0.000000
L 3.6902999 3.94613287 3.6937499 3.94406663 1 P 0 ;0,1,2=442,3=0.000000
L 3.6937499 3.94406663 3.6926001 3.9575 1 P 0 ;0,1,2=442,3=0.000000
L 3.6926001 3.9575 3.6822502 3.9575 1 P 0 ;0,1,2=442,3=0.000000
L 3.6524 3.9265 3.6524 3.9575 1 P 0 ;0,1,2=442,3=0.000000
L 3.6524 3.9575 3.66658376 3.93528327 1 P 0 ;0,1,2=442,3=0.000000
L 3.66658376 3.93528327 3.64741634 3.93528327 1 P 0 ;0,1,2=442,3=0.000000
L 3.31 4.092 3.31 4.048 1 P 0 
L 3.22 4.092 3.31 4.092 1 P 0 
L 3.31 4.048 3.22 4.048 1 P 0 
L 3.22 4.048 3.22 4.092 1 P 0 
L 3.19256673 4.08291624 3.19486693 4.08446683 1 P 0 ;0,1,2=443,3=0.000000
L 3.19486693 4.08446683 3.1975497 4.0855 1 P 0 ;0,1,2=443,3=0.000000
L 3.1975497 4.0855 3.20061644 4.0855 1 P 0 ;0,1,2=443,3=0.000000
L 3.20061644 4.0855 3.20406713 4.08394931 1 P 0 ;0,1,2=443,3=0.000000
L 3.20406713 4.08394931 3.2067499 4.08136654 1 P 0 ;0,1,2=443,3=0.000000
L 3.2067499 4.08136654 3.20866683 4.07826624 1 P 0 ;0,1,2=443,3=0.000000
L 3.20866683 4.07826624 3.21020049 4.0730998 1 P 0 ;0,1,2=443,3=0.000000
L 3.21020049 4.0730998 3.21058376 4.0684498 1 P 0 ;0,1,2=443,3=0.000000
L 3.21058376 4.0684498 3.20981663 4.0637999 1 P 0 ;0,1,2=443,3=0.000000
L 3.20981663 4.0637999 3.20866683 4.06069961 1 P 0 ;0,1,2=443,3=0.000000
L 3.20866683 4.06069961 3.20636663 4.05759931 1 P 0 ;0,1,2=443,3=0.000000
L 3.20636663 4.05759931 3.20368317 4.05553307 1 P 0 ;0,1,2=443,3=0.000000
L 3.20368317 4.05553307 3.20100039 4.0545 1 P 0 ;0,1,2=443,3=0.000000
L 3.20100039 4.0545 3.19831693 4.0545 1 P 0 ;0,1,2=443,3=0.000000
L 3.19831693 4.0545 3.19563346 4.05553307 1 P 0 ;0,1,2=443,3=0.000000
L 3.19563346 4.05553307 3.19333327 4.05708278 1 P 0 ;0,1,2=443,3=0.000000
L 3.19333327 4.05708278 3.19141634 4.05914892 1 P 0 ;0,1,2=443,3=0.000000
L 3.17843337 4.05914892 3.17613386 4.05656614 1 P 0 ;0,1,2=443,3=0.000000
L 3.17613386 4.05656614 3.17345039 4.05501654 1 P 0 ;0,1,2=443,3=0.000000
L 3.17345039 4.05501654 3.17000039 4.0545 1 P 0 ;0,1,2=443,3=0.000000
L 3.17000039 4.0545 3.1665497 4.05553307 1 P 0 ;0,1,2=443,3=0.000000
L 3.1665497 4.05553307 3.16386693 4.05759931 1 P 0 ;0,1,2=443,3=0.000000
L 3.16386693 4.05759931 3.16195 4.06121614 1 P 0 ;0,1,2=443,3=0.000000
L 3.16195 4.06121614 3.16156673 4.06534951 1 P 0 ;0,1,2=443,3=0.000000
L 3.16156673 4.06534951 3.16233327 4.06948287 1 P 0 ;0,1,2=443,3=0.000000
L 3.16233327 4.06948287 3.1642502 4.07206663 1 P 0 ;0,1,2=443,3=0.000000
L 3.1642502 4.07206663 3.16693366 4.07413287 1 P 0 ;0,1,2=443,3=0.000000
L 3.16693366 4.07413287 3.16961644 4.07464941 1 P 0 ;0,1,2=443,3=0.000000
L 3.16961644 4.07464941 3.1722999 4.07413287 1 P 0 ;0,1,2=443,3=0.000000
L 3.1722999 4.07413287 3.1757499 4.07206663 1 P 0 ;0,1,2=443,3=0.000000
L 3.1757499 4.07206663 3.1746001 4.0855 1 P 0 ;0,1,2=443,3=0.000000
L 3.1746001 4.0855 3.1642502 4.0855 1 P 0 ;0,1,2=443,3=0.000000
L 3.14628356 4.06741575 3.1436001 4.07103356 1 P 0 ;0,1,2=443,3=0.000000
L 3.1436001 4.07103356 3.1412999 4.0730998 1 P 0 ;0,1,2=443,3=0.000000
L 3.1412999 4.0730998 3.13823317 4.07413287 1 P 0 ;0,1,2=443,3=0.000000
L 3.13823317 4.07413287 3.1355497 4.0730998 1 P 0 ;0,1,2=443,3=0.000000
L 3.1355497 4.0730998 3.13363346 4.07103356 1 P 0 ;0,1,2=443,3=0.000000
L 3.13363346 4.07103356 3.1320998 4.06793327 1 P 0 ;0,1,2=443,3=0.000000
L 3.1320998 4.06793327 3.13171654 4.06431644 1 P 0 ;0,1,2=443,3=0.000000
L 3.13171654 4.06431644 3.1320998 4.06121614 1 P 0 ;0,1,2=443,3=0.000000
L 3.1320998 4.06121614 3.13363346 4.05811585 1 P 0 ;0,1,2=443,3=0.000000
L 3.13363346 4.05811585 3.13593366 4.05553307 1 P 0 ;0,1,2=443,3=0.000000
L 3.13593366 4.05553307 3.13861644 4.0545 1 P 0 ;0,1,2=443,3=0.000000
L 3.13861644 4.0545 3.14168317 4.05553307 1 P 0 ;0,1,2=443,3=0.000000
L 3.14168317 4.05553307 3.14436663 4.05863238 1 P 0 ;0,1,2=443,3=0.000000
L 3.14436663 4.05863238 3.1459003 4.06328327 1 P 0 ;0,1,2=443,3=0.000000
L 3.1459003 4.06328327 3.14628356 4.0684498 1 P 0 ;0,1,2=443,3=0.000000
L 3.14628356 4.0684498 3.14551713 4.07516594 1 P 0 ;0,1,2=443,3=0.000000
L 3.14551713 4.07516594 3.14436663 4.07878376 1 P 0 ;0,1,2=443,3=0.000000
L 3.14436663 4.07878376 3.14245039 4.0823997 1 P 0 ;0,1,2=443,3=0.000000
L 3.14245039 4.0823997 3.13976693 4.08498337 1 P 0 ;0,1,2=443,3=0.000000
L 3.13976693 4.08498337 3.13708346 4.0855 1 P 0 ;0,1,2=443,3=0.000000
L 3.13708346 4.0855 3.1344 4.08446683 1 P 0 ;0,1,2=443,3=0.000000
L 3.1344 4.08446683 3.13248297 4.08188307 1 P 0 ;0,1,2=443,3=0.000000
L 4.59 3.917 4.68 3.917 1 P 0 
L 4.68 3.873 4.59 3.873 1 P 0 
L 4.59 3.873 4.59 3.917 1 P 0 
L 4.68 3.917 4.68 3.873 1 P 0 
L 4.61756673 3.85791624 4.61986693 3.85946683 1 P 0 ;0,1,2=444,3=0.000000
L 4.61986693 3.85946683 4.6225497 3.8605 1 P 0 ;0,1,2=444,3=0.000000
L 4.6225497 3.8605 4.62561644 3.8605 1 P 0 ;0,1,2=444,3=0.000000
L 4.62561644 3.8605 4.62906713 3.85894931 1 P 0 ;0,1,2=444,3=0.000000
L 4.62906713 3.85894931 4.6317499 3.85636654 1 P 0 ;0,1,2=444,3=0.000000
L 4.6317499 3.85636654 4.63366683 3.85326624 1 P 0 ;0,1,2=444,3=0.000000
L 4.63366683 3.85326624 4.63520049 3.8480998 1 P 0 ;0,1,2=444,3=0.000000
L 4.63520049 3.8480998 4.63558376 3.8434498 1 P 0 ;0,1,2=444,3=0.000000
L 4.63558376 3.8434498 4.63481663 3.8387999 1 P 0 ;0,1,2=444,3=0.000000
L 4.63481663 3.8387999 4.63366683 3.83569961 1 P 0 ;0,1,2=444,3=0.000000
L 4.63366683 3.83569961 4.63136663 3.83259931 1 P 0 ;0,1,2=444,3=0.000000
L 4.63136663 3.83259931 4.62868317 3.83053307 1 P 0 ;0,1,2=444,3=0.000000
L 4.62868317 3.83053307 4.62600039 3.8295 1 P 0 ;0,1,2=444,3=0.000000
L 4.62600039 3.8295 4.62331693 3.8295 1 P 0 ;0,1,2=444,3=0.000000
L 4.62331693 3.8295 4.62063346 3.83053307 1 P 0 ;0,1,2=444,3=0.000000
L 4.62063346 3.83053307 4.61833327 3.83208278 1 P 0 ;0,1,2=444,3=0.000000
L 4.61833327 3.83208278 4.61641634 3.83414892 1 P 0 ;0,1,2=444,3=0.000000
L 4.59500039 3.8295 4.59231693 3.83001654 1 P 0 ;0,1,2=444,3=0.000000
L 4.59231693 3.83001654 4.5892502 3.83156614 1 P 0 ;0,1,2=444,3=0.000000
L 4.5892502 3.83156614 4.58733327 3.83414892 1 P 0 ;0,1,2=444,3=0.000000
L 4.58733327 3.83414892 4.58656673 3.83776673 1 P 0 ;0,1,2=444,3=0.000000
L 4.58656673 3.83776673 4.58733327 3.84138268 1 P 0 ;0,1,2=444,3=0.000000
L 4.58733327 3.84138268 4.58963346 3.84448287 1 P 0 ;0,1,2=444,3=0.000000
L 4.58963346 3.84448287 4.59308346 3.84603356 1 P 0 ;0,1,2=444,3=0.000000
L 4.59308346 3.84603356 4.59691663 3.84603356 1 P 0 ;0,1,2=444,3=0.000000
L 4.59691663 3.84603356 4.59921683 3.84706663 1 P 0 ;0,1,2=444,3=0.000000
L 4.59921683 3.84706663 4.60113386 3.84964941 1 P 0 ;0,1,2=444,3=0.000000
L 4.60113386 3.84964941 4.6019003 3.85326624 1 P 0 ;0,1,2=444,3=0.000000
L 4.6019003 3.85326624 4.6007499 3.85688307 1 P 0 ;0,1,2=444,3=0.000000
L 4.6007499 3.85688307 4.59806713 3.85946683 1 P 0 ;0,1,2=444,3=0.000000
L 4.59806713 3.85946683 4.59500039 3.8605 1 P 0 ;0,1,2=444,3=0.000000
L 4.59500039 3.8605 4.59193366 3.85946683 1 P 0 ;0,1,2=444,3=0.000000
L 4.59193366 3.85946683 4.5892502 3.85688307 1 P 0 ;0,1,2=444,3=0.000000
L 4.5892502 3.85688307 4.5880998 3.85326624 1 P 0 ;0,1,2=444,3=0.000000
L 4.5880998 3.85326624 4.58886693 3.84964941 1 P 0 ;0,1,2=444,3=0.000000
L 4.58886693 3.84964941 4.59078327 3.84706663 1 P 0 ;0,1,2=444,3=0.000000
L 4.59078327 3.84706663 4.59308346 3.84603356 1 P 0 ;0,1,2=444,3=0.000000
L 4.59308346 3.84603356 4.59691663 3.84603356 1 P 0 ;0,1,2=444,3=0.000000
L 4.59691663 3.84603356 4.60036663 3.84448287 1 P 0 ;0,1,2=444,3=0.000000
L 4.60036663 3.84448287 4.60266683 3.84138268 1 P 0 ;0,1,2=444,3=0.000000
L 4.60266683 3.84138268 4.60343337 3.83776673 1 P 0 ;0,1,2=444,3=0.000000
L 4.60343337 3.83776673 4.60266683 3.83414892 1 P 0 ;0,1,2=444,3=0.000000
L 4.60266683 3.83414892 4.6007499 3.83156614 1 P 0 ;0,1,2=444,3=0.000000
L 4.6007499 3.83156614 4.59768317 3.83001654 1 P 0 ;0,1,2=444,3=0.000000
L 4.59768317 3.83001654 4.59500039 3.8295 1 P 0 ;0,1,2=444,3=0.000000
L 4.56400039 3.8605 4.56706713 3.85946683 1 P 0 ;0,1,2=444,3=0.000000
L 4.56706713 3.85946683 4.56936663 3.85688307 1 P 0 ;0,1,2=444,3=0.000000
L 4.56936663 3.85688307 4.5709003 3.85378376 1 P 0 ;0,1,2=444,3=0.000000
L 4.5709003 3.85378376 4.5720501 3.84964941 1 P 0 ;0,1,2=444,3=0.000000
L 4.5720501 3.84964941 4.57243337 3.84499951 1 P 0 ;0,1,2=444,3=0.000000
L 4.57243337 3.84499951 4.5720501 3.84034951 1 P 0 ;0,1,2=444,3=0.000000
L 4.5720501 3.84034951 4.5709003 3.83621614 1 P 0 ;0,1,2=444,3=0.000000
L 4.5709003 3.83621614 4.56936663 3.83311585 1 P 0 ;0,1,2=444,3=0.000000
L 4.56936663 3.83311585 4.56706713 3.83053307 1 P 0 ;0,1,2=444,3=0.000000
L 4.56706713 3.83053307 4.56400039 3.8295 1 P 0 ;0,1,2=444,3=0.000000
L 4.56400039 3.8295 4.56093366 3.83053307 1 P 0 ;0,1,2=444,3=0.000000
L 4.56093366 3.83053307 4.55863346 3.83311585 1 P 0 ;0,1,2=444,3=0.000000
L 4.55863346 3.83311585 4.5570998 3.83621614 1 P 0 ;0,1,2=444,3=0.000000
L 4.5570998 3.83621614 4.55595 3.84034951 1 P 0 ;0,1,2=444,3=0.000000
L 4.55595 3.84034951 4.55556673 3.84499951 1 P 0 ;0,1,2=444,3=0.000000
L 4.55556673 3.84499951 4.55595 3.84964941 1 P 0 ;0,1,2=444,3=0.000000
L 4.55595 3.84964941 4.5570998 3.85378376 1 P 0 ;0,1,2=444,3=0.000000
L 4.5570998 3.85378376 4.55863346 3.85688307 1 P 0 ;0,1,2=444,3=0.000000
L 4.55863346 3.85688307 4.56093366 3.85946683 1 P 0 ;0,1,2=444,3=0.000000
L 4.56093366 3.85946683 4.56400039 3.8605 1 P 0 ;0,1,2=444,3=0.000000
L 4.68 3.918 4.59 3.918 1 P 0 
L 4.59 3.918 4.59 3.962 1 P 0 
L 4.59 3.962 4.68 3.962 1 P 0 
L 4.68 3.962 4.68 3.918 1 P 0 
L 4.61806673 4.01291624 4.62036693 4.01446683 1 P 0 ;0,1,2=445,3=0.000000
L 4.62036693 4.01446683 4.6230497 4.0155 1 P 0 ;0,1,2=445,3=0.000000
L 4.6230497 4.0155 4.62611644 4.0155 1 P 0 ;0,1,2=445,3=0.000000
L 4.62611644 4.0155 4.62956713 4.01394931 1 P 0 ;0,1,2=445,3=0.000000
L 4.62956713 4.01394931 4.6322499 4.01136654 1 P 0 ;0,1,2=445,3=0.000000
L 4.6322499 4.01136654 4.63416683 4.00826624 1 P 0 ;0,1,2=445,3=0.000000
L 4.63416683 4.00826624 4.63570049 4.0030998 1 P 0 ;0,1,2=445,3=0.000000
L 4.63570049 4.0030998 4.63608376 3.9984498 1 P 0 ;0,1,2=445,3=0.000000
L 4.63608376 3.9984498 4.63531663 3.9937999 1 P 0 ;0,1,2=445,3=0.000000
L 4.63531663 3.9937999 4.63416683 3.99069961 1 P 0 ;0,1,2=445,3=0.000000
L 4.63416683 3.99069961 4.63186663 3.98759931 1 P 0 ;0,1,2=445,3=0.000000
L 4.63186663 3.98759931 4.62918317 3.98553307 1 P 0 ;0,1,2=445,3=0.000000
L 4.62918317 3.98553307 4.62650039 3.9845 1 P 0 ;0,1,2=445,3=0.000000
L 4.62650039 3.9845 4.62381693 3.9845 1 P 0 ;0,1,2=445,3=0.000000
L 4.62381693 3.9845 4.62113346 3.98553307 1 P 0 ;0,1,2=445,3=0.000000
L 4.62113346 3.98553307 4.61883327 3.98708278 1 P 0 ;0,1,2=445,3=0.000000
L 4.61883327 3.98708278 4.61691634 3.98914892 1 P 0 ;0,1,2=445,3=0.000000
L 4.60278356 4.01033346 4.60048337 4.01343278 1 P 0 ;0,1,2=445,3=0.000000
L 4.60048337 4.01343278 4.5977999 4.01498337 1 P 0 ;0,1,2=445,3=0.000000
L 4.5977999 4.01498337 4.59473317 4.0155 1 P 0 ;0,1,2=445,3=0.000000
L 4.59473317 4.0155 4.5909 4.01446683 1 P 0 ;0,1,2=445,3=0.000000
L 4.5909 4.01446683 4.58821654 4.01188307 1 P 0 ;0,1,2=445,3=0.000000
L 4.58821654 4.01188307 4.58745 4.00878376 1 P 0 ;0,1,2=445,3=0.000000
L 4.58745 4.00878376 4.58783327 4.00568258 1 P 0 ;0,1,2=445,3=0.000000
L 4.58783327 4.00568258 4.58936693 4.0030998 1 P 0 ;0,1,2=445,3=0.000000
L 4.58936693 4.0030998 4.59703337 3.99793327 1 P 0 ;0,1,2=445,3=0.000000
L 4.59703337 3.99793327 4.60048337 3.99431644 1 P 0 ;0,1,2=445,3=0.000000
L 4.60048337 3.99431644 4.60278356 3.98914892 1 P 0 ;0,1,2=445,3=0.000000
L 4.60278356 3.98914892 4.6035501 3.9845 1 P 0 ;0,1,2=445,3=0.000000
L 4.6035501 3.9845 4.58745 3.9845 1 P 0 ;0,1,2=445,3=0.000000
L 4.56526693 3.9845 4.56450039 3.99121614 1 P 0 ;0,1,2=445,3=0.000000
L 4.56450039 3.99121614 4.5633499 3.99689921 1 P 0 ;0,1,2=445,3=0.000000
L 4.5633499 3.99689921 4.56181693 4.00206663 1 P 0 ;0,1,2=445,3=0.000000
L 4.56181693 4.00206663 4.5599 4.0077497 1 P 0 ;0,1,2=445,3=0.000000
L 4.5599 4.0077497 4.55683327 4.0155 1 P 0 ;0,1,2=445,3=0.000000
L 4.55683327 4.0155 4.57216683 4.0155 1 P 0 ;0,1,2=445,3=0.000000
L 4.54193337 3.99069961 4.53963386 3.98708278 1 P 0 ;0,1,2=445,3=0.000000
L 4.53963386 3.98708278 4.53656713 3.98501654 1 P 0 ;0,1,2=445,3=0.000000
L 4.53656713 3.98501654 4.53311644 3.9845 1 P 0 ;0,1,2=445,3=0.000000
L 4.53311644 3.9845 4.5300497 3.98501654 1 P 0 ;0,1,2=445,3=0.000000
L 4.5300497 3.98501654 4.52698297 3.98759931 1 P 0 ;0,1,2=445,3=0.000000
L 4.52698297 3.98759931 4.52506673 3.99069961 1 P 0 ;0,1,2=445,3=0.000000
L 4.52506673 3.99069961 4.52468346 3.9937999 1 P 0 ;0,1,2=445,3=0.000000
L 4.52468346 3.9937999 4.52545 3.99741575 1 P 0 ;0,1,2=445,3=0.000000
L 4.52545 3.99741575 4.52813346 3.99999951 1 P 0 ;0,1,2=445,3=0.000000
L 4.52813346 3.99999951 4.53081693 4.00103356 1 P 0 ;0,1,2=445,3=0.000000
L 4.53081693 4.00103356 4.53426693 4.00103356 1 P 0 ;0,1,2=445,3=0.000000
L 4.53081693 4.00103356 4.52851673 4.00258317 1 P 0 ;0,1,2=445,3=0.000000
L 4.52851673 4.00258317 4.5265998 4.00516594 1 P 0 ;0,1,2=445,3=0.000000
L 4.5265998 4.00516594 4.52583327 4.00826624 1 P 0 ;0,1,2=445,3=0.000000
L 4.52583327 4.00826624 4.5265998 4.01136654 1 P 0 ;0,1,2=445,3=0.000000
L 4.5265998 4.01136654 4.52851673 4.01394931 1 P 0 ;0,1,2=445,3=0.000000
L 4.52851673 4.01394931 4.53196673 4.0155 1 P 0 ;0,1,2=445,3=0.000000
L 4.53196673 4.0155 4.53541663 4.01498337 1 P 0 ;0,1,2=445,3=0.000000
L 4.53541663 4.01498337 4.53886663 4.01291624 1 P 0 ;0,1,2=445,3=0.000000
L 4.42 3.987 4.42 3.943 1 P 0 
L 4.33 3.987 4.42 3.987 1 P 0 
L 4.42 3.943 4.33 3.943 1 P 0 
L 4.33 3.943 4.33 3.987 1 P 0 
L 4.44306673 3.92791624 4.44536693 3.92946683 1 P 0 ;0,1,2=446,3=0.000000
L 4.44536693 3.92946683 4.4480497 3.9305 1 P 0 ;0,1,2=446,3=0.000000
L 4.4480497 3.9305 4.45111644 3.9305 1 P 0 ;0,1,2=446,3=0.000000
L 4.45111644 3.9305 4.45456713 3.92894931 1 P 0 ;0,1,2=446,3=0.000000
L 4.45456713 3.92894931 4.4572499 3.92636654 1 P 0 ;0,1,2=446,3=0.000000
L 4.4572499 3.92636654 4.45916683 3.92326624 1 P 0 ;0,1,2=446,3=0.000000
L 4.45916683 3.92326624 4.46070049 3.9180998 1 P 0 ;0,1,2=446,3=0.000000
L 4.46070049 3.9180998 4.46108376 3.9134498 1 P 0 ;0,1,2=446,3=0.000000
L 4.46108376 3.9134498 4.46031663 3.9087999 1 P 0 ;0,1,2=446,3=0.000000
L 4.46031663 3.9087999 4.45916683 3.90569961 1 P 0 ;0,1,2=446,3=0.000000
L 4.45916683 3.90569961 4.45686663 3.90259931 1 P 0 ;0,1,2=446,3=0.000000
L 4.45686663 3.90259931 4.45418317 3.90053307 1 P 0 ;0,1,2=446,3=0.000000
L 4.45418317 3.90053307 4.45150039 3.8995 1 P 0 ;0,1,2=446,3=0.000000
L 4.45150039 3.8995 4.44881693 3.8995 1 P 0 ;0,1,2=446,3=0.000000
L 4.44881693 3.8995 4.44613346 3.90053307 1 P 0 ;0,1,2=446,3=0.000000
L 4.44613346 3.90053307 4.44383327 3.90208278 1 P 0 ;0,1,2=446,3=0.000000
L 4.44383327 3.90208278 4.44191634 3.90414892 1 P 0 ;0,1,2=446,3=0.000000
L 4.42893337 3.90569961 4.42663386 3.90208278 1 P 0 ;0,1,2=446,3=0.000000
L 4.42663386 3.90208278 4.42356713 3.90001654 1 P 0 ;0,1,2=446,3=0.000000
L 4.42356713 3.90001654 4.42011644 3.8995 1 P 0 ;0,1,2=446,3=0.000000
L 4.42011644 3.8995 4.4170497 3.90001654 1 P 0 ;0,1,2=446,3=0.000000
L 4.4170497 3.90001654 4.41398297 3.90259931 1 P 0 ;0,1,2=446,3=0.000000
L 4.41398297 3.90259931 4.41206673 3.90569961 1 P 0 ;0,1,2=446,3=0.000000
L 4.41206673 3.90569961 4.41168346 3.9087999 1 P 0 ;0,1,2=446,3=0.000000
L 4.41168346 3.9087999 4.41245 3.91241575 1 P 0 ;0,1,2=446,3=0.000000
L 4.41245 3.91241575 4.41513346 3.91499951 1 P 0 ;0,1,2=446,3=0.000000
L 4.41513346 3.91499951 4.41781693 3.91603356 1 P 0 ;0,1,2=446,3=0.000000
L 4.41781693 3.91603356 4.42126693 3.91603356 1 P 0 ;0,1,2=446,3=0.000000
L 4.41781693 3.91603356 4.41551673 3.91758317 1 P 0 ;0,1,2=446,3=0.000000
L 4.41551673 3.91758317 4.4135998 3.92016594 1 P 0 ;0,1,2=446,3=0.000000
L 4.4135998 3.92016594 4.41283327 3.92326624 1 P 0 ;0,1,2=446,3=0.000000
L 4.41283327 3.92326624 4.4135998 3.92636654 1 P 0 ;0,1,2=446,3=0.000000
L 4.4135998 3.92636654 4.41551673 3.92894931 1 P 0 ;0,1,2=446,3=0.000000
L 4.41551673 3.92894931 4.41896673 3.9305 1 P 0 ;0,1,2=446,3=0.000000
L 4.41896673 3.9305 4.42241663 3.92998337 1 P 0 ;0,1,2=446,3=0.000000
L 4.42241663 3.92998337 4.42586663 3.92791624 1 P 0 ;0,1,2=446,3=0.000000
L 4.38950039 3.8995 4.38950039 3.9305 1 P 0 ;0,1,2=446,3=0.000000
L 4.38950039 3.9305 4.3941001 3.9243003 1 P 0 ;0,1,2=446,3=0.000000
L 4.3941001 3.8995 4.38490069 3.8995 1 P 0 ;0,1,2=446,3=0.000000
L 4.36693337 3.90414892 4.36463386 3.90156614 1 P 0 ;0,1,2=446,3=0.000000
L 4.36463386 3.90156614 4.36195039 3.90001654 1 P 0 ;0,1,2=446,3=0.000000
L 4.36195039 3.90001654 4.35850039 3.8995 1 P 0 ;0,1,2=446,3=0.000000
L 4.35850039 3.8995 4.3550497 3.90053307 1 P 0 ;0,1,2=446,3=0.000000
L 4.3550497 3.90053307 4.35236693 3.90259931 1 P 0 ;0,1,2=446,3=0.000000
L 4.35236693 3.90259931 4.35045 3.90621614 1 P 0 ;0,1,2=446,3=0.000000
L 4.35045 3.90621614 4.35006673 3.91034951 1 P 0 ;0,1,2=446,3=0.000000
L 4.35006673 3.91034951 4.35083327 3.91448287 1 P 0 ;0,1,2=446,3=0.000000
L 4.35083327 3.91448287 4.3527502 3.91706663 1 P 0 ;0,1,2=446,3=0.000000
L 4.3527502 3.91706663 4.35543366 3.91913287 1 P 0 ;0,1,2=446,3=0.000000
L 4.35543366 3.91913287 4.35811644 3.91964941 1 P 0 ;0,1,2=446,3=0.000000
L 4.35811644 3.91964941 4.3607999 3.91913287 1 P 0 ;0,1,2=446,3=0.000000
L 4.3607999 3.91913287 4.3642499 3.91706663 1 P 0 ;0,1,2=446,3=0.000000
L 4.3642499 3.91706663 4.3631001 3.9305 1 P 0 ;0,1,2=446,3=0.000000
L 4.3631001 3.9305 4.3527502 3.9305 1 P 0 ;0,1,2=446,3=0.000000
L 1.22 3.497 1.22 3.453 1 P 0 
L 1.13 3.497 1.22 3.497 1 P 0 
L 1.22 3.453 1.13 3.453 1 P 0 
L 1.13 3.453 1.13 3.497 1 P 0 
L 1.21256673 3.43791624 1.21486693 3.43946683 1 P 0 ;0,1,2=447,3=0.000000
L 1.21486693 3.43946683 1.2175497 3.4405 1 P 0 ;0,1,2=447,3=0.000000
L 1.2175497 3.4405 1.22061644 3.4405 1 P 0 ;0,1,2=447,3=0.000000
L 1.22061644 3.4405 1.22406713 3.43894931 1 P 0 ;0,1,2=447,3=0.000000
L 1.22406713 3.43894931 1.2267499 3.43636654 1 P 0 ;0,1,2=447,3=0.000000
L 1.2267499 3.43636654 1.22866683 3.43326624 1 P 0 ;0,1,2=447,3=0.000000
L 1.22866683 3.43326624 1.23020049 3.4280998 1 P 0 ;0,1,2=447,3=0.000000
L 1.23020049 3.4280998 1.23058376 3.4234498 1 P 0 ;0,1,2=447,3=0.000000
L 1.23058376 3.4234498 1.22981663 3.4187999 1 P 0 ;0,1,2=447,3=0.000000
L 1.22981663 3.4187999 1.22866683 3.41569961 1 P 0 ;0,1,2=447,3=0.000000
L 1.22866683 3.41569961 1.22636663 3.41259931 1 P 0 ;0,1,2=447,3=0.000000
L 1.22636663 3.41259931 1.22368317 3.41053307 1 P 0 ;0,1,2=447,3=0.000000
L 1.22368317 3.41053307 1.22100039 3.4095 1 P 0 ;0,1,2=447,3=0.000000
L 1.22100039 3.4095 1.21831693 3.4095 1 P 0 ;0,1,2=447,3=0.000000
L 1.21831693 3.4095 1.21563346 3.41053307 1 P 0 ;0,1,2=447,3=0.000000
L 1.21563346 3.41053307 1.21333327 3.41208278 1 P 0 ;0,1,2=447,3=0.000000
L 1.21333327 3.41208278 1.21141634 3.41414892 1 P 0 ;0,1,2=447,3=0.000000
L 1.19651713 3.41311585 1.19383366 3.41053307 1 P 0 ;0,1,2=447,3=0.000000
L 1.19383366 3.41053307 1.19076693 3.4095 1 P 0 ;0,1,2=447,3=0.000000
L 1.19076693 3.4095 1.1877002 3.41053307 1 P 0 ;0,1,2=447,3=0.000000
L 1.1877002 3.41053307 1.18501673 3.41363238 1 P 0 ;0,1,2=447,3=0.000000
L 1.18501673 3.41363238 1.1830998 3.41828327 1 P 0 ;0,1,2=447,3=0.000000
L 1.1830998 3.41828327 1.18233327 3.42293327 1 P 0 ;0,1,2=447,3=0.000000
L 1.18233327 3.42293327 1.18233327 3.42861634 1 P 0 ;0,1,2=447,3=0.000000
L 1.18233327 3.42861634 1.1830998 3.43326624 1 P 0 ;0,1,2=447,3=0.000000
L 1.1830998 3.43326624 1.18501673 3.4373997 1 P 0 ;0,1,2=447,3=0.000000
L 1.18501673 3.4373997 1.18731693 3.43946683 1 P 0 ;0,1,2=447,3=0.000000
L 1.18731693 3.43946683 1.19000039 3.4405 1 P 0 ;0,1,2=447,3=0.000000
L 1.19000039 3.4405 1.19306713 3.43946683 1 P 0 ;0,1,2=447,3=0.000000
L 1.19306713 3.43946683 1.19536663 3.4373997 1 P 0 ;0,1,2=447,3=0.000000
L 1.19536663 3.4373997 1.1969003 3.4343003 1 P 0 ;0,1,2=447,3=0.000000
L 1.1969003 3.4343003 1.19766683 3.43016594 1 P 0 ;0,1,2=447,3=0.000000
L 1.19766683 3.43016594 1.1969003 3.4265501 1 P 0 ;0,1,2=447,3=0.000000
L 1.1969003 3.4265501 1.19498337 3.42293327 1 P 0 ;0,1,2=447,3=0.000000
L 1.19498337 3.42293327 1.19268317 3.42086604 1 P 0 ;0,1,2=447,3=0.000000
L 1.19268317 3.42086604 1.19000039 3.42034951 1 P 0 ;0,1,2=447,3=0.000000
L 1.19000039 3.42034951 1.18693366 3.42138268 1 P 0 ;0,1,2=447,3=0.000000
L 1.18693366 3.42138268 1.18463346 3.42396634 1 P 0 ;0,1,2=447,3=0.000000
L 1.18463346 3.42396634 1.18233327 3.42861634 1 P 0 ;0,1,2=447,3=0.000000
L 1.16743337 3.41414892 1.16513386 3.41156614 1 P 0 ;0,1,2=447,3=0.000000
L 1.16513386 3.41156614 1.16245039 3.41001654 1 P 0 ;0,1,2=447,3=0.000000
L 1.16245039 3.41001654 1.15900039 3.4095 1 P 0 ;0,1,2=447,3=0.000000
L 1.15900039 3.4095 1.1555497 3.41053307 1 P 0 ;0,1,2=447,3=0.000000
L 1.1555497 3.41053307 1.15286693 3.41259931 1 P 0 ;0,1,2=447,3=0.000000
L 1.15286693 3.41259931 1.15095 3.41621614 1 P 0 ;0,1,2=447,3=0.000000
L 1.15095 3.41621614 1.15056673 3.42034951 1 P 0 ;0,1,2=447,3=0.000000
L 1.15056673 3.42034951 1.15133327 3.42448287 1 P 0 ;0,1,2=447,3=0.000000
L 1.15133327 3.42448287 1.1532502 3.42706663 1 P 0 ;0,1,2=447,3=0.000000
L 1.1532502 3.42706663 1.15593366 3.42913287 1 P 0 ;0,1,2=447,3=0.000000
L 1.15593366 3.42913287 1.15861644 3.42964941 1 P 0 ;0,1,2=447,3=0.000000
L 1.15861644 3.42964941 1.1612999 3.42913287 1 P 0 ;0,1,2=447,3=0.000000
L 1.1612999 3.42913287 1.1647499 3.42706663 1 P 0 ;0,1,2=447,3=0.000000
L 1.1647499 3.42706663 1.1636001 3.4405 1 P 0 ;0,1,2=447,3=0.000000
L 1.1636001 3.4405 1.1532502 3.4405 1 P 0 ;0,1,2=447,3=0.000000
L 1.108 3.63 1.152 3.63 1 P 0 
L 1.108 3.54 1.108 3.63 1 P 0 
L 1.152 3.63 1.152 3.54 1 P 0 
L 1.152 3.54 1.108 3.54 1 P 0 
L 1.14791624 3.67193327 1.14946683 3.66963307 1 P 0 ;0,1,2=448,3=90.000000
L 1.14946683 3.66963307 1.1505 3.6669503 1 P 0 ;0,1,2=448,3=90.000000
L 1.1505 3.6669503 1.1505 3.66388356 1 P 0 ;0,1,2=448,3=90.000000
L 1.1505 3.66388356 1.14894931 3.66043287 1 P 0 ;0,1,2=448,3=90.000000
L 1.14894931 3.66043287 1.14636654 3.6577501 1 P 0 ;0,1,2=448,3=90.000000
L 1.14636654 3.6577501 1.14326624 3.65583317 1 P 0 ;0,1,2=448,3=90.000000
L 1.14326624 3.65583317 1.1380998 3.65429951 1 P 0 ;0,1,2=448,3=90.000000
L 1.1380998 3.65429951 1.1334498 3.65391624 1 P 0 ;0,1,2=448,3=90.000000
L 1.1334498 3.65391624 1.1287999 3.65468337 1 P 0 ;0,1,2=448,3=90.000000
L 1.1287999 3.65468337 1.12569961 3.65583317 1 P 0 ;0,1,2=448,3=90.000000
L 1.12569961 3.65583317 1.12259931 3.65813337 1 P 0 ;0,1,2=448,3=90.000000
L 1.12259931 3.65813337 1.12053307 3.66081683 1 P 0 ;0,1,2=448,3=90.000000
L 1.12053307 3.66081683 1.1195 3.66349961 1 P 0 ;0,1,2=448,3=90.000000
L 1.1195 3.66349961 1.1195 3.66618307 1 P 0 ;0,1,2=448,3=90.000000
L 1.1195 3.66618307 1.12053307 3.66886654 1 P 0 ;0,1,2=448,3=90.000000
L 1.12053307 3.66886654 1.12208278 3.67116673 1 P 0 ;0,1,2=448,3=90.000000
L 1.12208278 3.67116673 1.12414892 3.67308366 1 P 0 ;0,1,2=448,3=90.000000
L 1.1195 3.69449961 1.1505 3.69449961 1 P 0 ;0,1,2=448,3=90.000000
L 1.1505 3.69449961 1.1443003 3.6898999 1 P 0 ;0,1,2=448,3=90.000000
L 1.1195 3.6898999 1.1195 3.69909931 1 P 0 ;0,1,2=448,3=90.000000
L 1.1505 3.72549961 1.14946683 3.72243287 1 P 0 ;0,1,2=448,3=90.000000
L 1.14946683 3.72243287 1.14688307 3.72013337 1 P 0 ;0,1,2=448,3=90.000000
L 1.14688307 3.72013337 1.14378376 3.7185997 1 P 0 ;0,1,2=448,3=90.000000
L 1.14378376 3.7185997 1.13964941 3.7174499 1 P 0 ;0,1,2=448,3=90.000000
L 1.13964941 3.7174499 1.13499951 3.71706663 1 P 0 ;0,1,2=448,3=90.000000
L 1.13499951 3.71706663 1.13034951 3.7174499 1 P 0 ;0,1,2=448,3=90.000000
L 1.13034951 3.7174499 1.12621614 3.7185997 1 P 0 ;0,1,2=448,3=90.000000
L 1.12621614 3.7185997 1.12311585 3.72013337 1 P 0 ;0,1,2=448,3=90.000000
L 1.12311585 3.72013337 1.12053307 3.72243287 1 P 0 ;0,1,2=448,3=90.000000
L 1.12053307 3.72243287 1.1195 3.72549961 1 P 0 ;0,1,2=448,3=90.000000
L 1.1195 3.72549961 1.12053307 3.72856634 1 P 0 ;0,1,2=448,3=90.000000
L 1.12053307 3.72856634 1.12311585 3.73086654 1 P 0 ;0,1,2=448,3=90.000000
L 1.12311585 3.73086654 1.12621614 3.7324002 1 P 0 ;0,1,2=448,3=90.000000
L 1.12621614 3.7324002 1.13034951 3.73355 1 P 0 ;0,1,2=448,3=90.000000
L 1.13034951 3.73355 1.13499951 3.73393327 1 P 0 ;0,1,2=448,3=90.000000
L 1.13499951 3.73393327 1.13964941 3.73355 1 P 0 ;0,1,2=448,3=90.000000
L 1.13964941 3.73355 1.14378376 3.7324002 1 P 0 ;0,1,2=448,3=90.000000
L 1.14378376 3.7324002 1.14688307 3.73086654 1 P 0 ;0,1,2=448,3=90.000000
L 1.14688307 3.73086654 1.14946683 3.72856634 1 P 0 ;0,1,2=448,3=90.000000
L 1.14946683 3.72856634 1.1505 3.72549961 1 P 0 ;0,1,2=448,3=90.000000
L 1.1505 3.75649961 1.14946683 3.75343287 1 P 0 ;0,1,2=448,3=90.000000
L 1.14946683 3.75343287 1.14688307 3.75113337 1 P 0 ;0,1,2=448,3=90.000000
L 1.14688307 3.75113337 1.14378376 3.7495997 1 P 0 ;0,1,2=448,3=90.000000
L 1.14378376 3.7495997 1.13964941 3.7484499 1 P 0 ;0,1,2=448,3=90.000000
L 1.13964941 3.7484499 1.13499951 3.74806663 1 P 0 ;0,1,2=448,3=90.000000
L 1.13499951 3.74806663 1.13034951 3.7484499 1 P 0 ;0,1,2=448,3=90.000000
L 1.13034951 3.7484499 1.12621614 3.7495997 1 P 0 ;0,1,2=448,3=90.000000
L 1.12621614 3.7495997 1.12311585 3.75113337 1 P 0 ;0,1,2=448,3=90.000000
L 1.12311585 3.75113337 1.12053307 3.75343287 1 P 0 ;0,1,2=448,3=90.000000
L 1.12053307 3.75343287 1.1195 3.75649961 1 P 0 ;0,1,2=448,3=90.000000
L 1.1195 3.75649961 1.12053307 3.75956634 1 P 0 ;0,1,2=448,3=90.000000
L 1.12053307 3.75956634 1.12311585 3.76186654 1 P 0 ;0,1,2=448,3=90.000000
L 1.12311585 3.76186654 1.12621614 3.7634002 1 P 0 ;0,1,2=448,3=90.000000
L 1.12621614 3.7634002 1.13034951 3.76455 1 P 0 ;0,1,2=448,3=90.000000
L 1.13034951 3.76455 1.13499951 3.76493327 1 P 0 ;0,1,2=448,3=90.000000
L 1.13499951 3.76493327 1.13964941 3.76455 1 P 0 ;0,1,2=448,3=90.000000
L 1.13964941 3.76455 1.14378376 3.7634002 1 P 0 ;0,1,2=448,3=90.000000
L 1.14378376 3.7634002 1.14688307 3.76186654 1 P 0 ;0,1,2=448,3=90.000000
L 1.14688307 3.76186654 1.14946683 3.75956634 1 P 0 ;0,1,2=448,3=90.000000
L 1.14946683 3.75956634 1.1505 3.75649961 1 P 0 ;0,1,2=448,3=90.000000
L 1.4 3.522 1.4 3.478 1 P 0 
L 1.31 3.522 1.4 3.522 1 P 0 
L 1.4 3.478 1.31 3.478 1 P 0 
L 1.31 3.478 1.31 3.522 1 P 0 
L 1.38256673 3.46791624 1.38486693 3.46946683 1 P 0 ;0,1,2=449,3=0.000000
L 1.38486693 3.46946683 1.3875497 3.4705 1 P 0 ;0,1,2=449,3=0.000000
L 1.3875497 3.4705 1.39061644 3.4705 1 P 0 ;0,1,2=449,3=0.000000
L 1.39061644 3.4705 1.39406713 3.46894931 1 P 0 ;0,1,2=449,3=0.000000
L 1.39406713 3.46894931 1.3967499 3.46636654 1 P 0 ;0,1,2=449,3=0.000000
L 1.3967499 3.46636654 1.39866683 3.46326624 1 P 0 ;0,1,2=449,3=0.000000
L 1.39866683 3.46326624 1.40020049 3.4580998 1 P 0 ;0,1,2=449,3=0.000000
L 1.40020049 3.4580998 1.40058376 3.4534498 1 P 0 ;0,1,2=449,3=0.000000
L 1.40058376 3.4534498 1.39981663 3.4487999 1 P 0 ;0,1,2=449,3=0.000000
L 1.39981663 3.4487999 1.39866683 3.44569961 1 P 0 ;0,1,2=449,3=0.000000
L 1.39866683 3.44569961 1.39636663 3.44259931 1 P 0 ;0,1,2=449,3=0.000000
L 1.39636663 3.44259931 1.39368317 3.44053307 1 P 0 ;0,1,2=449,3=0.000000
L 1.39368317 3.44053307 1.39100039 3.4395 1 P 0 ;0,1,2=449,3=0.000000
L 1.39100039 3.4395 1.38831693 3.4395 1 P 0 ;0,1,2=449,3=0.000000
L 1.38831693 3.4395 1.38563346 3.44053307 1 P 0 ;0,1,2=449,3=0.000000
L 1.38563346 3.44053307 1.38333327 3.44208278 1 P 0 ;0,1,2=449,3=0.000000
L 1.38333327 3.44208278 1.38141634 3.44414892 1 P 0 ;0,1,2=449,3=0.000000
L 1.36651713 3.44311585 1.36383366 3.44053307 1 P 0 ;0,1,2=449,3=0.000000
L 1.36383366 3.44053307 1.36076693 3.4395 1 P 0 ;0,1,2=449,3=0.000000
L 1.36076693 3.4395 1.3577002 3.44053307 1 P 0 ;0,1,2=449,3=0.000000
L 1.3577002 3.44053307 1.35501673 3.44363238 1 P 0 ;0,1,2=449,3=0.000000
L 1.35501673 3.44363238 1.3530998 3.44828327 1 P 0 ;0,1,2=449,3=0.000000
L 1.3530998 3.44828327 1.35233327 3.45293327 1 P 0 ;0,1,2=449,3=0.000000
L 1.35233327 3.45293327 1.35233327 3.45861634 1 P 0 ;0,1,2=449,3=0.000000
L 1.35233327 3.45861634 1.3530998 3.46326624 1 P 0 ;0,1,2=449,3=0.000000
L 1.3530998 3.46326624 1.35501673 3.4673997 1 P 0 ;0,1,2=449,3=0.000000
L 1.35501673 3.4673997 1.35731693 3.46946683 1 P 0 ;0,1,2=449,3=0.000000
L 1.35731693 3.46946683 1.36000039 3.4705 1 P 0 ;0,1,2=449,3=0.000000
L 1.36000039 3.4705 1.36306713 3.46946683 1 P 0 ;0,1,2=449,3=0.000000
L 1.36306713 3.46946683 1.36536663 3.4673997 1 P 0 ;0,1,2=449,3=0.000000
L 1.36536663 3.4673997 1.3669003 3.4643003 1 P 0 ;0,1,2=449,3=0.000000
L 1.3669003 3.4643003 1.36766683 3.46016594 1 P 0 ;0,1,2=449,3=0.000000
L 1.36766683 3.46016594 1.3669003 3.4565501 1 P 0 ;0,1,2=449,3=0.000000
L 1.3669003 3.4565501 1.36498337 3.45293327 1 P 0 ;0,1,2=449,3=0.000000
L 1.36498337 3.45293327 1.36268317 3.45086604 1 P 0 ;0,1,2=449,3=0.000000
L 1.36268317 3.45086604 1.36000039 3.45034951 1 P 0 ;0,1,2=449,3=0.000000
L 1.36000039 3.45034951 1.35693366 3.45138268 1 P 0 ;0,1,2=449,3=0.000000
L 1.35693366 3.45138268 1.35463346 3.45396634 1 P 0 ;0,1,2=449,3=0.000000
L 1.35463346 3.45396634 1.35233327 3.45861634 1 P 0 ;0,1,2=449,3=0.000000
L 1.33628356 3.45241575 1.3336001 3.45603356 1 P 0 ;0,1,2=449,3=0.000000
L 1.3336001 3.45603356 1.3312999 3.4580998 1 P 0 ;0,1,2=449,3=0.000000
L 1.3312999 3.4580998 1.32823317 3.45913287 1 P 0 ;0,1,2=449,3=0.000000
L 1.32823317 3.45913287 1.3255497 3.4580998 1 P 0 ;0,1,2=449,3=0.000000
L 1.3255497 3.4580998 1.32363346 3.45603356 1 P 0 ;0,1,2=449,3=0.000000
L 1.32363346 3.45603356 1.3220998 3.45293327 1 P 0 ;0,1,2=449,3=0.000000
L 1.3220998 3.45293327 1.32171654 3.44931644 1 P 0 ;0,1,2=449,3=0.000000
L 1.32171654 3.44931644 1.3220998 3.44621614 1 P 0 ;0,1,2=449,3=0.000000
L 1.3220998 3.44621614 1.32363346 3.44311585 1 P 0 ;0,1,2=449,3=0.000000
L 1.32363346 3.44311585 1.32593366 3.44053307 1 P 0 ;0,1,2=449,3=0.000000
L 1.32593366 3.44053307 1.32861644 3.4395 1 P 0 ;0,1,2=449,3=0.000000
L 1.32861644 3.4395 1.33168317 3.44053307 1 P 0 ;0,1,2=449,3=0.000000
L 1.33168317 3.44053307 1.33436663 3.44363238 1 P 0 ;0,1,2=449,3=0.000000
L 1.33436663 3.44363238 1.3359003 3.44828327 1 P 0 ;0,1,2=449,3=0.000000
L 1.3359003 3.44828327 1.33628356 3.4534498 1 P 0 ;0,1,2=449,3=0.000000
L 1.33628356 3.4534498 1.33551713 3.46016594 1 P 0 ;0,1,2=449,3=0.000000
L 1.33551713 3.46016594 1.33436663 3.46378376 1 P 0 ;0,1,2=449,3=0.000000
L 1.33436663 3.46378376 1.33245039 3.4673997 1 P 0 ;0,1,2=449,3=0.000000
L 1.33245039 3.4673997 1.32976693 3.46998337 1 P 0 ;0,1,2=449,3=0.000000
L 1.32976693 3.46998337 1.32708346 3.4705 1 P 0 ;0,1,2=449,3=0.000000
L 1.32708346 3.4705 1.3244 3.46946683 1 P 0 ;0,1,2=449,3=0.000000
L 1.3244 3.46946683 1.32248297 3.46688307 1 P 0 ;0,1,2=449,3=0.000000
L 5.532 2.09 5.532 2 1 P 0 
L 5.532 2 5.488 2 1 P 0 
L 5.488 2 5.488 2.09 1 P 0 
L 5.488 2.09 5.532 2.09 1 P 0 
L 5.47791624 1.92693327 5.47946683 1.92463307 1 P 0 ;0,1,2=450,3=90.000000
L 5.47946683 1.92463307 5.4805 1.9219503 1 P 0 ;0,1,2=450,3=90.000000
L 5.4805 1.9219503 5.4805 1.91888356 1 P 0 ;0,1,2=450,3=90.000000
L 5.4805 1.91888356 5.47894931 1.91543287 1 P 0 ;0,1,2=450,3=90.000000
L 5.47894931 1.91543287 5.47636654 1.9127501 1 P 0 ;0,1,2=450,3=90.000000
L 5.47636654 1.9127501 5.47326624 1.91083317 1 P 0 ;0,1,2=450,3=90.000000
L 5.47326624 1.91083317 5.4680998 1.90929951 1 P 0 ;0,1,2=450,3=90.000000
L 5.4680998 1.90929951 5.4634498 1.90891624 1 P 0 ;0,1,2=450,3=90.000000
L 5.4634498 1.90891624 5.4587999 1.90968337 1 P 0 ;0,1,2=450,3=90.000000
L 5.4587999 1.90968337 5.45569961 1.91083317 1 P 0 ;0,1,2=450,3=90.000000
L 5.45569961 1.91083317 5.45259931 1.91313337 1 P 0 ;0,1,2=450,3=90.000000
L 5.45259931 1.91313337 5.45053307 1.91581683 1 P 0 ;0,1,2=450,3=90.000000
L 5.45053307 1.91581683 5.4495 1.91849961 1 P 0 ;0,1,2=450,3=90.000000
L 5.4495 1.91849961 5.4495 1.92118307 1 P 0 ;0,1,2=450,3=90.000000
L 5.4495 1.92118307 5.45053307 1.92386654 1 P 0 ;0,1,2=450,3=90.000000
L 5.45053307 1.92386654 5.45208278 1.92616673 1 P 0 ;0,1,2=450,3=90.000000
L 5.45208278 1.92616673 5.45414892 1.92808366 1 P 0 ;0,1,2=450,3=90.000000
L 5.47533346 1.94221644 5.47843278 1.94451663 1 P 0 ;0,1,2=450,3=90.000000
L 5.47843278 1.94451663 5.47998337 1.9472001 1 P 0 ;0,1,2=450,3=90.000000
L 5.47998337 1.9472001 5.4805 1.95026683 1 P 0 ;0,1,2=450,3=90.000000
L 5.4805 1.95026683 5.47946683 1.9541 1 P 0 ;0,1,2=450,3=90.000000
L 5.47946683 1.9541 5.47688307 1.95678346 1 P 0 ;0,1,2=450,3=90.000000
L 5.47688307 1.95678346 5.47378376 1.95755 1 P 0 ;0,1,2=450,3=90.000000
L 5.47378376 1.95755 5.47068258 1.95716673 1 P 0 ;0,1,2=450,3=90.000000
L 5.47068258 1.95716673 5.4680998 1.95563307 1 P 0 ;0,1,2=450,3=90.000000
L 5.4680998 1.95563307 5.46293327 1.94796663 1 P 0 ;0,1,2=450,3=90.000000
L 5.46293327 1.94796663 5.45931644 1.94451663 1 P 0 ;0,1,2=450,3=90.000000
L 5.45931644 1.94451663 5.45414892 1.94221644 1 P 0 ;0,1,2=450,3=90.000000
L 5.45414892 1.94221644 5.4495 1.9414499 1 P 0 ;0,1,2=450,3=90.000000
L 5.4495 1.9414499 5.4495 1.95755 1 P 0 ;0,1,2=450,3=90.000000
L 5.46241575 1.97321644 5.46603356 1.9758999 1 P 0 ;0,1,2=450,3=90.000000
L 5.46603356 1.9758999 5.4680998 1.9782001 1 P 0 ;0,1,2=450,3=90.000000
L 5.4680998 1.9782001 5.46913287 1.98126683 1 P 0 ;0,1,2=450,3=90.000000
L 5.46913287 1.98126683 5.4680998 1.9839503 1 P 0 ;0,1,2=450,3=90.000000
L 5.4680998 1.9839503 5.46603356 1.98586654 1 P 0 ;0,1,2=450,3=90.000000
L 5.46603356 1.98586654 5.46293327 1.9874002 1 P 0 ;0,1,2=450,3=90.000000
L 5.46293327 1.9874002 5.45931644 1.98778346 1 P 0 ;0,1,2=450,3=90.000000
L 5.45931644 1.98778346 5.45621614 1.9874002 1 P 0 ;0,1,2=450,3=90.000000
L 5.45621614 1.9874002 5.45311585 1.98586654 1 P 0 ;0,1,2=450,3=90.000000
L 5.45311585 1.98586654 5.45053307 1.98356634 1 P 0 ;0,1,2=450,3=90.000000
L 5.45053307 1.98356634 5.4495 1.98088356 1 P 0 ;0,1,2=450,3=90.000000
L 5.4495 1.98088356 5.45053307 1.97781683 1 P 0 ;0,1,2=450,3=90.000000
L 5.45053307 1.97781683 5.45363238 1.97513337 1 P 0 ;0,1,2=450,3=90.000000
L 5.45363238 1.97513337 5.45828327 1.9735997 1 P 0 ;0,1,2=450,3=90.000000
L 5.45828327 1.9735997 5.4634498 1.97321644 1 P 0 ;0,1,2=450,3=90.000000
L 5.4634498 1.97321644 5.47016594 1.97398287 1 P 0 ;0,1,2=450,3=90.000000
L 5.47016594 1.97398287 5.47378376 1.97513337 1 P 0 ;0,1,2=450,3=90.000000
L 5.47378376 1.97513337 5.4773997 1.97704961 1 P 0 ;0,1,2=450,3=90.000000
L 5.4773997 1.97704961 5.47998337 1.97973307 1 P 0 ;0,1,2=450,3=90.000000
L 5.47998337 1.97973307 5.4805 1.98241654 1 P 0 ;0,1,2=450,3=90.000000
L 5.4805 1.98241654 5.47946683 1.9851 1 P 0 ;0,1,2=450,3=90.000000
L 5.47946683 1.9851 5.47688307 1.98701703 1 P 0 ;0,1,2=450,3=90.000000
L 5.45414892 2.00306663 5.45156614 2.00536614 1 P 0 ;0,1,2=450,3=90.000000
L 5.45156614 2.00536614 5.45001654 2.00804961 1 P 0 ;0,1,2=450,3=90.000000
L 5.45001654 2.00804961 5.4495 2.01149961 1 P 0 ;0,1,2=450,3=90.000000
L 5.4495 2.01149961 5.45053307 2.0149503 1 P 0 ;0,1,2=450,3=90.000000
L 5.45053307 2.0149503 5.45259931 2.01763307 1 P 0 ;0,1,2=450,3=90.000000
L 5.45259931 2.01763307 5.45621614 2.01955 1 P 0 ;0,1,2=450,3=90.000000
L 5.45621614 2.01955 5.46034951 2.01993327 1 P 0 ;0,1,2=450,3=90.000000
L 5.46034951 2.01993327 5.46448287 2.01916673 1 P 0 ;0,1,2=450,3=90.000000
L 5.46448287 2.01916673 5.46706663 2.0172498 1 P 0 ;0,1,2=450,3=90.000000
L 5.46706663 2.0172498 5.46913287 2.01456634 1 P 0 ;0,1,2=450,3=90.000000
L 5.46913287 2.01456634 5.46964941 2.01188356 1 P 0 ;0,1,2=450,3=90.000000
L 5.46964941 2.01188356 5.46913287 2.0092001 1 P 0 ;0,1,2=450,3=90.000000
L 5.46913287 2.0092001 5.46706663 2.0057501 1 P 0 ;0,1,2=450,3=90.000000
L 5.46706663 2.0057501 5.4805 2.0068999 1 P 0 ;0,1,2=450,3=90.000000
L 5.4805 2.0068999 5.4805 2.0172498 1 P 0 ;0,1,2=450,3=90.000000
L 5.78 2.599 5.78 2.763 1 P 0 
L 5.78 2.763 5.646 2.763 1 P 0 
L 5.646 2.763 5.646 2.599 1 P 0 
L 5.646 2.599 5.78 2.599 1 P 0 
S P 0
OB 5.763 2.578 I
OC 5.763 2.578 5.748 2.578 Y
OE
SE
L 5.8004 2.7495 5.8004 2.7805 1 P 0 ;0,1,2=112,3=0.000000
L 5.8004 2.7805 5.81458376 2.75828327 1 P 0 ;0,1,2=112,3=0.000000
L 5.81458376 2.75828327 5.79541634 2.75828327 1 P 0 ;0,1,2=112,3=0.000000
L 5.63843337 2.74569961 5.63613386 2.74208278 1 P 0 ;0,1,2=113,3=0.000000
L 5.63613386 2.74208278 5.63306713 2.74001654 1 P 0 ;0,1,2=113,3=0.000000
L 5.63306713 2.74001654 5.62961644 2.7395 1 P 0 ;0,1,2=113,3=0.000000
L 5.62961644 2.7395 5.6265497 2.74001654 1 P 0 ;0,1,2=113,3=0.000000
L 5.6265497 2.74001654 5.62348297 2.74259931 1 P 0 ;0,1,2=113,3=0.000000
L 5.62348297 2.74259931 5.62156673 2.74569961 1 P 0 ;0,1,2=113,3=0.000000
L 5.62156673 2.74569961 5.62118346 2.7487999 1 P 0 ;0,1,2=113,3=0.000000
L 5.62118346 2.7487999 5.62195 2.75241575 1 P 0 ;0,1,2=113,3=0.000000
L 5.62195 2.75241575 5.62463346 2.75499951 1 P 0 ;0,1,2=113,3=0.000000
L 5.62463346 2.75499951 5.62731693 2.75603356 1 P 0 ;0,1,2=113,3=0.000000
L 5.62731693 2.75603356 5.63076693 2.75603356 1 P 0 ;0,1,2=113,3=0.000000
L 5.62731693 2.75603356 5.62501673 2.75758317 1 P 0 ;0,1,2=113,3=0.000000
L 5.62501673 2.75758317 5.6230998 2.76016594 1 P 0 ;0,1,2=113,3=0.000000
L 5.6230998 2.76016594 5.62233327 2.76326624 1 P 0 ;0,1,2=113,3=0.000000
L 5.62233327 2.76326624 5.6230998 2.76636654 1 P 0 ;0,1,2=113,3=0.000000
L 5.6230998 2.76636654 5.62501673 2.76894931 1 P 0 ;0,1,2=113,3=0.000000
L 5.62501673 2.76894931 5.62846673 2.7705 1 P 0 ;0,1,2=113,3=0.000000
L 5.62846673 2.7705 5.63191663 2.76998337 1 P 0 ;0,1,2=113,3=0.000000
L 5.63191663 2.76998337 5.63536663 2.76791624 1 P 0 ;0,1,2=113,3=0.000000
L 5.73756673 2.81791624 5.73986693 2.81946683 1 P 0 ;0,1,2=451,3=0.000000
L 5.73986693 2.81946683 5.7425497 2.8205 1 P 0 ;0,1,2=451,3=0.000000
L 5.7425497 2.8205 5.74561644 2.8205 1 P 0 ;0,1,2=451,3=0.000000
L 5.74561644 2.8205 5.74906713 2.81894931 1 P 0 ;0,1,2=451,3=0.000000
L 5.74906713 2.81894931 5.7517499 2.81636654 1 P 0 ;0,1,2=451,3=0.000000
L 5.7517499 2.81636654 5.75366683 2.81326624 1 P 0 ;0,1,2=451,3=0.000000
L 5.75366683 2.81326624 5.75520049 2.8080998 1 P 0 ;0,1,2=451,3=0.000000
L 5.75520049 2.8080998 5.75558376 2.8034498 1 P 0 ;0,1,2=451,3=0.000000
L 5.75558376 2.8034498 5.75481663 2.7987999 1 P 0 ;0,1,2=451,3=0.000000
L 5.75481663 2.7987999 5.75366683 2.79569961 1 P 0 ;0,1,2=451,3=0.000000
L 5.75366683 2.79569961 5.75136663 2.79259931 1 P 0 ;0,1,2=451,3=0.000000
L 5.75136663 2.79259931 5.74868317 2.79053307 1 P 0 ;0,1,2=451,3=0.000000
L 5.74868317 2.79053307 5.74600039 2.7895 1 P 0 ;0,1,2=451,3=0.000000
L 5.74600039 2.7895 5.74331693 2.7895 1 P 0 ;0,1,2=451,3=0.000000
L 5.74331693 2.7895 5.74063346 2.79053307 1 P 0 ;0,1,2=451,3=0.000000
L 5.74063346 2.79053307 5.73833327 2.79208278 1 P 0 ;0,1,2=451,3=0.000000
L 5.73833327 2.79208278 5.73641634 2.79414892 1 P 0 ;0,1,2=451,3=0.000000
L 5.72266683 2.7895 5.72266683 2.8205 1 P 0 ;0,1,2=451,3=0.000000
L 5.72266683 2.8205 5.71308346 2.8205 1 P 0 ;0,1,2=451,3=0.000000
L 5.71308346 2.8205 5.71001673 2.81894931 1 P 0 ;0,1,2=451,3=0.000000
L 5.71001673 2.81894931 5.7080998 2.81688307 1 P 0 ;0,1,2=451,3=0.000000
L 5.7080998 2.81688307 5.70733327 2.8127497 1 P 0 ;0,1,2=451,3=0.000000
L 5.70733327 2.8127497 5.7080998 2.80861634 1 P 0 ;0,1,2=451,3=0.000000
L 5.7080998 2.80861634 5.7104 2.80603356 1 P 0 ;0,1,2=451,3=0.000000
L 5.7104 2.80603356 5.71308346 2.80448287 1 P 0 ;0,1,2=451,3=0.000000
L 5.71308346 2.80448287 5.72266683 2.80448287 1 P 0 ;0,1,2=451,3=0.000000
L 5.71308346 2.80448287 5.70733327 2.7895 1 P 0 ;0,1,2=451,3=0.000000
L 5.68476693 2.7895 5.68400039 2.79621614 1 P 0 ;0,1,2=451,3=0.000000
L 5.68400039 2.79621614 5.6828499 2.80189921 1 P 0 ;0,1,2=451,3=0.000000
L 5.6828499 2.80189921 5.68131693 2.80706663 1 P 0 ;0,1,2=451,3=0.000000
L 5.68131693 2.80706663 5.6794 2.8127497 1 P 0 ;0,1,2=451,3=0.000000
L 5.6794 2.8127497 5.67633327 2.8205 1 P 0 ;0,1,2=451,3=0.000000
L 5.67633327 2.8205 5.69166683 2.8205 1 P 0 ;0,1,2=451,3=0.000000
L 5.67728356 2.58033346 5.67498337 2.58343278 1 P 0 ;0,1,2=7,3=0.000000
L 5.67498337 2.58343278 5.6722999 2.58498337 1 P 0 ;0,1,2=7,3=0.000000
L 5.6722999 2.58498337 5.66923317 2.5855 1 P 0 ;0,1,2=7,3=0.000000
L 5.66923317 2.5855 5.6654 2.58446683 1 P 0 ;0,1,2=7,3=0.000000
L 5.6654 2.58446683 5.66271654 2.58188307 1 P 0 ;0,1,2=7,3=0.000000
L 5.66271654 2.58188307 5.66195 2.57878376 1 P 0 ;0,1,2=7,3=0.000000
L 5.66195 2.57878376 5.66233327 2.57568258 1 P 0 ;0,1,2=7,3=0.000000
L 5.66233327 2.57568258 5.66386693 2.5730998 1 P 0 ;0,1,2=7,3=0.000000
L 5.66386693 2.5730998 5.67153337 2.56793327 1 P 0 ;0,1,2=7,3=0.000000
L 5.67153337 2.56793327 5.67498337 2.56431644 1 P 0 ;0,1,2=7,3=0.000000
L 5.67498337 2.56431644 5.67728356 2.55914892 1 P 0 ;0,1,2=7,3=0.000000
L 5.67728356 2.55914892 5.6780501 2.5545 1 P 0 ;0,1,2=7,3=0.000000
L 5.6780501 2.5545 5.66195 2.5545 1 P 0 ;0,1,2=7,3=0.000000
L 5.775 2.884 5.775 3.048 1 P 0 
L 5.775 3.048 5.641 3.048 1 P 0 
L 5.641 3.048 5.641 2.884 1 P 0 
L 5.641 2.884 5.775 2.884 1 P 0 
S P 0
OB 5.758 2.863 I
OC 5.758 2.863 5.743 2.863 Y
OE
SE
L 5.85791624 2.89743327 5.85946683 2.89513307 1 P 0 ;0,1,2=452,3=90.000000
L 5.85946683 2.89513307 5.8605 2.8924503 1 P 0 ;0,1,2=452,3=90.000000
L 5.8605 2.8924503 5.8605 2.88938356 1 P 0 ;0,1,2=452,3=90.000000
L 5.8605 2.88938356 5.85894931 2.88593287 1 P 0 ;0,1,2=452,3=90.000000
L 5.85894931 2.88593287 5.85636654 2.8832501 1 P 0 ;0,1,2=452,3=90.000000
L 5.85636654 2.8832501 5.85326624 2.88133317 1 P 0 ;0,1,2=452,3=90.000000
L 5.85326624 2.88133317 5.8480998 2.87979951 1 P 0 ;0,1,2=452,3=90.000000
L 5.8480998 2.87979951 5.8434498 2.87941624 1 P 0 ;0,1,2=452,3=90.000000
L 5.8434498 2.87941624 5.8387999 2.88018337 1 P 0 ;0,1,2=452,3=90.000000
L 5.8387999 2.88018337 5.83569961 2.88133317 1 P 0 ;0,1,2=452,3=90.000000
L 5.83569961 2.88133317 5.83259931 2.88363337 1 P 0 ;0,1,2=452,3=90.000000
L 5.83259931 2.88363337 5.83053307 2.88631683 1 P 0 ;0,1,2=452,3=90.000000
L 5.83053307 2.88631683 5.8295 2.88899961 1 P 0 ;0,1,2=452,3=90.000000
L 5.8295 2.88899961 5.8295 2.89168307 1 P 0 ;0,1,2=452,3=90.000000
L 5.8295 2.89168307 5.83053307 2.89436654 1 P 0 ;0,1,2=452,3=90.000000
L 5.83053307 2.89436654 5.83208278 2.89666673 1 P 0 ;0,1,2=452,3=90.000000
L 5.83208278 2.89666673 5.83414892 2.89858366 1 P 0 ;0,1,2=452,3=90.000000
L 5.8295 2.91233317 5.8605 2.91233317 1 P 0 ;0,1,2=452,3=90.000000
L 5.8605 2.91233317 5.8605 2.92191654 1 P 0 ;0,1,2=452,3=90.000000
L 5.8605 2.92191654 5.85894931 2.92498327 1 P 0 ;0,1,2=452,3=90.000000
L 5.85894931 2.92498327 5.85688307 2.9269002 1 P 0 ;0,1,2=452,3=90.000000
L 5.85688307 2.9269002 5.8527497 2.92766673 1 P 0 ;0,1,2=452,3=90.000000
L 5.8527497 2.92766673 5.84861634 2.9269002 1 P 0 ;0,1,2=452,3=90.000000
L 5.84861634 2.9269002 5.84603356 2.9246 1 P 0 ;0,1,2=452,3=90.000000
L 5.84603356 2.9246 5.84448287 2.92191654 1 P 0 ;0,1,2=452,3=90.000000
L 5.84448287 2.92191654 5.84448287 2.91233317 1 P 0 ;0,1,2=452,3=90.000000
L 5.84448287 2.92191654 5.8295 2.92766673 1 P 0 ;0,1,2=452,3=90.000000
L 5.84241575 2.94371644 5.84603356 2.9463999 1 P 0 ;0,1,2=452,3=90.000000
L 5.84603356 2.9463999 5.8480998 2.9487001 1 P 0 ;0,1,2=452,3=90.000000
L 5.8480998 2.9487001 5.84913287 2.95176683 1 P 0 ;0,1,2=452,3=90.000000
L 5.84913287 2.95176683 5.8480998 2.9544503 1 P 0 ;0,1,2=452,3=90.000000
L 5.8480998 2.9544503 5.84603356 2.95636654 1 P 0 ;0,1,2=452,3=90.000000
L 5.84603356 2.95636654 5.84293327 2.9579002 1 P 0 ;0,1,2=452,3=90.000000
L 5.84293327 2.9579002 5.83931644 2.95828346 1 P 0 ;0,1,2=452,3=90.000000
L 5.83931644 2.95828346 5.83621614 2.9579002 1 P 0 ;0,1,2=452,3=90.000000
L 5.83621614 2.9579002 5.83311585 2.95636654 1 P 0 ;0,1,2=452,3=90.000000
L 5.83311585 2.95636654 5.83053307 2.95406634 1 P 0 ;0,1,2=452,3=90.000000
L 5.83053307 2.95406634 5.8295 2.95138356 1 P 0 ;0,1,2=452,3=90.000000
L 5.8295 2.95138356 5.83053307 2.94831683 1 P 0 ;0,1,2=452,3=90.000000
L 5.83053307 2.94831683 5.83363238 2.94563337 1 P 0 ;0,1,2=452,3=90.000000
L 5.83363238 2.94563337 5.83828327 2.9440997 1 P 0 ;0,1,2=452,3=90.000000
L 5.83828327 2.9440997 5.8434498 2.94371644 1 P 0 ;0,1,2=452,3=90.000000
L 5.8434498 2.94371644 5.85016594 2.94448287 1 P 0 ;0,1,2=452,3=90.000000
L 5.85016594 2.94448287 5.85378376 2.94563337 1 P 0 ;0,1,2=452,3=90.000000
L 5.85378376 2.94563337 5.8573997 2.94754961 1 P 0 ;0,1,2=452,3=90.000000
L 5.8573997 2.94754961 5.85998337 2.95023307 1 P 0 ;0,1,2=452,3=90.000000
L 5.85998337 2.95023307 5.8605 2.95291654 1 P 0 ;0,1,2=452,3=90.000000
L 5.8605 2.95291654 5.85946683 2.9556 1 P 0 ;0,1,2=452,3=90.000000
L 5.85946683 2.9556 5.85688307 2.95751703 1 P 0 ;0,1,2=452,3=90.000000
L 5.66343337 3.06569961 5.66113386 3.06208278 1 P 0 ;0,1,2=113,3=0.000000
L 5.66113386 3.06208278 5.65806713 3.06001654 1 P 0 ;0,1,2=113,3=0.000000
L 5.65806713 3.06001654 5.65461644 3.0595 1 P 0 ;0,1,2=113,3=0.000000
L 5.65461644 3.0595 5.6515497 3.06001654 1 P 0 ;0,1,2=113,3=0.000000
L 5.6515497 3.06001654 5.64848297 3.06259931 1 P 0 ;0,1,2=113,3=0.000000
L 5.64848297 3.06259931 5.64656673 3.06569961 1 P 0 ;0,1,2=113,3=0.000000
L 5.64656673 3.06569961 5.64618346 3.0687999 1 P 0 ;0,1,2=113,3=0.000000
L 5.64618346 3.0687999 5.64695 3.07241575 1 P 0 ;0,1,2=113,3=0.000000
L 5.64695 3.07241575 5.64963346 3.07499951 1 P 0 ;0,1,2=113,3=0.000000
L 5.64963346 3.07499951 5.65231693 3.07603356 1 P 0 ;0,1,2=113,3=0.000000
L 5.65231693 3.07603356 5.65576693 3.07603356 1 P 0 ;0,1,2=113,3=0.000000
L 5.65231693 3.07603356 5.65001673 3.07758317 1 P 0 ;0,1,2=113,3=0.000000
L 5.65001673 3.07758317 5.6480998 3.08016594 1 P 0 ;0,1,2=113,3=0.000000
L 5.6480998 3.08016594 5.64733327 3.08326624 1 P 0 ;0,1,2=113,3=0.000000
L 5.64733327 3.08326624 5.6480998 3.08636654 1 P 0 ;0,1,2=113,3=0.000000
L 5.6480998 3.08636654 5.65001673 3.08894931 1 P 0 ;0,1,2=113,3=0.000000
L 5.65001673 3.08894931 5.65346673 3.0905 1 P 0 ;0,1,2=113,3=0.000000
L 5.65346673 3.0905 5.65691663 3.08998337 1 P 0 ;0,1,2=113,3=0.000000
L 5.65691663 3.08998337 5.66036663 3.08791624 1 P 0 ;0,1,2=113,3=0.000000
L 5.7604 3.0595 5.7604 3.0905 1 P 0 ;0,1,2=112,3=0.000000
L 5.7604 3.0905 5.77458376 3.06828327 1 P 0 ;0,1,2=112,3=0.000000
L 5.77458376 3.06828327 5.75541634 3.06828327 1 P 0 ;0,1,2=112,3=0.000000
L 5.66728356 2.86533346 5.66498337 2.86843278 1 P 0 ;0,1,2=7,3=0.000000
L 5.66498337 2.86843278 5.6622999 2.86998337 1 P 0 ;0,1,2=7,3=0.000000
L 5.6622999 2.86998337 5.65923317 2.8705 1 P 0 ;0,1,2=7,3=0.000000
L 5.65923317 2.8705 5.6554 2.86946683 1 P 0 ;0,1,2=7,3=0.000000
L 5.6554 2.86946683 5.65271654 2.86688307 1 P 0 ;0,1,2=7,3=0.000000
L 5.65271654 2.86688307 5.65195 2.86378376 1 P 0 ;0,1,2=7,3=0.000000
L 5.65195 2.86378376 5.65233327 2.86068258 1 P 0 ;0,1,2=7,3=0.000000
L 5.65233327 2.86068258 5.65386693 2.8580998 1 P 0 ;0,1,2=7,3=0.000000
L 5.65386693 2.8580998 5.66153337 2.85293327 1 P 0 ;0,1,2=7,3=0.000000
L 5.66153337 2.85293327 5.66498337 2.84931644 1 P 0 ;0,1,2=7,3=0.000000
L 5.66498337 2.84931644 5.66728356 2.84414892 1 P 0 ;0,1,2=7,3=0.000000
L 5.66728356 2.84414892 5.6680501 2.8395 1 P 0 ;0,1,2=7,3=0.000000
L 5.6680501 2.8395 5.65195 2.8395 1 P 0 ;0,1,2=7,3=0.000000
L 2.48208996 2.316 2.48208996 2.27751004 1 P 0 
L 2.48208996 2.27751004 2.4923 2.27751004 1 P 0 
L 2.4923 2.27751004 2.4923 2.20248996 1 P 0 
L 2.4923 2.20248996 2.48208996 2.20248996 1 P 0 
L 2.48208996 2.20248996 2.48208996 2.164 1 P 0 
L 2.39791004 2.316 2.48208996 2.316 1 P 0 
L 2.48208996 2.164 2.39791004 2.164 1 P 0 
L 2.39791004 2.164 2.39791004 2.20248996 1 P 0 
L 2.39791004 2.20248996 2.3877 2.20248996 1 P 0 
L 2.3877 2.20248996 2.3877 2.27751004 1 P 0 
L 2.3877 2.27751004 2.39791004 2.27751004 1 P 0 
L 2.39791004 2.27751004 2.39791004 2.316 1 P 0 
S P 0
OB 2.4847 2.138519980315 I
OC 2.4847 2.138519980315 2.4697 2.138519980315 Y
OE
SE
L 2.50586673 2.29324911 2.50426703 2.29116624 1 P 0 ;0,1,2=111,3=0.000000
L 2.50426703 2.29116624 2.5024003 2.28991654 1 P 0 ;0,1,2=111,3=0.000000
L 2.5024003 2.28991654 2.5000003 2.2895 1 P 0 ;0,1,2=111,3=0.000000
L 2.5000003 2.2895 2.4975998 2.29033307 1 P 0 ;0,1,2=111,3=0.000000
L 2.4975998 2.29033307 2.49573356 2.29199941 1 P 0 ;0,1,2=111,3=0.000000
L 2.49573356 2.29199941 2.4944 2.29491624 1 P 0 ;0,1,2=111,3=0.000000
L 2.4944 2.29491624 2.49413337 2.29824961 1 P 0 ;0,1,2=111,3=0.000000
L 2.49413337 2.29824961 2.49466663 2.30158297 1 P 0 ;0,1,2=111,3=0.000000
L 2.49466663 2.30158297 2.4960002 2.30366663 1 P 0 ;0,1,2=111,3=0.000000
L 2.4960002 2.30366663 2.49786693 2.30533297 1 P 0 ;0,1,2=111,3=0.000000
L 2.49786693 2.30533297 2.49973317 2.30574951 1 P 0 ;0,1,2=111,3=0.000000
L 2.49973317 2.30574951 2.5016 2.30533297 1 P 0 ;0,1,2=111,3=0.000000
L 2.5016 2.30533297 2.5039999 2.30366663 1 P 0 ;0,1,2=111,3=0.000000
L 2.5039999 2.30366663 2.5032001 2.3145 1 P 0 ;0,1,2=111,3=0.000000
L 2.5032001 2.3145 2.4960002 2.3145 1 P 0 ;0,1,2=111,3=0.000000
L 2.3668 2.2845 2.3668 2.3095 1 P 0 ;0,1,2=112,3=0.000000
L 2.3668 2.3095 2.37666703 2.29158327 1 P 0 ;0,1,2=112,3=0.000000
L 2.37666703 2.29158327 2.36333307 2.29158327 1 P 0 ;0,1,2=112,3=0.000000
L 2.3705 2.18556663 2.34828327 2.18556663 1 P 0 ;0,1,2=453,3=90.000000
L 2.34828327 2.18556663 2.34363238 2.1870997 1 P 0 ;0,1,2=453,3=90.000000
L 2.34363238 2.1870997 2.34053307 2.19016634 1 P 0 ;0,1,2=453,3=90.000000
L 2.34053307 2.19016634 2.3395 2.19399961 1 P 0 ;0,1,2=453,3=90.000000
L 2.3395 2.19399961 2.34053307 2.19783356 1 P 0 ;0,1,2=453,3=90.000000
L 2.34053307 2.19783356 2.34363238 2.2009002 1 P 0 ;0,1,2=453,3=90.000000
L 2.34363238 2.2009002 2.34828327 2.20243327 1 P 0 ;0,1,2=453,3=90.000000
L 2.34828327 2.20243327 2.3705 2.20243327 1 P 0 ;0,1,2=453,3=90.000000
L 2.3395 2.22499961 2.3705 2.22499961 1 P 0 ;0,1,2=453,3=90.000000
L 2.3705 2.22499961 2.3643003 2.2203999 1 P 0 ;0,1,2=453,3=90.000000
L 2.3395 2.2203999 2.3395 2.22959931 1 P 0 ;0,1,2=453,3=90.000000
L 2.3705 2.25599961 2.36946683 2.25293287 1 P 0 ;0,1,2=453,3=90.000000
L 2.36946683 2.25293287 2.36688307 2.25063337 1 P 0 ;0,1,2=453,3=90.000000
L 2.36688307 2.25063337 2.36378376 2.2490997 1 P 0 ;0,1,2=453,3=90.000000
L 2.36378376 2.2490997 2.35964941 2.2479499 1 P 0 ;0,1,2=453,3=90.000000
L 2.35964941 2.2479499 2.35499951 2.24756663 1 P 0 ;0,1,2=453,3=90.000000
L 2.35499951 2.24756663 2.35034951 2.2479499 1 P 0 ;0,1,2=453,3=90.000000
L 2.35034951 2.2479499 2.34621614 2.2490997 1 P 0 ;0,1,2=453,3=90.000000
L 2.34621614 2.2490997 2.34311585 2.25063337 1 P 0 ;0,1,2=453,3=90.000000
L 2.34311585 2.25063337 2.34053307 2.25293287 1 P 0 ;0,1,2=453,3=90.000000
L 2.34053307 2.25293287 2.3395 2.25599961 1 P 0 ;0,1,2=453,3=90.000000
L 2.3395 2.25599961 2.34053307 2.25906634 1 P 0 ;0,1,2=453,3=90.000000
L 2.34053307 2.25906634 2.34311585 2.26136654 1 P 0 ;0,1,2=453,3=90.000000
L 2.34311585 2.26136654 2.34621614 2.2629002 1 P 0 ;0,1,2=453,3=90.000000
L 2.34621614 2.2629002 2.35034951 2.26405 1 P 0 ;0,1,2=453,3=90.000000
L 2.35034951 2.26405 2.35499951 2.26443327 1 P 0 ;0,1,2=453,3=90.000000
L 2.35499951 2.26443327 2.35964941 2.26405 1 P 0 ;0,1,2=453,3=90.000000
L 2.35964941 2.26405 2.36378376 2.2629002 1 P 0 ;0,1,2=453,3=90.000000
L 2.36378376 2.2629002 2.36688307 2.26136654 1 P 0 ;0,1,2=453,3=90.000000
L 2.36688307 2.26136654 2.36946683 2.25906634 1 P 0 ;0,1,2=453,3=90.000000
L 2.36946683 2.25906634 2.3705 2.25599961 1 P 0 ;0,1,2=453,3=90.000000
L 2.38586673 2.12949961 2.38426703 2.12658287 1 P 0 ;0,1,2=113,3=0.000000
L 2.38426703 2.12658287 2.38213366 2.12491654 1 P 0 ;0,1,2=113,3=0.000000
L 2.38213366 2.12491654 2.37973317 2.1245 1 P 0 ;0,1,2=113,3=0.000000
L 2.37973317 2.1245 2.3775998 2.12491654 1 P 0 ;0,1,2=113,3=0.000000
L 2.3775998 2.12491654 2.37546644 2.12699941 1 P 0 ;0,1,2=113,3=0.000000
L 2.37546644 2.12699941 2.37413337 2.12949961 1 P 0 ;0,1,2=113,3=0.000000
L 2.37413337 2.12949961 2.37386683 2.1319999 1 P 0 ;0,1,2=113,3=0.000000
L 2.37386683 2.1319999 2.3744 2.13491594 1 P 0 ;0,1,2=113,3=0.000000
L 2.3744 2.13491594 2.37626673 2.13699961 1 P 0 ;0,1,2=113,3=0.000000
L 2.37626673 2.13699961 2.37813356 2.13783346 1 P 0 ;0,1,2=113,3=0.000000
L 2.37813356 2.13783346 2.38053346 2.13783346 1 P 0 ;0,1,2=113,3=0.000000
L 2.37813356 2.13783346 2.37653337 2.13908327 1 P 0 ;0,1,2=113,3=0.000000
L 2.37653337 2.13908327 2.3751999 2.14116614 1 P 0 ;0,1,2=113,3=0.000000
L 2.3751999 2.14116614 2.37466663 2.14366634 1 P 0 ;0,1,2=113,3=0.000000
L 2.37466663 2.14366634 2.3751999 2.14616654 1 P 0 ;0,1,2=113,3=0.000000
L 2.3751999 2.14616654 2.37653337 2.14824941 1 P 0 ;0,1,2=113,3=0.000000
L 2.37653337 2.14824941 2.37893337 2.1495 1 P 0 ;0,1,2=113,3=0.000000
L 2.37893337 2.1495 2.38133337 2.14908337 1 P 0 ;0,1,2=113,3=0.000000
L 2.38133337 2.14908337 2.38373337 2.14741634 1 P 0 ;0,1,2=113,3=0.000000
L 1.88008376 0.3645 1.87050039 0.3955 1 P 0 ;0,1,2=454,3=0.000000
L 1.87050039 0.3955 1.86091634 0.3645 1 P 0 ;0,1,2=454,3=0.000000
L 1.86436693 0.37534951 1.87663386 0.37534951 1 P 0 ;0,1,2=454,3=0.000000
L 1.83950039 0.3645 1.83950039 0.3955 1 P 0 ;0,1,2=454,3=0.000000
L 1.83950039 0.3955 1.8441001 0.3893003 1 P 0 ;0,1,2=454,3=0.000000
L 1.8441001 0.3645 1.83490069 0.3645 1 P 0 ;0,1,2=454,3=0.000000
L 3.0645 0.29941624 3.0955 0.30899961 1 P 0 ;0,1,2=455,3=90.000000
L 3.0955 0.30899961 3.0645 0.31858366 1 P 0 ;0,1,2=455,3=90.000000
L 3.07534951 0.31513307 3.07534951 0.30286614 1 P 0 ;0,1,2=455,3=90.000000
L 3.07069961 0.33156663 3.06708278 0.33386614 1 P 0 ;0,1,2=455,3=90.000000
L 3.06708278 0.33386614 3.06501654 0.33693287 1 P 0 ;0,1,2=455,3=90.000000
L 3.06501654 0.33693287 3.0645 0.34038356 1 P 0 ;0,1,2=455,3=90.000000
L 3.0645 0.34038356 3.06501654 0.3434503 1 P 0 ;0,1,2=455,3=90.000000
L 3.06501654 0.3434503 3.06759931 0.34651703 1 P 0 ;0,1,2=455,3=90.000000
L 3.06759931 0.34651703 3.07069961 0.34843327 1 P 0 ;0,1,2=455,3=90.000000
L 3.07069961 0.34843327 3.0737999 0.34881654 1 P 0 ;0,1,2=455,3=90.000000
L 3.0737999 0.34881654 3.07741575 0.34805 1 P 0 ;0,1,2=455,3=90.000000
L 3.07741575 0.34805 3.07999951 0.34536654 1 P 0 ;0,1,2=455,3=90.000000
L 3.07999951 0.34536654 3.08103356 0.34268307 1 P 0 ;0,1,2=455,3=90.000000
L 3.08103356 0.34268307 3.08103356 0.33923307 1 P 0 ;0,1,2=455,3=90.000000
L 3.08103356 0.34268307 3.08258317 0.34498327 1 P 0 ;0,1,2=455,3=90.000000
L 3.08258317 0.34498327 3.08516594 0.3469002 1 P 0 ;0,1,2=455,3=90.000000
L 3.08516594 0.3469002 3.08826624 0.34766673 1 P 0 ;0,1,2=455,3=90.000000
L 3.08826624 0.34766673 3.09136654 0.3469002 1 P 0 ;0,1,2=455,3=90.000000
L 3.09136654 0.3469002 3.09394931 0.34498327 1 P 0 ;0,1,2=455,3=90.000000
L 3.09394931 0.34498327 3.0955 0.34153327 1 P 0 ;0,1,2=455,3=90.000000
L 3.0955 0.34153327 3.09498337 0.33808337 1 P 0 ;0,1,2=455,3=90.000000
L 3.09498337 0.33808337 3.09291624 0.33463337 1 P 0 ;0,1,2=455,3=90.000000
L 3.09033346 0.36371644 3.09343278 0.36601663 1 P 0 ;0,1,2=455,3=90.000000
L 3.09343278 0.36601663 3.09498337 0.3687001 1 P 0 ;0,1,2=455,3=90.000000
L 3.09498337 0.3687001 3.0955 0.37176683 1 P 0 ;0,1,2=455,3=90.000000
L 3.0955 0.37176683 3.09446683 0.3756 1 P 0 ;0,1,2=455,3=90.000000
L 3.09446683 0.3756 3.09188307 0.37828346 1 P 0 ;0,1,2=455,3=90.000000
L 3.09188307 0.37828346 3.08878376 0.37905 1 P 0 ;0,1,2=455,3=90.000000
L 3.08878376 0.37905 3.08568258 0.37866673 1 P 0 ;0,1,2=455,3=90.000000
L 3.08568258 0.37866673 3.0830998 0.37713307 1 P 0 ;0,1,2=455,3=90.000000
L 3.0830998 0.37713307 3.07793327 0.36946663 1 P 0 ;0,1,2=455,3=90.000000
L 3.07793327 0.36946663 3.07431644 0.36601663 1 P 0 ;0,1,2=455,3=90.000000
L 3.07431644 0.36601663 3.06914892 0.36371644 1 P 0 ;0,1,2=455,3=90.000000
L 3.06914892 0.36371644 3.0645 0.3629499 1 P 0 ;0,1,2=455,3=90.000000
L 3.0645 0.3629499 3.0645 0.37905 1 P 0 ;0,1,2=455,3=90.000000

### steps/pcb/layers/sst/features
#
#Num Features
#
F 36867

#
#Units
#
U INCH

#
#Feature symbol names
#
$0 r5
$1 r6
$2 r10
$3 rect55.44x20 I

#
#Feature attribute names
#
@0 .nomenclature
@1 .string
@2 .string_angle

#
#Feature attribute text strings
#
&0 B
&1 A
&2 1
&3 11
&4 2
&5 J5
&6 12
&7 J13
&8 6
&9 U39
&10 3
&11 4
&12 U40
&13 16
&14 9
&15 U37
&16 8
&17 U38
&18 U30
&19 U19
&20 5
&21 CR2
&22 C
&23 CR1
&24 L17
&25 L18
&26 L19
&27 64
&28 U18
&29 49
&30 48
&31 33
&32 17
&33 32
&34 L5
&35 Q1
&36 SILKSCREEN TOP
&37 P/N : R4006-B0001-02
&38 Date: 2022-02-25
&39 Layer:
&40 Rev : 01
&41 TP50
&42 TP51
&43 TP48
&44 TP47
&45 TP62
&46 TP49
&47 TP46
&48 TP45
&49 TP44
&50 TP43
&51 TP42
&52 TP41
&53 TP40
&54 TP39
&55 TP38
&56 TP37
&57 TP36
&58 TP35
&59 TP34
&60 TP33
&61 TP32
&62 TP31
&63 TP30
&64 TP29
&65 TP28
&66 TP27
&67 TP26
&68 TP25
&69 TP24
&70 TP23
&71 TP22
&72 TP21
&73 TP20
&74 TP19
&75 TP18
&76 TP17
&77 TP16
&78 TP15
&79 TP14
&80 TP13
&81 TP12
&82 TP11
&83 TP56
&84 TP55
&85 TP59
&86 TP58
&87 TP53
&88 TP57
&89 TP139
&90 TP138
&91 TP61
&92 TP1
&93 TP54
&94 TP137
&95 TP135
&96 TP136
&97 TP134
&98 TP6
&99 TP78
&100 TP180
&101 TP183
&102 TP184
&103 TP185
&104 TP186
&105 TP187
&106 TP188
&107 TP193
&108 TP194
&109 TP196
&110 TP199
&111 TP200
&112 TP201
&113 TP202
&114 TP203
&115 TP204
&116 TP60
&117 TP52
&118 J9
&119 J17
&120 J1
&121 GH2
&122 GH4
&123 GH1
&124 GH3
&125 J2
&126 J3
&127 J4
&128 DS14
&129 DS17
&130 DS15
&131 DS18
&132 DS16
&133 10
&134 U41
&135 U21
&136 U25
&137 U20
&138 7
&139 U22
&140 28
&141 14
&142 U33
&143 22
&144 15
&145 21
&146 ME8
&147 ME6
&148 ME5
&149 ME7
&150 U15
&151 U16
&152 U13
&153 U14
&154 ME12
&155 ME9
&156 ME10
&157 ME11
&158 U7
&159 MAC_PIN4
&160 MAC_PIN6
&161 MAC_PIN7
&162 MAC_PIN8
&163 MAC_PIN3
&164 MAC_PIN5
&165 MAC_PIN1
&166 MAC_PIN2
&167 U27
&168 P3
&169 ME3
&170 ME4
&171 ME1
&172 ME2
&173 U28
&174 20
&175 U29
&176 L34
&177 L23
&178 L24
&179 L12
&180 L15
&181 L16
&182 L33
&183 L7
&184 L8
&185 L9
&186 L20
&187 L6
&188 L13
&189 L11
&190 CR12
&191 Y4
&192 Y3
&193 P2
&194 U23
&195 P1
&196 19
&197 AB
&198 AA
&199 V
&200 W
&201 Y
&202 U24
&203 T
&204 R
&205 P
&206 N
&207 U
&208 H
&209 M
&210 L
&211 K
&212 J
&213 E
&214 D
&215 G
&216 F
&217 18
&218 13
&219 C175
&220 C176
&221 C177
&222 C174
&223 C198
&224 FU1
&225 R9
&226 CR10
&227 U11
&228 U5
&229 U6
&230 U26
&231 U2
&232 L1
&233 L2
&234 U35
&235 U32
&236 U36
&237 U1
&238 R189
&239 R190
&240 Y1
&241 R240
&242 R242
&243 R236
&244 R88
&245 R96
&246 R287
&247 R63
&248 R57
&249 R55
&250 R56
&251 R22
&252 R25
&253 R354
&254 R104
&255 R266
&256 R98
&257 R97
&258 R87
&259 R366
&260 R364
&261 R362
&262 R348
&263 R339
&264 R238
&265 R234
&266 R167
&267 R164
&268 R496
&269 R497
&270 R498
&271 R499
&272 R487
&273 R452
&274 R486
&275 R485
&276 R472
&277 R471
&278 R462
&279 R461
&280 R449
&281 R448
&282 R484
&283 R459
&284 R453
&285 R456
&286 R443
&287 R465
&288 R464
&289 R481
&290 R480
&291 R477
&292 R476
&293 R475
&294 R474
&295 R435
&296 R490
&297 R439
&298 R438
&299 R327
&300 R325
&301 R308
&302 R285
&303 R283
&304 R445
&305 R442
&306 R455
&307 R186
&308 R128
&309 R129
&310 R346
&311 R347
&312 R350
&313 R351
&314 R356
&315 R352
&316 R353
&317 R237
&318 R359
&319 R360
&320 R120
&321 R121
&322 R122
&323 R126
&324 R127
&325 R156
&326 R157
&327 R367
&328 R370
&329 R371
&330 R372
&331 R34
&332 R399
&333 R427
&334 R425
&335 R426
&336 R398
&337 R397
&338 R376
&339 R391
&340 R374
&341 R424
&342 R394
&343 R400
&344 R385
&345 R124
&346 R272
&347 R388
&348 R273
&349 R373
&350 R21
&351 R20
&352 R70
&353 R72
&354 R381
&355 R331
&356 R383
&357 R365
&358 R377
&359 R368
&360 R393
&361 R375
&362 R392
&363 R396
&364 R401
&365 R395
&366 R386
&367 R125
&368 R387
&369 R389
&370 R274
&371 R390
&372 R7
&373 R8
&374 R4
&375 R313
&376 R184
&377 R183
&378 R312
&379 R46
&380 R15
&381 R19
&382 R1992
&383 R345
&384 R13
&385 R11
&386 R12
&387 R71
&388 R73
&389 R361
&390 R408
&391 R412
&392 R418
&393 R29
&394 R406
&395 R422
&396 R6
&397 R294
&398 R5
&399 R306
&400 R291
&401 R79
&402 R78
&403 R301
&404 R307
&405 R94
&406 R95
&407 R214
&408 R193
&409 R213
&410 R289
&411 R302
&412 R83
&413 R277
&414 R84
&415 R85
&416 R276
&417 R86
&418 R290
&419 R194
&420 R222
&421 R221
&422 R241
&423 R239
&424 R235
&425 R212
&426 R211
&427 R93
&428 R288
&429 R143
&430 R181
&431 R178
&432 R305
&433 R141
&434 R320
&435 R311
&436 R310
&437 R140
&438 R52
&439 R35
&440 R17
&441 R38
&442 R40
&443 R268
&444 R112
&445 R116
&446 R117
&447 R113
&448 R114
&449 R324
&450 R323
&451 R182
&452 R179
&453 R170
&454 R172
&455 R254
&456 R248
&457 R255
&458 R245
&459 R419
&460 R414
&461 R410
&462 R423
&463 R298
&464 R297
&465 R296
&466 R299
&467 R67
&468 R68
&469 R66
&470 R407
&471 R292
&472 R303
&473 R304
&474 R489
&475 R14
&476 R231
&477 R228
&478 R185
&479 R166
&480 R187
&481 DS12
&482 DS20
&483 DS19
&484 DS3
&485 DS6
&486 DS4
&487 DS9
&488 DS1
&489 DS7
&490 DS11
&491 DS10
&492 DS5
&493 DS8
&494 DS2
&495 C310
&496 C311
&497 C317
&498 C318
&499 C307
&500 C4
&501 C8
&502 C11
&503 C43
&504 C75
&505 C86
&506 C87
&507 C51
&508 C47
&509 C234
&510 C231
&511 C192
&512 C191
&513 C190
&514 C55
&515 C16
&516 C77
&517 C193
&518 C258
&519 C264
&520 C267
&521 C291
&522 C155
&523 C137
&524 C308
&525 C284
&526 C9
&527 C10
&528 C6
&529 C30
&530 C32
&531 C14
&532 C15
&533 C13
&534 C173
&535 C269
&536 C260
&537 C271
&538 C270
&539 C292
&540 C239
&541 C228
&542 C224
&543 C48
&544 C21
&545 C20
&546 C232
&547 C238
&548 C22
&549 C240
&550 C194
&551 C72
&552 C185
&553 C50
&554 C79
&555 C186
&556 C300
&557 C195
&558 C257
&559 C61
&560 C253
&561 C254
&562 C247
&563 C148
&564 C37
&565 C288
&566 C287
&567 C249
&568 C250
&569 C309
&570 C97
&571 C298
&572 C302
&573 C304
&574 C85
&575 C84
&576 C83
&577 C3
&578 C2
&579 C5
&580 C7
&581 C278
&582 C277
&583 C276
&584 C225
&585 C312
&586 C313
&587 C33
&588 C41
&589 C29
&590 C31
&591 C74
&592 C17
&593 C12
&594 C306
&595 C268
&596 C92
&597 C285
&598 C183
&599 C227
&600 C251
&601 C252
&602 C242
&603 C230
&604 C226
&605 C18
&606 C52
&607 C236
&608 C235
&609 C233
&610 C237
&611 C187
&612 C272
&613 C314
&614 C38
&615 C196
&616 C188
&617 C184
&618 C76
&619 C49
&620 C46
&621 C182
&622 C199
&623 C53
&624 C81
&625 C197
&626 C189
&627 C259
&628 C256
&629 C262
&630 C89
&631 C255
&632 C261
&633 C305
&634 C63
&635 C40
&636 C274
&637 C275
&638 C280
&639 C281
&640 C279
&641 J18
&642 CR5
&643 CR4
&644 Y2
&645 U3
&646 U34
&647 U17
&648 U9
&649 J10
&650 J14
&651 J11
&652 U4
&653 B1
&654 GF1
&655 B32

#
#Layer features
#
L 3.295 2.1 3.295 2.13 1 P 0 
L 3.295 2.13 3.285 2.13 1 P 0 
L 3.295 2.01 3.295 2.06 1 P 0 
L 3.295 1.925 3.295 1.96 1 P 0 
L 3.245 1.79 3.245 1.855 1 P 0 
L 3.245 1.855 3.295 1.855 1 P 0 
L 3.295 1.855 3.295 1.885 1 P 0 
L 3.075 1.65 3.075 1.62 1 P 0 
L 3.075 1.62 3.095 1.62 1 P 0 
L 3.095 1.62 3.095 1.07 1 P 0 
L 3.095 1.07 3.245 1.07 1 P 0 
L 3.245 1.07 3.245 1.745 1 P 0 
L 3.075 1.855 3.075 1.795 1 P 0 
L 3.105 1.975 3.105 1.95 1 P 0 
L 3.105 1.95 3.08 1.95 1 P 0 
L 3.08 1.95 3.08 1.9 1 P 0 
L 3.11 2.07 3.11 2.005 1 P 0 
L 3.14 2.13 3.11 2.13 1 P 0 
L 3.11 2.13 3.11 2.105 1 P 0 
L 6.14096998 0.76166998 6.1406 0.76238002 1 P 8191 
L 6.14128002 0.76093996 6.14096998 0.76166998 1 P 8191 
L 6.14151998 0.76016998 6.14128002 0.76093996 1 P 8191 
L 6.14168996 0.75938996 6.14151998 0.76016998 1 P 8191 
L 6.14151998 0.75541998 6.14168996 0.75621004 1 P 8191 
L 6.10686998 0.76703002 6.10606998 0.76713996 1 P 8191 
L 6.10768002 0.767 6.10686998 0.76703002 1 P 8191 
L 6.13248002 0.767 6.10768002 0.767 1 P 0 
L 6.10606998 0.76713996 6.10528002 0.76731998 1 P 8191 
L 6.11083002 0.83293996 6.11071998 0.83216004 1 P 8191 
L 6.111 0.8337 6.11083002 0.83293996 1 P 8191 
L 6.11123996 0.83448002 6.111 0.8337 1 P 8191 
L 6.11068002 0.83136998 6.11071998 0.83058002 1 P 8191 
L 6.11071998 0.83058002 6.11083002 0.82981004 1 P 8191 
L 6.11071998 0.83216004 6.11068002 0.83136998 1 P 8191 
L 6.11083002 0.82981004 6.111 0.82903996 1 P 8191 
L 6.111 0.82903996 6.11123996 0.82826004 1 P 8191 
L 6.11123996 0.82826004 6.11156004 0.8275 1 P 8191 
L 6.11755 0.82248996 6.11831998 0.82231004 1 P 8191 
L 6.11831998 0.82231004 6.1191 0.82221998 1 P 8191 
L 6.1191 0.82221998 6.11988002 0.82218002 1 P 8191 
L 6.11988002 0.82218002 6.13068002 0.82218002 1 P 0 
L 6.1146 0.82386004 6.11528002 0.82341998 1 P 8191 
L 6.11528002 0.82341998 6.116 0.82306004 1 P 8191 
L 6.116 0.82306004 6.11676998 0.82273996 1 P 8191 
L 6.11676998 0.82273996 6.11755 0.82248996 1 P 8191 
L 6.11156004 0.8275 6.11193002 0.82676998 1 P 8191 
L 6.11193002 0.82676998 6.11236004 0.82608996 1 P 8191 
L 6.11236004 0.82608996 6.11283996 0.82546004 1 P 8191 
L 6.11283996 0.82546004 6.11338002 0.82486998 1 P 8191 
L 6.11338002 0.82486998 6.11396004 0.82433996 1 P 8191 
L 6.11396004 0.82433996 6.1146 0.82386004 1 P 8191 
L 6.10606998 0.78525 6.10686998 0.78535 1 P 8191 
L 6.10686998 0.78535 6.10768002 0.78538996 1 P 8191 
L 6.10768002 0.78538996 6.17858996 0.78538996 1 P 0 
L 6.10528002 0.78506004 6.10606998 0.78525 1 P 8191 
L 6.13856004 0.76478002 6.1379 0.76526998 1 P 8191 
L 6.13916004 0.76423996 6.13856004 0.76478002 1 P 8191 
L 6.1397 0.76366004 6.13916004 0.76423996 1 P 8191 
L 6.13563996 0.76641998 6.13483996 0.76668002 1 P 8191 
L 6.13643996 0.76608996 6.13563996 0.76641998 1 P 8191 
L 6.1372 0.76571004 6.13643996 0.76608996 1 P 8191 
L 6.1379 0.76526998 6.1372 0.76571004 1 P 8191 
L 6.13483996 0.76668002 6.13405 0.76686004 1 P 8191 
L 6.14018002 0.76303996 6.1397 0.76366004 1 P 8191 
L 6.1406 0.76238002 6.14018002 0.76303996 1 P 8191 
L 6.13326004 0.76696004 6.13248002 0.767 1 P 8191 
L 6.13405 0.76686004 6.13326004 0.76696004 1 P 8191 
L 6.13973996 0.83298002 6.13956998 0.83375 1 P 8191 
L 6.13956998 0.83375 6.13933002 0.83451998 1 P 8191 
L 6.13985 0.83218002 6.13973996 0.83298002 1 P 8191 
L 6.13973996 0.82976998 6.13985 0.83056998 1 P 8191 
L 6.13985 0.83056998 6.13988002 0.83136998 1 P 8191 
L 6.13988002 0.83136998 6.13985 0.83218002 1 P 8191 
L 6.13865 0.82678002 6.13901998 0.82748996 1 P 8191 
L 6.13901998 0.82748996 6.13933002 0.82823002 1 P 8191 
L 6.13933002 0.82823002 6.13956998 0.82898996 1 P 8191 
L 6.13956998 0.82898996 6.13973996 0.82976998 1 P 8191 
L 6.13771998 0.82546004 6.13821998 0.8261 1 P 8191 
L 6.13821998 0.8261 6.13865 0.82678002 1 P 8191 
L 6.13596004 0.82383002 6.1366 0.82433002 1 P 8191 
L 6.1366 0.82433002 6.13718002 0.82486004 1 P 8191 
L 6.13718002 0.82486004 6.13771998 0.82546004 1 P 8191 
L 6.13528002 0.82341004 6.13596004 0.82383002 1 P 8191 
L 6.13456998 0.82303996 6.13528002 0.82341004 1 P 8191 
L 6.13228996 0.82231998 6.13306998 0.82248996 1 P 8191 
L 6.13306998 0.82248996 6.13383002 0.82273002 1 P 8191 
L 6.13383002 0.82273002 6.13456998 0.82303996 1 P 8191 
L 6.13068002 0.82218002 6.1315 0.82221998 1 P 8191 
L 6.1315 0.82221998 6.13228996 0.82231998 1 P 8191 
L 6.11156004 0.83526004 6.11123996 0.83448002 1 P 8191 
L 6.11831998 0.84041998 6.11755 0.84026004 1 P 8191 
L 6.1191 0.84053996 6.11831998 0.84041998 1 P 8191 
L 6.11988002 0.84056998 6.1191 0.84053996 1 P 8191 
L 6.11528002 0.83931998 6.1146 0.83888996 1 P 8191 
L 6.116 0.83968996 6.11528002 0.83931998 1 P 8191 
L 6.11676998 0.84001004 6.116 0.83968996 1 P 8191 
L 6.11755 0.84026004 6.11676998 0.84001004 1 P 8191 
L 6.11396004 0.83841004 6.11338002 0.83786998 1 P 8191 
L 6.1146 0.83888996 6.11396004 0.83841004 1 P 8191 
L 6.11193002 0.83598002 6.11156004 0.83526004 1 P 8191 
L 6.11236004 0.83666004 6.11193002 0.83598002 1 P 8191 
L 6.11283996 0.83728996 6.11236004 0.83666004 1 P 8191 
L 6.11338002 0.83786998 6.11283996 0.83728996 1 P 8191 
L 6.13933002 0.83451998 6.13901998 0.83526004 1 P 8191 
L 6.13821998 0.83663996 6.13771998 0.83728996 1 P 8191 
L 6.13865 0.83596004 6.13821998 0.83663996 1 P 8191 
L 6.13901998 0.83526004 6.13865 0.83596004 1 P 8191 
L 6.13596004 0.83891004 6.13528002 0.83933996 1 P 8191 
L 6.1366 0.83841998 6.13596004 0.83891004 1 P 8191 
L 6.13718002 0.83788002 6.1366 0.83841998 1 P 8191 
L 6.13771998 0.83728996 6.13718002 0.83788002 1 P 8191 
L 6.13528002 0.83933996 6.13456998 0.8397 1 P 8191 
L 6.13306998 0.84026004 6.13228996 0.84041998 1 P 8191 
L 6.13383002 0.84001998 6.13306998 0.84026004 1 P 8191 
L 6.13456998 0.8397 6.13383002 0.84001998 1 P 8191 
L 6.1315 0.84053996 6.13068002 0.84056998 1 P 8191 
L 6.13228996 0.84041998 6.1315 0.84053996 1 P 8191 
L 6.14183996 0.7578 6.1418 0.7586 1 P 8191 
L 6.1418 0.7586 6.14168996 0.75938996 1 P 8191 
L 6.14168996 0.75621004 6.1418 0.757 1 P 8191 
L 6.1418 0.757 6.14183996 0.7578 1 P 8191 
L 6.17858996 0.78538996 6.17938002 0.78541998 1 P 8191 
L 6.17938002 0.80375 6.17858996 0.80378002 1 P 8191 
L 6.18763996 0.79696004 6.18738996 0.79771998 1 P 8191 
L 6.1878 0.79618002 6.18763996 0.79696004 1 P 8191 
L 6.18795 0.79458002 6.18791998 0.79538002 1 P 8191 
L 6.18791998 0.79538002 6.1878 0.79618002 1 P 8191 
L 6.18763996 0.79221998 6.1878 0.79298996 1 P 8191 
L 6.1878 0.79298996 6.18791998 0.79378996 1 P 8191 
L 6.18791998 0.79378996 6.18795 0.79458002 1 P 8191 
L 6.18671998 0.79001004 6.18708002 0.79071004 1 P 8191 
L 6.18708002 0.79071004 6.18738996 0.79146004 1 P 8191 
L 6.18738996 0.79146004 6.18763996 0.79221998 1 P 8191 
L 6.18628996 0.78935 6.18671998 0.79001004 1 P 8191 
L 6.18401998 0.78711004 6.18468002 0.78761004 1 P 8191 
L 6.18468002 0.78761004 6.18528002 0.78813996 1 P 8191 
L 6.18528002 0.78813996 6.18581004 0.78873002 1 P 8191 
L 6.18581004 0.78873002 6.18628996 0.78935 1 P 8191 
L 6.18176004 0.78596004 6.18256004 0.7863 1 P 8191 
L 6.18256004 0.7863 6.18331998 0.78668002 1 P 8191 
L 6.18331998 0.78668002 6.18401998 0.78711004 1 P 8191 
L 6.18096004 0.78571004 6.18176004 0.78596004 1 P 8191 
L 6.17938002 0.78541998 6.18016998 0.78553002 1 P 8191 
L 6.18016998 0.78553002 6.18096004 0.78571004 1 P 8191 
L 6.18708002 0.79846004 6.18671998 0.79916004 1 P 8191 
L 6.18738996 0.79771998 6.18708002 0.79846004 1 P 8191 
L 6.18468002 0.80156004 6.18401998 0.80206004 1 P 8191 
L 6.18528002 0.80101998 6.18468002 0.80156004 1 P 8191 
L 6.18581004 0.80045 6.18528002 0.80101998 1 P 8191 
L 6.18628996 0.79981998 6.18581004 0.80045 1 P 8191 
L 6.18671998 0.79916004 6.18628996 0.79981998 1 P 8191 
L 6.18176004 0.80321004 6.18096004 0.80346004 1 P 8191 
L 6.18256004 0.80288002 6.18176004 0.80321004 1 P 8191 
L 6.18331998 0.8025 6.18256004 0.80288002 1 P 8191 
L 6.18401998 0.80206004 6.18331998 0.8025 1 P 8191 
L 6.18016998 0.80363996 6.17938002 0.80375 1 P 8191 
L 6.18096004 0.80346004 6.18016998 0.80363996 1 P 8191 
L 6.13916004 0.75136004 6.1397 0.75193996 1 P 8191 
L 6.1397 0.75193996 6.14018002 0.75256004 1 P 8191 
L 6.14018002 0.75256004 6.1406 0.75321998 1 P 8191 
L 6.1379 0.75033002 6.13856004 0.75081998 1 P 8191 
L 6.13856004 0.75081998 6.13916004 0.75136004 1 P 8191 
L 6.1372 0.74988996 6.1379 0.75033002 1 P 8191 
L 6.14128002 0.75466004 6.14151998 0.75541998 1 P 8191 
L 6.1406 0.75321998 6.14096998 0.75393002 1 P 8191 
L 6.14096998 0.75393002 6.14128002 0.75466004 1 P 8191 
L 6.13643996 0.7495 6.1372 0.74988996 1 P 8191 
L 6.12031004 0.71191998 6.12083996 0.71206004 1 P 8191 
L 6.12083996 0.71206004 6.1214 0.71226004 1 P 8191 
L 6.11928002 0.71181998 6.11978002 0.71183996 1 P 8191 
L 6.11978002 0.71183996 6.12031004 0.71191998 1 P 8191 
L 6.12168002 0.72928996 6.12086998 0.72961998 1 P 8191 
L 6.11846998 0.73018002 6.11768002 0.73021004 1 P 8191 
L 6.11926998 0.73006004 6.11846998 0.73018002 1 P 8191 
L 6.12006004 0.72988996 6.11926998 0.73006004 1 P 8191 
L 6.12086998 0.72961998 6.12006004 0.72988996 1 P 8191 
L 6.12423996 0.71423996 6.12476004 0.71483002 1 P 8191 
L 6.12476004 0.71483002 6.12526998 0.71548002 1 P 8191 
L 6.12311998 0.71326004 6.12368996 0.71371998 1 P 8191 
L 6.12368996 0.71371998 6.12423996 0.71423996 1 P 8191 
L 6.1214 0.71226004 6.12196998 0.71253002 1 P 8191 
L 6.12196998 0.71253002 6.12253996 0.71286004 1 P 8191 
L 6.12253996 0.71286004 6.12311998 0.71326004 1 P 8191 
L 6.1238 0.72796004 6.12313996 0.72846004 1 P 8191 
L 6.12438996 0.72741998 6.1238 0.72796004 1 P 8191 
L 6.12491998 0.72683996 6.12438996 0.72741998 1 P 8191 
L 6.1254 0.72621998 6.12491998 0.72683996 1 P 8191 
L 6.12243996 0.7289 6.12168002 0.72928996 1 P 8191 
L 6.12313996 0.72846004 6.12243996 0.7289 1 P 8191 
L 6.1261 0.71691998 6.12643996 0.71771998 1 P 8191 
L 6.12643996 0.71771998 6.1267 0.71853002 1 P 8191 
L 6.1267 0.71853002 6.12688002 0.71933996 1 P 8191 
L 6.12526998 0.71548002 6.12571004 0.71618002 1 P 8191 
L 6.12571004 0.71618002 6.1261 0.71691998 1 P 8191 
L 6.12648996 0.7241 6.12618996 0.72485 1 P 8191 
L 6.12673002 0.72333996 6.12648996 0.7241 1 P 8191 
L 6.12691004 0.72255 6.12673002 0.72333996 1 P 8191 
L 6.127 0.72015 6.12703996 0.72096004 1 P 8191 
L 6.12703996 0.72096004 6.127 0.72176004 1 P 8191 
L 6.127 0.72176004 6.12691004 0.72255 1 P 8191 
L 6.12688002 0.71933996 6.127 0.72015 1 P 8191 
L 6.12581998 0.72556004 6.1254 0.72621998 1 P 8191 
L 6.12618996 0.72485 6.12581998 0.72556004 1 P 8191 
L 6.13483996 0.74891998 6.13563996 0.74918002 1 P 8191 
L 6.13563996 0.74918002 6.13643996 0.7495 1 P 8191 
L 6.13405 0.74873996 6.13483996 0.74891998 1 P 8191 
L 6.13248002 0.7486 6.13326004 0.74863996 1 P 8191 
L 6.13326004 0.74863996 6.13405 0.74873996 1 P 8191 
L 6.18795 0.67941998 6.18795 0.84056998 1 P 0 
A 6.17123002 0.75771004 6.17123002 0.75771004 6.16195 0.75771004 1 P 0 Y
L 6.10368996 0.76788996 6.10296004 0.76826004 1 P 8191 
L 6.10448002 0.76756998 6.10368996 0.76788996 1 P 8191 
L 6.10528002 0.76731998 6.10448002 0.76756998 1 P 8191 
L 6.10296004 0.78411998 6.10368996 0.7845 1 P 8191 
L 6.10368996 0.7845 6.10448002 0.78481998 1 P 8191 
L 6.10448002 0.78481998 6.10528002 0.78506004 1 P 8191 
L 5.9774 0.76113996 5.97731998 0.76096004 1 P 8191 
L 5.97748002 0.7613 5.9774 0.76113996 1 P 8191 
L 5.97756998 0.76146998 5.97748002 0.7613 1 P 8191 
L 5.97776004 0.76178002 5.97766004 0.76161998 1 P 8191 
L 5.97766004 0.76161998 5.97756998 0.76146998 1 P 8191 
L 5.97795 0.76205 5.97785 0.76191998 1 P 8191 
L 5.97785 0.76191998 5.97776004 0.76178002 1 P 8191 
L 6.00241004 0.75826004 5.99206998 0.75826004 1 P 0 
L 5.99206998 0.75826004 5.99206998 0.76138002 1 P 8191 
L 5.96508996 0.76461998 5.9651 0.7647 1 P 8191 
L 5.9651 0.7647 5.96511004 0.76476998 1 P 8191 
L 5.96511004 0.76476998 5.96511998 0.76483996 1 P 8191 
L 5.96511998 0.76483996 5.96515 0.7649 1 P 8191 
L 5.96515 0.7649 5.96518002 0.76498002 1 P 8191 
L 5.96518002 0.76498002 5.96521004 0.76503996 1 P 8191 
L 5.96521004 0.76503996 5.96525 0.7651 1 P 8191 
L 5.96525 0.7651 5.96528996 0.76513996 1 P 8191 
L 5.96528996 0.76513996 5.96533996 0.76518996 1 P 8191 
L 5.96533996 0.76518996 5.96538996 0.76523002 1 P 8191 
L 5.96538996 0.76523002 5.96543996 0.76526998 1 P 8191 
L 5.96543996 0.76526998 5.9655 0.7653 1 P 8191 
L 5.9655 0.7653 5.96556004 0.76533996 1 P 8191 
L 5.96556004 0.76533996 5.96563996 0.76536004 1 P 8191 
L 5.96563996 0.76536004 5.96571004 0.76538002 1 P 8191 
L 5.96571004 0.76538002 5.96578002 0.7654 1 P 8191 
L 5.96578002 0.7654 5.96585 0.7654 1 P 8191 
L 5.96585 0.7654 5.96593002 0.76541004 1 P 8191 
L 5.96593002 0.76541004 5.97998996 0.76541004 1 P 0 
L 5.98065 0.76573002 5.98071004 0.76581998 1 P 8191 
L 5.98071004 0.76581998 5.98076004 0.76591004 1 P 8191 
L 5.98076004 0.76591004 5.9808 0.76601998 1 P 8191 
L 5.9808 0.76601998 5.98081004 0.76613002 1 P 8191 
L 5.98081004 0.76613002 5.98081998 0.76623996 1 P 8191 
L 5.98081998 0.76623996 5.98081998 0.77201998 1 P 8191 
L 5.99248996 0.77643996 5.97973996 0.76386998 1 P 0 
L 5.97998996 0.76541004 5.98011004 0.76541998 1 P 8191 
L 5.98011004 0.76541998 5.98021004 0.76543996 1 P 8191 
L 5.98021004 0.76543996 5.98031998 0.76546998 1 P 8191 
L 5.98031998 0.76546998 5.98041004 0.76551998 1 P 8191 
L 5.98041004 0.76551998 5.9805 0.76558002 1 P 8191 
L 5.9805 0.76558002 5.98058002 0.76565 1 P 8191 
L 5.98058002 0.76565 5.98065 0.76573002 1 P 8191 
L 5.97805 0.76218002 5.97795 0.76205 1 P 8191 
L 5.97816004 0.7623 5.97805 0.76218002 1 P 8191 
L 5.97973996 0.76386998 5.97816004 0.7623 1 P 8191 
L 5.98203996 0.82976004 5.97901998 0.82883002 1 P 8191 
L 5.97935 0.82503002 5.98211004 0.82593002 1 P 8191 
L 5.97901998 0.82883002 5.97605 0.82773996 1 P 8191 
L 5.97663996 0.824 5.97935 0.82503002 1 P 8191 
L 5.97605 0.82773996 5.97316004 0.82648002 1 P 8191 
L 5.974 0.82281004 5.97663996 0.824 1 P 8191 
L 5.97316004 0.82648002 5.97033002 0.82506004 1 P 8191 
L 5.97033002 0.82506004 5.96758002 0.82346998 1 P 8191 
L 5.9635 0.7755 5.9636 0.7755 1 P 8191 
L 5.9636 0.7755 5.9637 0.7755 1 P 8191 
L 5.9637 0.7755 5.96378996 0.77553002 1 P 8191 
L 5.96378996 0.77553002 5.96388002 0.77555 1 P 8191 
L 5.96388002 0.77555 5.96396004 0.77558002 1 P 8191 
L 5.96396004 0.77558002 5.96403002 0.77561998 1 P 8191 
L 5.96403002 0.77561998 5.96408996 0.77566998 1 P 8191 
L 5.96408996 0.77566998 5.96415 0.77573002 1 P 8191 
L 5.96415 0.77573002 5.9642 0.77578996 1 P 8191 
L 5.9642 0.77578996 5.96423996 0.77586004 1 P 8191 
L 5.96423996 0.77586004 5.96426998 0.77593996 1 P 8191 
L 5.96426998 0.77593996 5.9643 0.77603002 1 P 8191 
L 5.9643 0.77603002 5.96431998 0.77611998 1 P 8191 
L 5.96431998 0.77611998 5.96433002 0.77621998 1 P 8191 
L 5.96433002 0.77621998 5.96433002 0.77633002 1 P 8191 
L 5.96433002 0.77633002 5.96433002 0.80531998 1 P 0 
L 5.9619 0.77256004 5.96176004 0.7725 1 P 8191 
L 5.96203996 0.77261998 5.9619 0.77256004 1 P 8191 
L 5.96216004 0.77266004 5.96203996 0.77261998 1 P 8191 
L 5.96255 0.77278996 5.96241998 0.77276004 1 P 8191 
L 5.96241998 0.77276004 5.9623 0.77271004 1 P 8191 
L 5.9623 0.77271004 5.96216004 0.77266004 1 P 8191 
L 5.96278996 0.77283996 5.96266998 0.77281998 1 P 8191 
L 5.96266998 0.77281998 5.96255 0.77278996 1 P 8191 
L 5.96291004 0.77286004 5.96278996 0.77283996 1 P 8191 
L 5.97998996 0.77286004 5.96291004 0.77286004 1 P 0 
L 5.98048002 0.7761 5.98051004 0.776 1 P 8191 
L 5.98051004 0.776 5.98056004 0.7759 1 P 8191 
L 5.98056004 0.7759 5.98061004 0.77581998 1 P 8191 
L 5.98061004 0.77581998 5.98068002 0.77573996 1 P 8191 
L 5.98043996 0.77633002 5.98045 0.77621004 1 P 8191 
L 5.98045 0.77621004 5.98048002 0.7761 1 P 8191 
L 5.98043996 0.79871004 5.98043996 0.77633002 1 P 0 
L 5.98068002 0.77573996 5.98076004 0.77566004 1 P 8191 
L 5.98076004 0.77566004 5.98086004 0.77561004 1 P 8191 
L 5.98086004 0.77561004 5.98096004 0.77556004 1 P 8191 
L 5.98096004 0.77556004 5.98105 0.77551998 1 P 8191 
L 5.98011004 0.77285 5.97998996 0.77286004 1 P 8191 
L 5.98041004 0.77273996 5.98031998 0.77278996 1 P 8191 
L 5.98031998 0.77278996 5.98021004 0.77281998 1 P 8191 
L 5.98021004 0.77281998 5.98011004 0.77285 1 P 8191 
L 5.98065 0.77253996 5.98058002 0.77261998 1 P 8191 
L 5.98058002 0.77261998 5.9805 0.77268002 1 P 8191 
L 5.9805 0.77268002 5.98041004 0.77273996 1 P 8191 
L 5.98081998 0.77201998 5.98081004 0.77213996 1 P 8191 
L 5.98081004 0.77213996 5.9808 0.77225 1 P 8191 
L 5.9808 0.77225 5.98076004 0.77233996 1 P 8191 
L 5.98076004 0.77233996 5.98071004 0.77243996 1 P 8191 
L 5.98071004 0.77243996 5.98065 0.77253996 1 P 8191 
L 5.97471004 0.7755 5.97481004 0.7755 1 P 8191 
L 5.97481004 0.7755 5.97491004 0.77551004 1 P 8191 
L 5.97491004 0.77551004 5.975 0.77553002 1 P 8191 
L 5.975 0.77553002 5.97508002 0.77555 1 P 8191 
L 5.97508002 0.77555 5.97516004 0.77558002 1 P 8191 
L 5.97516004 0.77558002 5.97523996 0.77561998 1 P 8191 
L 5.97523996 0.77561998 5.9753 0.77566998 1 P 8191 
L 5.9753 0.77566998 5.97536004 0.77573002 1 P 8191 
L 5.97536004 0.77573002 5.9754 0.77578996 1 P 8191 
L 5.9754 0.77578996 5.97543996 0.77586004 1 P 8191 
L 5.97543996 0.77586004 5.97548002 0.77593996 1 P 8191 
L 5.97548002 0.77593996 5.9755 0.77603002 1 P 8191 
L 5.9755 0.77603002 5.97551998 0.77611998 1 P 8191 
L 5.97551998 0.77611998 5.97553002 0.77621998 1 P 8191 
L 5.97553002 0.77621998 5.97553996 0.77633002 1 P 8191 
L 5.97553996 0.77633002 5.97553996 0.79871004 1 P 0 
L 5.96783996 0.77611998 5.96786004 0.77603002 1 P 8191 
L 5.96786004 0.77603002 5.96788002 0.77593996 1 P 8191 
L 5.96788002 0.77593996 5.96791998 0.77586004 1 P 8191 
L 5.96791998 0.77586004 5.96796004 0.77578996 1 P 8191 
L 5.96783002 0.77633002 5.96783996 0.77621998 1 P 8191 
L 5.96783996 0.77621998 5.96783996 0.77611998 1 P 8191 
L 5.96783002 0.80531998 5.96783002 0.77633002 1 P 0 
L 5.96796004 0.77578996 5.96801004 0.77573002 1 P 8191 
L 5.96801004 0.77573002 5.96806998 0.77566998 1 P 8191 
L 5.96806998 0.77566998 5.96813002 0.77561998 1 P 8191 
L 5.96813002 0.77561998 5.9682 0.77558002 1 P 8191 
L 5.9682 0.77558002 5.96828002 0.77555 1 P 8191 
L 5.96828002 0.77555 5.96836004 0.77553002 1 P 8191 
L 5.96836004 0.77553002 5.96846004 0.77551004 1 P 8191 
L 5.96846004 0.77551004 5.96856004 0.7755 1 P 8191 
L 5.96856004 0.7755 5.96866004 0.7755 1 P 8191 
L 5.96866004 0.7755 5.97471004 0.7755 1 P 0 
L 5.96758002 0.82346998 5.96491998 0.82173996 1 P 8191 
L 5.97141004 0.82148002 5.974 0.82281004 1 P 8191 
L 5.96433002 0.80531998 5.96433002 0.80543002 1 P 8191 
L 5.96433002 0.80543002 5.96431998 0.80553002 1 P 8191 
L 5.96431998 0.80553002 5.9643 0.80561998 1 P 8191 
L 5.9643 0.80561998 5.96426998 0.8057 1 P 8191 
L 5.96648002 0.81841004 5.96891004 0.82001998 1 P 8191 
L 5.96491998 0.82173996 5.96236998 0.81986004 1 P 8191 
L 5.96188002 0.8148 5.96411998 0.81666004 1 P 8191 
L 5.96411998 0.81666004 5.96648002 0.81841004 1 P 8191 
L 5.9636 0.80615 5.9635 0.80616004 1 P 8191 
L 5.96378996 0.80611998 5.9637 0.80613996 1 P 8191 
L 5.9637 0.80613996 5.9636 0.80615 1 P 8191 
L 5.96396004 0.80606004 5.96388002 0.8061 1 P 8191 
L 5.96388002 0.8061 5.96378996 0.80611998 1 P 8191 
L 5.9642 0.80586004 5.96415 0.80591998 1 P 8191 
L 5.96415 0.80591998 5.96408996 0.80598002 1 P 8191 
L 5.96408996 0.80598002 5.96403002 0.80601998 1 P 8191 
L 5.96403002 0.80601998 5.96396004 0.80606004 1 P 8191 
L 5.96426998 0.8057 5.96423996 0.80578002 1 P 8191 
L 5.96423996 0.80578002 5.9642 0.80586004 1 P 8191 
L 5.97553996 0.79871004 5.98043996 0.79871004 1 P 8191 
L 5.96786004 0.80553996 5.96783996 0.80543996 1 P 8191 
L 5.96783996 0.80543996 5.96783002 0.80531998 1 P 8191 
L 5.96793996 0.80573996 5.96788996 0.80565 1 P 8191 
L 5.96788996 0.80565 5.96786004 0.80553996 1 P 8191 
L 5.96891004 0.82001998 5.97141004 0.82148002 1 P 8191 
L 5.96855 0.80615 5.96843996 0.80613002 1 P 8191 
L 5.96866004 0.80616004 5.96855 0.80615 1 P 8191 
L 5.99008996 0.80616004 5.96866004 0.80616004 1 P 0 
L 5.968 0.80583002 5.96793996 0.80573996 1 P 8191 
L 5.96823996 0.80605 5.96815 0.80598002 1 P 8191 
L 5.96815 0.80598002 5.96806998 0.80591004 1 P 8191 
L 5.96806998 0.80591004 5.968 0.80583002 1 P 8191 
L 5.96833002 0.80608996 5.96823996 0.80605 1 P 8191 
L 5.96843996 0.80613002 5.96833002 0.80608996 1 P 8191 
L 5.96236998 0.81986004 5.95991998 0.81785 1 P 8191 
L 5.95973996 0.81281998 5.96188002 0.8148 1 P 8191 
L 5.99593996 0.76601998 6.00241004 0.76601998 1 P 0 
L 6.00288002 0.7729 5.99593996 0.76601998 1 P 0 
L 5.99775 0.83181998 5.99453996 0.83175 1 P 8191 
L 5.99356004 0.82796998 5.99648002 0.82808996 1 P 8191 
L 5.99456998 0.82308002 5.9944 0.8231 1 P 8191 
L 5.9944 0.8231 5.99423996 0.8231 1 P 8191 
L 5.99491998 0.82301998 5.99475 0.82306004 1 P 8191 
L 5.99475 0.82306004 5.99456998 0.82308002 1 P 8191 
L 5.9951 0.82298002 5.99491998 0.82301998 1 P 8191 
L 5.99546004 0.82288002 5.99528002 0.82293996 1 P 8191 
L 5.99528002 0.82293996 5.9951 0.82298002 1 P 8191 
L 5.99563996 0.82281998 5.99546004 0.82288002 1 P 8191 
L 5.99581998 0.82273996 5.99563996 0.82281998 1 P 8191 
L 5.99453996 0.83175 5.99136998 0.83151998 1 P 8191 
L 5.99065 0.82768996 5.99356004 0.82796998 1 P 8191 
L 5.99423996 0.8231 5.99248996 0.8231 1 P 8191 
L 5.99136998 0.83151998 5.98821998 0.8311 1 P 8191 
L 5.98776004 0.82726004 5.99065 0.82768996 1 P 8191 
L 5.98821998 0.8311 5.98511004 0.83051998 1 P 8191 
L 5.98491998 0.82666998 5.98776004 0.82726004 1 P 8191 
L 5.98511004 0.83051998 5.98203996 0.82976004 1 P 8191 
L 5.98211004 0.82593002 5.98491998 0.82666998 1 P 8191 
L 5.99648002 0.82808996 5.99943002 0.82805 1 P 8191 
L 5.99248996 0.8231 5.99248996 0.77643996 1 P 0 
L 5.98748002 0.7759 5.98751998 0.77598996 1 P 8191 
L 5.98751998 0.77598996 5.98756004 0.77608996 1 P 8191 
L 5.98756004 0.77608996 5.98756998 0.7762 1 P 8191 
L 5.98756998 0.7762 5.98758002 0.77633002 1 P 8191 
L 5.98758002 0.77633002 5.98758002 0.79871004 1 P 0 
L 5.9868 0.7755 5.98691004 0.7755 1 P 8191 
L 5.98691004 0.7755 5.98701004 0.77551998 1 P 8191 
L 5.98701004 0.77551998 5.98711004 0.77556004 1 P 8191 
L 5.98711004 0.77556004 5.9872 0.7756 1 P 8191 
L 5.9872 0.7756 5.98728002 0.77566004 1 P 8191 
L 5.98728002 0.77566004 5.98736004 0.77573002 1 P 8191 
L 5.98736004 0.77573002 5.98743002 0.77581004 1 P 8191 
L 5.98743002 0.77581004 5.98748002 0.7759 1 P 8191 
L 5.98105 0.77551998 5.98116004 0.7755 1 P 8191 
L 5.98116004 0.7755 5.98128002 0.7755 1 P 8191 
L 5.98128002 0.7755 5.9868 0.7755 1 P 8191 
L 5.98758002 0.79871004 5.99008996 0.79871004 1 P 8191 
L 5.99008996 0.79871004 5.99008996 0.80616004 1 P 0 
L 5.99985 0.81871998 5.99581998 0.82273996 1 P 8191 
L 6.03123002 0.75826004 6.02061998 0.75826004 1 P 0 
L 6.02061998 0.75826004 6.02061998 0.76571004 1 P 0 
L 6.03895 0.75711004 6.03896998 0.75726004 1 P 8191 
L 6.03896998 0.75726004 6.03898002 0.75738996 1 P 8191 
L 6.03898002 0.75738996 6.03898002 0.76693996 1 P 0 
L 6.03853996 0.75608002 6.03861998 0.75623002 1 P 8191 
L 6.03861998 0.75623002 6.0387 0.75638002 1 P 8191 
L 6.0387 0.75638002 6.03876004 0.75653002 1 P 8191 
L 6.03876004 0.75653002 6.03881998 0.75668002 1 P 8191 
L 6.03881998 0.75668002 6.03888002 0.75681998 1 P 8191 
L 6.03888002 0.75681998 6.03891998 0.75696998 1 P 8191 
L 6.03891998 0.75696998 6.03895 0.75711004 1 P 8191 
L 6.03123002 0.76571004 6.03123002 0.75826004 1 P 0 
L 6.00241004 0.76601998 6.00241004 0.75826004 1 P 0 
L 6.02061998 0.76571004 6.03123002 0.76571004 1 P 0 
L 6.05093002 0.76541004 6.06123002 0.76541004 1 P 0 
L 6.03893002 0.76743002 6.0389 0.76758996 1 P 8191 
L 6.0389 0.76758996 6.03886004 0.76776998 1 P 8191 
L 6.03886004 0.76776998 6.03881004 0.76793996 1 P 8191 
L 6.03881004 0.76793996 6.03876004 0.76811004 1 P 8191 
L 6.03876004 0.76811004 6.0387 0.7683 1 P 8191 
L 6.0387 0.7683 6.03863002 0.76846998 1 P 8191 
L 6.03898002 0.76693996 6.03896998 0.7671 1 P 8191 
L 6.03896998 0.7671 6.03896004 0.76726004 1 P 8191 
L 6.03896004 0.76726004 6.03893002 0.76743002 1 P 8191 
L 6.03863002 0.76846998 6.0346 0.7725 1 P 8191 
L 6.01005 0.76756998 6.01003002 0.76766004 1 P 8191 
L 6.01003002 0.76766004 6.01001004 0.76775 1 P 8191 
L 6.01001004 0.76775 6.00998996 0.76783996 1 P 8191 
L 6.00998996 0.76783996 6.00996004 0.76793002 1 P 8191 
L 6.00996004 0.76793002 6.00993996 0.76801998 1 P 8191 
L 6.00993996 0.76801998 6.00991998 0.7681 1 P 8191 
L 6.00991998 0.7681 6.00988996 0.76818996 1 P 8191 
L 6.00988996 0.76818996 6.00986004 0.76828002 1 P 8191 
L 6.00986004 0.76828002 6.00983996 0.76836004 1 P 8191 
L 6.00983996 0.76836004 6.0098 0.76843996 1 P 8191 
L 6.0098 0.76843996 6.00976998 0.76851998 1 P 8191 
L 6.01011998 0.76693996 6.01011998 0.76703002 1 P 8191 
L 6.01011998 0.76703002 6.01011998 0.76711004 1 P 8191 
L 6.01011998 0.76711004 6.01011004 0.76721004 1 P 8191 
L 6.01011004 0.76721004 6.01008996 0.7673 1 P 8191 
L 6.01008996 0.7673 6.01008002 0.76738002 1 P 8191 
L 6.01008002 0.76738002 6.01006998 0.76746998 1 P 8191 
L 6.01006998 0.76746998 6.01005 0.76756998 1 P 8191 
L 6.00976998 0.76851998 6.00573996 0.77255 1 P 8191 
L 6.02501998 0.82458002 6.02221004 0.82605 1 P 8191 
L 6.02221004 0.82605 6.01933996 0.82736004 1 P 8191 
L 6.01913002 0.82343996 6.02175 0.82218002 1 P 8191 
L 6.02773996 0.82295 6.02501998 0.82458002 1 P 8191 
L 6.01933996 0.82736004 6.0164 0.8285 1 P 8191 
L 6.01645 0.82455 6.01913002 0.82343996 1 P 8191 
L 6.01371998 0.82551004 6.01645 0.82455 1 P 8191 
L 6.0164 0.8285 6.0134 0.82948996 1 P 8191 
L 6.01093002 0.82633002 6.01371998 0.82551004 1 P 8191 
L 6.0134 0.82948996 6.01033996 0.8303 1 P 8191 
L 6.02423996 0.79381998 6.02413996 0.79383996 1 P 8191 
L 6.02413996 0.79383996 6.02401998 0.79385 1 P 8191 
L 6.02453002 0.79366998 6.02443996 0.79373996 1 P 8191 
L 6.02443996 0.79373996 6.02435 0.79378002 1 P 8191 
L 6.02435 0.79378002 6.02423996 0.79381998 1 P 8191 
L 6.02478996 0.79333996 6.02473996 0.79343002 1 P 8191 
L 6.02473996 0.79343002 6.02468002 0.79353002 1 P 8191 
L 6.02468002 0.79353002 6.02461004 0.79361004 1 P 8191 
L 6.02461004 0.79361004 6.02453002 0.79366998 1 P 8191 
L 6.02485 0.79301998 6.02483996 0.79313002 1 P 8191 
L 6.02483996 0.79313002 6.02483002 0.79323996 1 P 8191 
L 6.02483002 0.79323996 6.02478996 0.79333996 1 P 8191 
L 6.02401998 0.7878 6.02411998 0.78781004 1 P 8191 
L 6.02411998 0.78781004 6.02421998 0.78781998 1 P 8191 
L 6.02421998 0.78781998 6.02431998 0.78783002 1 P 8191 
L 6.02431998 0.78783002 6.0244 0.78786004 1 P 8191 
L 6.0244 0.78786004 6.02448002 0.7879 1 P 8191 
L 6.02448002 0.7879 6.02456004 0.78793996 1 P 8191 
L 6.02456004 0.78793996 6.02461998 0.78798002 1 P 8191 
L 6.02461998 0.78798002 6.02468002 0.78803996 1 P 8191 
L 6.02468002 0.78803996 6.02471998 0.7881 1 P 8191 
L 6.02471998 0.7881 6.02476004 0.78818002 1 P 8191 
L 6.02476004 0.78818002 6.0248 0.78826004 1 P 8191 
L 6.0248 0.78826004 6.02481998 0.78833996 1 P 8191 
L 6.02481998 0.78833996 6.02483996 0.78843002 1 P 8191 
L 6.02483996 0.78843002 6.02485 0.78853002 1 P 8191 
L 6.02485 0.78853002 6.02485 0.78863002 1 P 8191 
L 6.02485 0.78863002 6.02485 0.79301998 1 P 8191 
L 6.05091998 0.77498002 6.05408002 0.77498002 1 P 8191 
L 6.05081004 0.77793002 6.05091998 0.77498002 1 P 8191 
L 6.04325 0.77225 6.04323002 0.77213996 1 P 8191 
L 6.04323002 0.77213996 6.04321998 0.77201998 1 P 8191 
L 6.04328002 0.77233996 6.04325 0.77225 1 P 8191 
L 6.04346004 0.77261998 6.04338996 0.77253996 1 P 8191 
L 6.04338996 0.77253996 6.04333002 0.77243996 1 P 8191 
L 6.04333002 0.77243996 6.04328002 0.77233996 1 P 8191 
L 6.04353996 0.77268002 6.04346004 0.77261998 1 P 8191 
L 6.04383002 0.77281998 6.04371998 0.77278996 1 P 8191 
L 6.04371998 0.77278996 6.04363002 0.77273996 1 P 8191 
L 6.04363002 0.77273996 6.04353996 0.77268002 1 P 8191 
L 6.04405 0.77286004 6.04393996 0.77285 1 P 8191 
L 6.04393996 0.77285 6.04383002 0.77281998 1 P 8191 
L 6.06301998 0.77286004 6.04405 0.77286004 1 P 0 
L 6.03388002 0.77273996 6.0337 0.77278002 1 P 8191 
L 6.03406004 0.77268996 6.03388002 0.77273996 1 P 8191 
L 6.03441998 0.77258002 6.03423996 0.77263002 1 P 8191 
L 6.03423996 0.77263002 6.03406004 0.77268996 1 P 8191 
L 6.0346 0.7725 6.03441998 0.77258002 1 P 8191 
L 6.03318996 0.77285 6.03301998 0.77286004 1 P 8191 
L 6.03351998 0.77281004 6.03336004 0.77283002 1 P 8191 
L 6.03336004 0.77283002 6.03318996 0.77285 1 P 8191 
L 6.0337 0.77278002 6.03351998 0.77281004 1 P 8191 
L 6.02621004 0.7755 6.02631998 0.7755 1 P 8191 
L 6.02631998 0.7755 6.02643996 0.77551998 1 P 8191 
L 6.02643996 0.77551998 6.02653996 0.77556004 1 P 8191 
L 6.02653996 0.77556004 6.02663996 0.77561004 1 P 8191 
L 6.02663996 0.77561004 6.02671998 0.77566004 1 P 8191 
L 6.02671998 0.77566004 6.0268 0.77573996 1 P 8191 
L 6.0268 0.77573996 6.02688002 0.77581998 1 P 8191 
L 6.02688002 0.77581998 6.02693002 0.7759 1 P 8191 
L 6.02693002 0.7759 6.02698002 0.776 1 P 8191 
L 6.02698002 0.776 6.02701004 0.7761 1 P 8191 
L 6.02701004 0.7761 6.02703996 0.77621004 1 P 8191 
L 6.02703996 0.77621004 6.02703996 0.77633002 1 P 8191 
L 6.02703996 0.77633002 6.02703996 0.7818 1 P 8191 
L 6.05188002 0.79066004 6.05093002 0.79366998 1 P 8191 
L 6.05268002 0.78758996 6.05188002 0.79066004 1 P 8191 
L 6.05328002 0.7845 6.05268002 0.78758996 1 P 8191 
L 6.04981004 0.79661998 6.04851998 0.79951004 1 P 8191 
L 6.05093002 0.79366998 6.04981004 0.79661998 1 P 8191 
L 6.04881004 0.78938002 6.04955 0.78656004 1 P 8191 
L 6.04955 0.78656004 6.05011998 0.78371004 1 P 8191 
L 6.05011998 0.78371004 6.05055 0.78083996 1 P 8191 
L 6.05055 0.78083996 6.05081004 0.77793002 1 P 8191 
L 6.04571998 0.7975 6.0469 0.79485 1 P 8191 
L 6.0469 0.79485 6.04793002 0.79213996 1 P 8191 
L 6.04793002 0.79213996 6.04881004 0.78938002 1 P 8191 
L 6.02653996 0.78256998 6.02643996 0.7826 1 P 8191 
L 6.02643996 0.7826 6.02633002 0.78261998 1 P 8191 
L 6.02633002 0.78261998 6.02621004 0.78263002 1 P 8191 
L 6.0268 0.78238996 6.02671998 0.78246004 1 P 8191 
L 6.02671998 0.78246004 6.02663996 0.78251998 1 P 8191 
L 6.02663996 0.78251998 6.02653996 0.78256998 1 P 8191 
L 6.02703996 0.7818 6.02703996 0.78191004 1 P 8191 
L 6.02703996 0.78191004 6.02701004 0.78201998 1 P 8191 
L 6.02701004 0.78201998 6.02698002 0.78211998 1 P 8191 
L 6.02698002 0.78211998 6.02693002 0.78221998 1 P 8191 
L 6.02693002 0.78221998 6.02688002 0.78231004 1 P 8191 
L 6.02688002 0.78231004 6.0268 0.78238996 1 P 8191 
L 6.01353996 0.77268002 6.01346004 0.77261998 1 P 8191 
L 6.01383002 0.77281998 6.01373002 0.77278996 1 P 8191 
L 6.01373002 0.77278996 6.01363002 0.77273996 1 P 8191 
L 6.01363002 0.77273996 6.01353996 0.77268002 1 P 8191 
L 6.01405 0.77286004 6.01393996 0.77285 1 P 8191 
L 6.01393996 0.77285 6.01383002 0.77281998 1 P 8191 
L 6.03301998 0.77286004 6.01405 0.77286004 1 P 0 
L 6.01323002 0.77213996 6.01321998 0.77201998 1 P 8191 
L 6.01328002 0.77233996 6.01325 0.77225 1 P 8191 
L 6.01325 0.77225 6.01323002 0.77213996 1 P 8191 
L 6.01346004 0.77261998 6.01338996 0.77253996 1 P 8191 
L 6.01338996 0.77253996 6.01333002 0.77243996 1 P 8191 
L 6.01333002 0.77243996 6.01328002 0.77233996 1 P 8191 
L 6.00913002 0.77551004 6.00931998 0.7755 1 P 8191 
L 6.00931998 0.7755 6.00951998 0.7755 1 P 8191 
L 6.00951998 0.7755 6.02621004 0.7755 1 P 0 
L 6.0115 0.79385 6.01146004 0.79386004 1 P 8191 
L 6.01146004 0.79386004 6.01143002 0.79388002 1 P 8191 
L 6.01143002 0.79388002 6.0114 0.7939 1 P 8191 
L 6.0114 0.7939 6.01136998 0.79391998 1 P 8191 
L 6.01136998 0.79391998 6.01135 0.79393996 1 P 8191 
L 6.01135 0.79393996 6.01133002 0.79396998 1 P 8191 
L 6.01133002 0.79396998 6.01131998 0.79398996 1 P 8191 
L 6.01131998 0.79398996 6.01131998 0.79401998 1 P 8191 
L 6.01131998 0.79401998 6.01131998 0.7988 1 P 8191 
L 6.01153996 0.79385 6.0115 0.79385 1 P 8191 
L 6.02401998 0.79385 6.01153996 0.79385 1 P 0 
L 6.01131998 0.78758002 6.01131998 0.78761998 1 P 8191 
L 6.01131998 0.78761998 6.01133002 0.78766004 1 P 8191 
L 6.01133002 0.78766004 6.01135 0.78768996 1 P 8191 
L 6.01135 0.78768996 6.01136998 0.78771998 1 P 8191 
L 6.01136998 0.78771998 6.0114 0.78773996 1 P 8191 
L 6.0114 0.78773996 6.01143996 0.78776998 1 P 8191 
L 6.01143996 0.78776998 6.01146998 0.78778002 1 P 8191 
L 6.01146998 0.78778002 6.0115 0.7878 1 P 8191 
L 6.0115 0.7878 6.01153996 0.7878 1 P 8191 
L 6.01153996 0.7878 6.02401998 0.7878 1 P 0 
L 6.0115 0.78263996 6.01146998 0.78265 1 P 8191 
L 6.01146998 0.78265 6.01143996 0.78266004 1 P 8191 
L 6.01143996 0.78266004 6.0114 0.78268996 1 P 8191 
L 6.0114 0.78268996 6.01136998 0.78271998 1 P 8191 
L 6.01136998 0.78271998 6.01135 0.78275 1 P 8191 
L 6.01135 0.78275 6.01133002 0.78278002 1 P 8191 
L 6.01133002 0.78278002 6.01131998 0.78281998 1 P 8191 
L 6.01131998 0.78281998 6.01131998 0.78286004 1 P 8191 
L 6.01131998 0.78286004 6.01131998 0.78758002 1 P 8191 
L 6.01153996 0.78263002 6.0115 0.78263996 1 P 8191 
L 6.02621004 0.78263002 6.01153996 0.78263002 1 P 0 
L 6.02431004 0.82078002 6.02678002 0.81923996 1 P 8191 
L 6.02175 0.82218002 6.02431004 0.82078002 1 P 8191 
L 6.04708002 0.80233002 6.04548002 0.80506004 1 P 8191 
L 6.04851998 0.79951004 6.04708002 0.80233002 1 P 8191 
L 6.04548002 0.80506004 6.04371998 0.8077 1 P 8191 
L 6.04293002 0.80261004 6.0444 0.8001 1 P 8191 
L 6.0444 0.8001 6.04571998 0.7975 1 P 8191 
L 6.0396 0.80738996 6.04131998 0.80505 1 P 8191 
L 6.04131998 0.80505 6.04293002 0.80261004 1 P 8191 
L 6.02703996 0.80531998 6.02703996 0.80543996 1 P 8191 
L 6.02703996 0.80543996 6.02701004 0.80553996 1 P 8191 
L 6.02701004 0.80553996 6.02698002 0.80565 1 P 8191 
L 6.02698002 0.80565 6.02693002 0.80573996 1 P 8191 
L 6.02621004 0.79901998 6.02633002 0.79901998 1 P 8191 
L 6.02633002 0.79901998 6.02643996 0.79905 1 P 8191 
L 6.02643996 0.79905 6.02655 0.79908002 1 P 8191 
L 6.02655 0.79908002 6.02663996 0.79911998 1 P 8191 
L 6.02663996 0.79911998 6.02673002 0.79918002 1 P 8191 
L 6.02673002 0.79918002 6.02681004 0.79923996 1 P 8191 
L 6.02681004 0.79923996 6.02688002 0.79931004 1 P 8191 
L 6.02688002 0.79931004 6.02693002 0.7994 1 P 8191 
L 6.02693002 0.7994 6.02698002 0.7995 1 P 8191 
L 6.02698002 0.7995 6.02701004 0.79958996 1 P 8191 
L 6.02701004 0.79958996 6.02703996 0.7997 1 P 8191 
L 6.02703996 0.7997 6.02703996 0.79981004 1 P 8191 
L 6.02703996 0.79981004 6.02703996 0.80531998 1 P 8191 
L 6.04181998 0.81023996 6.03978002 0.81266998 1 P 8191 
L 6.04371998 0.8077 6.04181998 0.81023996 1 P 8191 
L 6.03978002 0.81266998 6.0376 0.815 1 P 8191 
L 6.03773996 0.80965 6.0396 0.80738996 1 P 8191 
L 6.0376 0.815 6.03531004 0.81718996 1 P 8191 
L 6.03366998 0.81383996 6.03576004 0.8118 1 P 8191 
L 6.03576004 0.8118 6.03773996 0.80965 1 P 8191 
L 6.03531004 0.81718996 6.03288996 0.81925 1 P 8191 
L 6.03146998 0.81576004 6.03366998 0.81383996 1 P 8191 
L 6.03288996 0.81925 6.03036004 0.82118002 1 P 8191 
L 6.02916004 0.81756998 6.03146998 0.81576004 1 P 8191 
L 6.03036004 0.82118002 6.02773996 0.82295 1 P 8191 
L 6.02678002 0.81923996 6.02916004 0.81756998 1 P 8191 
L 6.02643996 0.80613002 6.02631998 0.80615 1 P 8191 
L 6.02631998 0.80615 6.02621004 0.80616004 1 P 8191 
L 6.02653996 0.80608996 6.02643996 0.80613002 1 P 8191 
L 6.0268 0.80591004 6.02671998 0.80598002 1 P 8191 
L 6.02671998 0.80598002 6.02663996 0.80605 1 P 8191 
L 6.02663996 0.80605 6.02653996 0.80608996 1 P 8191 
L 6.02693002 0.80573996 6.02688002 0.80583002 1 P 8191 
L 6.02688002 0.80583002 6.0268 0.80591004 1 P 8191 
L 6.01131998 0.7988 6.01131998 0.79883002 1 P 8191 
L 6.01131998 0.79883002 6.01133002 0.79886004 1 P 8191 
L 6.01133002 0.79886004 6.01135 0.7989 1 P 8191 
L 6.01135 0.7989 6.01136998 0.79893002 1 P 8191 
L 6.01136998 0.79893002 6.0114 0.79896004 1 P 8191 
L 6.0114 0.79896004 6.01143996 0.79898002 1 P 8191 
L 6.01143996 0.79898002 6.01146998 0.799 1 P 8191 
L 6.01146998 0.799 6.0115 0.79901998 1 P 8191 
L 6.0115 0.79901998 6.01153996 0.79901998 1 P 8191 
L 6.01153996 0.79901998 6.02621004 0.79901998 1 P 0 
L 6.00951998 0.80616004 6.00936004 0.80615 1 P 8191 
L 6.00936004 0.80615 6.0092 0.80613996 1 P 8191 
L 6.02621004 0.80616004 6.00951998 0.80616004 1 P 0 
L 6.00523996 0.8275 6.00811004 0.82698996 1 P 8191 
L 6.00723996 0.83093996 6.00408996 0.83141004 1 P 8191 
L 6.00235 0.82785 6.00523996 0.8275 1 P 8191 
L 6.00408996 0.83141004 6.00093002 0.8317 1 P 8191 
L 5.99943002 0.82805 6.00235 0.82785 1 P 8191 
L 6.00093002 0.8317 5.99775 0.83181998 1 P 8191 
L 6.00811004 0.82698996 6.01093002 0.82633002 1 P 8191 
L 6.01033996 0.8303 6.00723996 0.83093996 1 P 8191 
L 6.00501998 0.77278002 6.00483996 0.77281998 1 P 8191 
L 6.0052 0.77273996 6.00501998 0.77278002 1 P 8191 
L 6.00556004 0.77261998 6.00536998 0.77268002 1 P 8191 
L 6.00536998 0.77268002 6.0052 0.77273996 1 P 8191 
L 6.00573996 0.77255 6.00556004 0.77261998 1 P 8191 
L 6.00396004 0.77986998 6.00798996 0.77583996 1 P 8191 
L 6.00416004 0.7729 6.00288002 0.7729 1 P 8191 
L 6.00431998 0.77288996 6.00416004 0.7729 1 P 8191 
L 6.00466004 0.77286004 6.00448996 0.77286998 1 P 8191 
L 6.00448996 0.77286998 6.00431998 0.77288996 1 P 8191 
L 6.00483996 0.77281998 6.00466004 0.77286004 1 P 8191 
L 6.00018996 0.77463002 6.0002 0.775 1 P 8191 
L 6.0002 0.775 6.0002 0.81718002 1 P 0 
L 5.99916004 0.77218002 5.99938996 0.77248002 1 P 8191 
L 5.99938996 0.77248002 5.99958996 0.7728 1 P 8191 
L 5.99958996 0.7728 5.99976998 0.77315 1 P 8191 
L 5.99976998 0.77315 5.99991998 0.77353002 1 P 8191 
L 5.99991998 0.77353002 6.00005 0.7739 1 P 8191 
L 6.00005 0.7739 6.00013002 0.77426998 1 P 8191 
L 6.00013002 0.77426998 6.00018996 0.77463002 1 P 8191 
L 5.99891998 0.77191004 5.99916004 0.77218002 1 P 8191 
L 6.00366004 0.78083996 6.00368002 0.78066004 1 P 8191 
L 6.00368002 0.78066004 6.00371998 0.78048996 1 P 8191 
L 6.00363002 0.78101998 6.00366004 0.78083996 1 P 8191 
L 6.00361004 0.78141004 6.00361004 0.78121004 1 P 8191 
L 6.00361004 0.78121004 6.00363002 0.78101998 1 P 8191 
L 6.00361004 0.80023996 6.00361004 0.78141004 1 P 0 
L 6.00371998 0.78048996 6.00376998 0.78031998 1 P 8191 
L 6.00376998 0.78031998 6.00383002 0.78016004 1 P 8191 
L 6.00383002 0.78016004 6.00388002 0.78001998 1 P 8191 
L 6.00388002 0.78001998 6.00396004 0.77986998 1 P 8191 
L 6.00363002 0.80063002 6.00361004 0.80043996 1 P 8191 
L 6.00368002 0.80098996 6.00366004 0.80081998 1 P 8191 
L 6.00366004 0.80081998 6.00363002 0.80063002 1 P 8191 
L 6.00371998 0.80116998 6.00368002 0.80098996 1 P 8191 
L 6.00383002 0.80148996 6.00376998 0.80133002 1 P 8191 
L 6.00376998 0.80133002 6.00371998 0.80116998 1 P 8191 
L 6.00396004 0.80178002 6.00388002 0.80163002 1 P 8191 
L 6.00388002 0.80163002 6.00383002 0.80148996 1 P 8191 
L 6.00798996 0.80581004 6.00396004 0.80178002 1 P 8191 
L 6.00361004 0.80043996 6.00361004 0.80023996 1 P 8191 
L 5.99996998 0.8184 5.99993996 0.81848002 1 P 8191 
L 5.99993996 0.81848002 5.99991998 0.81856004 1 P 8191 
L 5.99991998 0.81856004 5.99988002 0.81863996 1 P 8191 
L 5.99988002 0.81863996 5.99985 0.81871998 1 P 8191 
L 6.00015 0.8177 6.00013002 0.81778996 1 P 8191 
L 6.00013002 0.81778996 6.00011998 0.81788002 1 P 8191 
L 6.00011998 0.81788002 6.00008996 0.81798002 1 P 8191 
L 6.00008996 0.81798002 6.00006998 0.81806004 1 P 8191 
L 6.00006998 0.81806004 6.00003996 0.81815 1 P 8191 
L 6.00003996 0.81815 6.00001998 0.81823002 1 P 8191 
L 6.00001998 0.81823002 6 0.81831998 1 P 8191 
L 6 0.81831998 5.99996998 0.8184 1 P 8191 
L 6.0002 0.81718002 6.0002 0.81726998 1 P 8191 
L 6.0002 0.81726998 6.0002 0.81735 1 P 8191 
L 6.0002 0.81735 6.00018996 0.81743996 1 P 8191 
L 6.00018996 0.81743996 6.00018002 0.81753002 1 P 8191 
L 6.00018002 0.81753002 6.00016004 0.81761998 1 P 8191 
L 6.00016004 0.81761998 6.00015 0.8177 1 P 8191 
L 6.00798996 0.77583996 6.00813002 0.77576998 1 P 8191 
L 6.00813002 0.77576998 6.00828002 0.77571004 1 P 8191 
L 6.00828002 0.77571004 6.00843996 0.77566004 1 P 8191 
L 6.00843996 0.77566004 6.0086 0.77561004 1 P 8191 
L 6.0086 0.77561004 6.00876998 0.77556998 1 P 8191 
L 6.00876998 0.77556998 6.00896004 0.77553996 1 P 8191 
L 6.00896004 0.77553996 6.00913002 0.77551004 1 P 8191 
L 6.0092 0.80613996 6.00903996 0.80611004 1 P 8191 
L 6.00816998 0.80588002 6.00798996 0.80581004 1 P 8191 
L 6.00835 0.80593996 6.00816998 0.80588002 1 P 8191 
L 6.0087 0.80603996 6.00851998 0.80598996 1 P 8191 
L 6.00851998 0.80598996 6.00835 0.80593996 1 P 8191 
L 6.00886998 0.80608002 6.0087 0.80603996 1 P 8191 
L 6.00903996 0.80611004 6.00886998 0.80608002 1 P 8191 
L 6.06893002 0.76743002 6.0689 0.76758996 1 P 8191 
L 6.0689 0.76758996 6.06886004 0.76776998 1 P 8191 
L 6.06886004 0.76776998 6.06881004 0.76793996 1 P 8191 
L 6.06881004 0.76793996 6.06876004 0.76811004 1 P 8191 
L 6.06876004 0.76811004 6.0687 0.7683 1 P 8191 
L 6.0687 0.7683 6.06863002 0.76846998 1 P 8191 
L 6.06898002 0.76693996 6.06896998 0.7671 1 P 8191 
L 6.06896998 0.7671 6.06896004 0.76726004 1 P 8191 
L 6.06896004 0.76726004 6.06893002 0.76743002 1 P 8191 
L 6.06863002 0.76846998 6.0646 0.7725 1 P 8191 
L 6.06901998 0.82218002 6.08823002 0.82218002 1 P 0 
L 6.06661004 0.82186004 6.0674 0.82203002 1 P 8191 
L 6.0674 0.82203002 6.06821004 0.82213996 1 P 8191 
L 6.06821004 0.82213996 6.06901998 0.82218002 1 P 8191 
L 6.05371998 0.78136004 6.05328002 0.7845 1 P 8191 
L 6.05398996 0.77818002 6.05371998 0.78136004 1 P 8191 
L 6.06318996 0.77285 6.06301998 0.77286004 1 P 8191 
L 6.06351998 0.77281004 6.06336004 0.77283002 1 P 8191 
L 6.06336004 0.77283002 6.06318996 0.77285 1 P 8191 
L 6.05408002 0.77498002 6.05398996 0.77818002 1 P 8191 
L 6.0636 0.80548002 6.06296004 0.80596998 1 P 8191 
L 6.06296004 0.81998996 6.0636 0.82046998 1 P 8191 
L 6.06133996 0.81821998 6.06183996 0.81886004 1 P 8191 
L 6.06183996 0.81886004 6.06236998 0.81946004 1 P 8191 
L 6.06236998 0.81946004 6.06296004 0.81998996 1 P 8191 
L 6.05996998 0.81528002 6.06021998 0.81606004 1 P 8191 
L 6.06021998 0.81606004 6.06053996 0.81681998 1 P 8191 
L 6.06053996 0.81681998 6.06091004 0.81753996 1 P 8191 
L 6.06091004 0.81753996 6.06133996 0.81821998 1 P 8191 
L 6.05968996 0.81221004 6.05966004 0.81298002 1 P 8191 
L 6.05966004 0.81298002 6.05968996 0.81375 1 P 8191 
L 6.05968996 0.81375 6.0598 0.81451998 1 P 8191 
L 6.0598 0.81451998 6.05996998 0.81528002 1 P 8191 
L 6.05996998 0.81068002 6.0598 0.81143996 1 P 8191 
L 6.0598 0.81143996 6.05968996 0.81221004 1 P 8191 
L 6.06053996 0.80913996 6.06021998 0.8099 1 P 8191 
L 6.06021998 0.8099 6.05996998 0.81068002 1 P 8191 
L 6.06091004 0.80841004 6.06053996 0.80913996 1 P 8191 
L 6.06133996 0.80773996 6.06091004 0.80841004 1 P 8191 
L 6.06183996 0.8071 6.06133996 0.80773996 1 P 8191 
L 6.06236998 0.8065 6.06183996 0.8071 1 P 8191 
L 6.06296004 0.80596998 6.06236998 0.8065 1 P 8191 
L 6.06388002 0.77273996 6.0637 0.77278002 1 P 8191 
L 6.0637 0.77278002 6.06351998 0.77281004 1 P 8191 
L 6.06406004 0.77268996 6.06388002 0.77273996 1 P 8191 
L 6.06441998 0.77258002 6.06423996 0.77263002 1 P 8191 
L 6.06423996 0.77263002 6.06406004 0.77268996 1 P 8191 
L 6.0646 0.7725 6.06441998 0.77258002 1 P 8191 
L 6.06581998 0.82161004 6.06661004 0.82186004 1 P 8191 
L 6.17858996 0.80378002 6.06901998 0.80378002 1 P 0 
L 6.06661004 0.8041 6.06581998 0.80435 1 P 8191 
L 6.0674 0.80393002 6.06661004 0.8041 1 P 8191 
L 6.06821004 0.80381998 6.0674 0.80393002 1 P 8191 
L 6.06901998 0.80378002 6.06821004 0.80381998 1 P 8191 
L 6.06428996 0.80505 6.0636 0.80548002 1 P 8191 
L 6.06503996 0.80468002 6.06428996 0.80505 1 P 8191 
L 6.06581998 0.80435 6.06503996 0.80468002 1 P 8191 
L 6.06428996 0.8209 6.06503996 0.82128002 1 P 8191 
L 6.06503996 0.82128002 6.06581998 0.82161004 1 P 8191 
L 6.0636 0.82046998 6.06428996 0.8209 1 P 8191 
L 6.10048996 0.7703 6.1 0.77093996 1 P 8191 
L 6.10103996 0.76971998 6.10048996 0.7703 1 P 8191 
L 6.10161998 0.76918002 6.10103996 0.76971998 1 P 8191 
L 6.10226998 0.7687 6.10161998 0.76918002 1 P 8191 
L 6.10296004 0.76826004 6.10226998 0.7687 1 P 8191 
L 6.09956998 0.77161998 6.0992 0.77235 1 P 8191 
L 6.1 0.77093996 6.09956998 0.77161998 1 P 8191 
L 6.09756004 0.83216998 6.09745 0.83296998 1 P 8191 
L 6.09745 0.83296998 6.09728002 0.83373996 1 P 8191 
L 6.09745 0.82978002 6.09756004 0.83058002 1 P 8191 
L 6.09756004 0.83058002 6.0976 0.83136998 1 P 8191 
L 6.0976 0.83136998 6.09756004 0.83216998 1 P 8191 
L 6.09728002 0.829 6.09745 0.82978002 1 P 8191 
L 6.09728002 0.83373996 6.09703996 0.8345 1 P 8191 
L 6.09636004 0.82678996 6.09671998 0.8275 1 P 8191 
L 6.09671998 0.8275 6.09703996 0.82823996 1 P 8191 
L 6.09703996 0.82823996 6.09728002 0.829 1 P 8191 
L 6.09431998 0.82438996 6.09491998 0.82493996 1 P 8191 
L 6.09491998 0.82493996 6.09545 0.82551004 1 P 8191 
L 6.09545 0.82551004 6.09593002 0.82613996 1 P 8191 
L 6.09593002 0.82613996 6.09636004 0.82678996 1 P 8191 
L 6.09296004 0.82346004 6.09366004 0.8239 1 P 8191 
L 6.09366004 0.8239 6.09431998 0.82438996 1 P 8191 
L 6.0914 0.82275 6.0922 0.82308002 1 P 8191 
L 6.0922 0.82308002 6.09296004 0.82346004 1 P 8191 
L 6.08901998 0.82221004 6.0898 0.82231998 1 P 8191 
L 6.0898 0.82231998 6.0906 0.8225 1 P 8191 
L 6.0906 0.8225 6.0914 0.82275 1 P 8191 
L 6.08823002 0.82218002 6.08901998 0.82221004 1 P 8191 
L 6.09835 0.77541998 6.09831998 0.77618996 1 P 8191 
L 6.09831998 0.77618996 6.09835 0.77696998 1 P 8191 
L 6.09846004 0.77466004 6.09835 0.77541998 1 P 8191 
L 6.09863002 0.77388996 6.09846004 0.77466004 1 P 8191 
L 6.0992 0.77235 6.09888002 0.77311998 1 P 8191 
L 6.09888002 0.77311998 6.09863002 0.77388996 1 P 8191 
L 6.10161998 0.78321004 6.10226998 0.78368996 1 P 8191 
L 6.10226998 0.78368996 6.10296004 0.78411998 1 P 8191 
L 6.1 0.78143996 6.10048996 0.78208002 1 P 8191 
L 6.10048996 0.78208002 6.10103996 0.78266004 1 P 8191 
L 6.10103996 0.78266004 6.10161998 0.78321004 1 P 8191 
L 6.09956998 0.78076004 6.1 0.78143996 1 P 8191 
L 6.09846004 0.77773002 6.09863002 0.7785 1 P 8191 
L 6.09863002 0.7785 6.09888002 0.77926004 1 P 8191 
L 6.09888002 0.77926004 6.0992 0.78003002 1 P 8191 
L 6.0992 0.78003002 6.09956998 0.78076004 1 P 8191 
L 6.09835 0.77696998 6.09846004 0.77773002 1 P 8191 
L 6.09703996 0.8345 6.09671998 0.83525 1 P 8191 
L 6.09491998 0.83781998 6.09431998 0.83835 1 P 8191 
L 6.09545 0.83723002 6.09491998 0.83781998 1 P 8191 
L 6.09593002 0.83661004 6.09545 0.83723002 1 P 8191 
L 6.09636004 0.83595 6.09593002 0.83661004 1 P 8191 
L 6.09671998 0.83525 6.09636004 0.83595 1 P 8191 
L 6.0922 0.83966004 6.0914 0.83998996 1 P 8191 
L 6.09296004 0.83928002 6.0922 0.83966004 1 P 8191 
L 6.09366004 0.83883996 6.09296004 0.83928002 1 P 8191 
L 6.09431998 0.83835 6.09366004 0.83883996 1 P 8191 
L 6.0898 0.84041998 6.08901998 0.84053996 1 P 8191 
L 6.0906 0.84025 6.0898 0.84041998 1 P 8191 
L 6.0914 0.83998996 6.0906 0.84025 1 P 8191 
L 6.08901998 0.84053996 6.08823002 0.84056998 1 P 8191 
L 5.96533996 0.74983002 5.96526998 0.74991004 1 P 8191 
L 5.96526998 0.74991004 5.9652 0.75001004 1 P 8191 
L 5.9652 0.75001004 5.96516004 0.7501 1 P 8191 
L 5.96516004 0.7501 5.96511998 0.7502 1 P 8191 
L 5.96511998 0.7502 5.9651 0.75031004 1 P 8191 
L 5.9651 0.75031004 5.96508996 0.75041998 1 P 8191 
L 5.96508996 0.75041998 5.96508996 0.76461998 1 P 0 
L 5.96551004 0.7497 5.96541998 0.74976998 1 P 8191 
L 5.96541998 0.74976998 5.96533996 0.74983002 1 P 8191 
L 5.97943996 0.75266004 5.99891998 0.77191004 1 P 0 
L 5.97731998 0.75526004 5.9774 0.75508996 1 P 8191 
L 5.9774 0.75508996 5.97748996 0.75491004 1 P 8191 
L 5.97731998 0.76096004 5.97731998 0.75526004 1 P 8191 
L 5.97758002 0.75473996 5.97768002 0.75458002 1 P 8191 
L 5.97768002 0.75458002 5.97776998 0.75443002 1 P 8191 
L 5.97748996 0.75491004 5.97758002 0.75473996 1 P 8191 
L 5.97776998 0.75443002 5.97786998 0.75428996 1 P 8191 
L 5.97798002 0.75415 5.97808002 0.75401998 1 P 8191 
L 5.97786998 0.75428996 5.97798002 0.75415 1 P 8191 
L 5.9782 0.7539 5.97943996 0.75266004 1 P 8191 
L 5.97808002 0.75401998 5.9782 0.7539 1 P 8191 
L 5.96571004 0.74961998 5.9656 0.74966004 1 P 8191 
L 5.9656 0.74966004 5.96551004 0.7497 1 P 8191 
L 5.96593002 0.74958996 5.96581004 0.7496 1 P 8191 
L 5.96581004 0.7496 5.96571004 0.74961998 1 P 8191 
L 5.97998996 0.74958996 5.96593002 0.74958996 1 P 0 
L 5.98011004 0.74958002 5.97998996 0.74958996 1 P 8191 
L 5.98041998 0.74948996 5.98031998 0.74953002 1 P 8191 
L 5.98031998 0.74953002 5.98021998 0.74956004 1 P 8191 
L 5.98021998 0.74956004 5.98011004 0.74958002 1 P 8191 
L 5.98058996 0.74936998 5.98051004 0.74943002 1 P 8191 
L 5.98051004 0.74943002 5.98041998 0.74948996 1 P 8191 
L 5.99218002 0.75131004 5.99223996 0.7514 1 P 8191 
L 5.99223996 0.7514 5.99231004 0.75146998 1 P 8191 
L 5.99231004 0.75146998 5.99238996 0.75153996 1 P 8191 
L 5.99238996 0.75153996 5.99248002 0.75158996 1 P 8191 
L 5.99248002 0.75158996 5.99256998 0.75163996 1 P 8191 
L 5.99256998 0.75163996 5.99266998 0.75166004 1 P 8191 
L 5.99266998 0.75166004 5.99278002 0.75168996 1 P 8191 
L 5.99278002 0.75168996 5.99291004 0.7517 1 P 8191 
L 5.99291004 0.7517 6.00158002 0.7517 1 P 0 
L 5.99206998 0.7509 5.99208002 0.75101998 1 P 8191 
L 5.99208002 0.75101998 5.9921 0.75111998 1 P 8191 
L 5.9921 0.75111998 5.99213996 0.75121998 1 P 8191 
L 5.99213996 0.75121998 5.99218002 0.75131004 1 P 8191 
L 5.99206998 0.76138002 5.98436004 0.75373996 1 P 0 
L 6.02098996 0.7513 6.02101998 0.75133996 1 P 8191 
L 6.02101998 0.75133996 6.02105 0.75136004 1 P 8191 
L 6.02105 0.75136004 6.02108002 0.75138002 1 P 8191 
L 6.02108002 0.75138002 6.02111998 0.75138002 1 P 8191 
L 6.02111998 0.75138002 6.02115 0.75138996 1 P 8191 
L 6.02115 0.75138996 6.0261 0.75138996 1 P 8191 
L 6.02093002 0.75116998 6.02093996 0.75121004 1 P 8191 
L 6.02093996 0.75121004 6.02095 0.75123996 1 P 8191 
L 6.02095 0.75123996 6.02096004 0.75126998 1 P 8191 
L 6.02096004 0.75126998 6.02098996 0.7513 1 P 8191 
L 6.03451004 0.75196004 6.03853996 0.75608002 1 P 8191 
L 6.0261 0.75138996 6.02613996 0.75138002 1 P 8191 
L 6.02613996 0.75138002 6.02618996 0.75138002 1 P 8191 
L 6.02618996 0.75138002 6.02623002 0.75136998 1 P 8191 
L 6.02623002 0.75136998 6.02626998 0.75135 1 P 8191 
L 6.02626998 0.75135 6.0263 0.75133002 1 P 8191 
L 6.0263 0.75133002 6.02633996 0.7513 1 P 8191 
L 6.02638996 0.75125 6.0264 0.75121998 1 P 8191 
L 6.02633996 0.7513 6.02636004 0.75126998 1 P 8191 
L 6.02636004 0.75126998 6.02638996 0.75125 1 P 8191 
L 6.05093002 0.74958996 6.05093002 0.76541004 1 P 0 
L 6.06123002 0.74958996 6.05093002 0.74958996 1 P 0 
L 6.00191998 0.75163996 6.00201004 0.75158996 1 P 8191 
L 6.00208996 0.75153996 6.00216998 0.75146998 1 P 8191 
L 6.00216998 0.75146998 6.00223996 0.7514 1 P 8191 
L 6.00223996 0.7514 6.0023 0.75131004 1 P 8191 
L 6.00201004 0.75158996 6.00208996 0.75153996 1 P 8191 
L 6.0024 0.75101998 6.00241004 0.7509 1 P 8191 
L 6.0023 0.75131004 6.00235 0.75121998 1 P 8191 
L 6.00235 0.75121998 6.00238002 0.75111998 1 P 8191 
L 6.00238002 0.75111998 6.0024 0.75101998 1 P 8191 
L 6.00158002 0.7517 6.0017 0.75168996 1 P 8191 
L 6.0017 0.75168996 6.00181004 0.75166004 1 P 8191 
L 6.00181004 0.75166004 6.00191998 0.75163996 1 P 8191 
L 6.06123002 0.76541004 6.06123002 0.74958996 1 P 0 
L 5.94511004 0.76151004 5.9445 0.7643 1 P 8191 
L 5.94586998 0.75876004 5.94511004 0.76151004 1 P 8191 
L 5.94676004 0.75606004 5.94586998 0.75876004 1 P 8191 
L 5.94151998 0.76371998 5.9422 0.76073996 1 P 8191 
L 5.9422 0.76073996 5.94303996 0.75781998 1 P 8191 
L 5.94373002 0.76996998 5.94356998 0.77286004 1 P 8191 
L 5.94403996 0.76711004 5.94373002 0.76996998 1 P 8191 
L 5.9445 0.7643 5.94403996 0.76711004 1 P 8191 
L 5.94043996 0.77286004 5.94063996 0.76976998 1 P 8191 
L 5.94063996 0.76976998 5.941 0.76673002 1 P 8191 
L 5.941 0.76673002 5.94151998 0.76371998 1 P 8191 
L 5.9574 0.76713996 5.95738996 0.76693996 1 P 8191 
L 5.95743996 0.76751004 5.95741004 0.76733002 1 P 8191 
L 5.95741004 0.76733002 5.9574 0.76713996 1 P 8191 
L 5.95746998 0.76768996 5.95743996 0.76751004 1 P 8191 
L 5.95755 0.76803002 5.9575 0.76786004 1 P 8191 
L 5.9575 0.76786004 5.95746998 0.76768996 1 P 8191 
L 5.95766998 0.76833996 5.9576 0.76818002 1 P 8191 
L 5.9576 0.76818002 5.95755 0.76803002 1 P 8191 
L 5.95773996 0.76846998 5.95766998 0.76833996 1 P 8191 
L 5.96176004 0.7725 5.95773996 0.76846998 1 P 8191 
L 5.94608002 0.7755 5.94618996 0.7755 1 P 8191 
L 5.94618996 0.7755 5.94628002 0.77551998 1 P 8191 
L 5.94628002 0.77551998 5.94638996 0.77556004 1 P 8191 
L 5.94638996 0.77556004 5.94648002 0.7756 1 P 8191 
L 5.94648002 0.7756 5.94656004 0.77566004 1 P 8191 
L 5.94656004 0.77566004 5.94663996 0.77573002 1 P 8191 
L 5.94663996 0.77573002 5.9467 0.77581004 1 P 8191 
L 5.9467 0.77581004 5.94676004 0.7759 1 P 8191 
L 5.94676004 0.7759 5.9468 0.77598996 1 P 8191 
L 5.9468 0.77598996 5.94683002 0.77608996 1 P 8191 
L 5.94683002 0.77608996 5.94685 0.7762 1 P 8191 
L 5.94685 0.7762 5.94686004 0.77633002 1 P 8191 
L 5.94686004 0.77633002 5.94686004 0.79791998 1 P 0 
L 5.93918002 0.7761 5.93921998 0.776 1 P 8191 
L 5.93921998 0.776 5.93926004 0.7759 1 P 8191 
L 5.93926004 0.7759 5.93931998 0.77581998 1 P 8191 
L 5.93931998 0.77581998 5.9394 0.77573996 1 P 8191 
L 5.93915 0.77633002 5.93916004 0.77621004 1 P 8191 
L 5.93916004 0.77621004 5.93918002 0.7761 1 P 8191 
L 5.93915 0.79791998 5.93915 0.77633002 1 P 0 
L 5.9394 0.77573996 5.93948002 0.77566004 1 P 8191 
L 5.93948002 0.77566004 5.93956004 0.77561004 1 P 8191 
L 5.93956004 0.77561004 5.93966004 0.77556004 1 P 8191 
L 5.93966004 0.77556004 5.93976004 0.77551998 1 P 8191 
L 5.93976004 0.77551998 5.93986998 0.7755 1 P 8191 
L 5.93986998 0.7755 5.93998002 0.7755 1 P 8191 
L 5.93998002 0.7755 5.94608002 0.7755 1 P 0 
L 5.94356998 0.77286004 5.94043996 0.77286004 1 P 8191 
L 5.9471 0.79848996 5.94718002 0.79855 1 P 8191 
L 5.94718002 0.79855 5.94726004 0.79861004 1 P 8191 
L 5.94726004 0.79861004 5.94736004 0.79865 1 P 8191 
L 5.94736004 0.79865 5.94746004 0.79868002 1 P 8191 
L 5.94746004 0.79868002 5.94756998 0.7987 1 P 8191 
L 5.94756998 0.7987 5.94768996 0.79871004 1 P 8191 
L 5.94768996 0.79871004 5.95391998 0.79871004 1 P 0 
L 5.94686004 0.79791998 5.94688002 0.79803002 1 P 8191 
L 5.94688002 0.79803002 5.94688996 0.79813996 1 P 8191 
L 5.94688996 0.79813996 5.94691998 0.79823002 1 P 8191 
L 5.94691998 0.79823002 5.94696998 0.79833002 1 P 8191 
L 5.94696998 0.79833002 5.94703996 0.79841004 1 P 8191 
L 5.94703996 0.79841004 5.9471 0.79848996 1 P 8191 
L 5.93848002 0.7987 5.93858996 0.79868002 1 P 8191 
L 5.93858996 0.79868002 5.93868002 0.79865 1 P 8191 
L 5.93868002 0.79865 5.93878002 0.79861004 1 P 8191 
L 5.93878002 0.79861004 5.93886004 0.79855 1 P 8191 
L 5.93886004 0.79855 5.93893002 0.79848996 1 P 8191 
L 5.93893002 0.79848996 5.939 0.79841998 1 P 8191 
L 5.939 0.79841998 5.93905 0.79833996 1 P 8191 
L 5.93905 0.79833996 5.93908996 0.79825 1 P 8191 
L 5.93913996 0.79803996 5.93915 0.79791998 1 P 8191 
L 5.93908996 0.79825 5.93911998 0.79813996 1 P 8191 
L 5.93911998 0.79813996 5.93913996 0.79803996 1 P 8191 
L 5.93836004 0.79871004 5.93848002 0.7987 1 P 8191 
L 5.95663996 0.77611998 5.95665 0.77603002 1 P 8191 
L 5.95665 0.77603002 5.95668002 0.77593996 1 P 8191 
L 5.95661998 0.77633002 5.95663002 0.77621998 1 P 8191 
L 5.95663002 0.77621998 5.95663996 0.77611998 1 P 8191 
L 5.95661998 0.80531998 5.95661998 0.77633002 1 P 0 
L 5.95676004 0.77578996 5.9568 0.77573002 1 P 8191 
L 5.9568 0.77573002 5.95686004 0.77566998 1 P 8191 
L 5.95686004 0.77566998 5.95691998 0.77561998 1 P 8191 
L 5.95691998 0.77561998 5.957 0.77558002 1 P 8191 
L 5.95668002 0.77593996 5.95671998 0.77586004 1 P 8191 
L 5.95671998 0.77586004 5.95676004 0.77578996 1 P 8191 
L 5.957 0.77558002 5.95708002 0.77555 1 P 8191 
L 5.95708002 0.77555 5.95716004 0.77553002 1 P 8191 
L 5.95716004 0.77553002 5.95725 0.7755 1 P 8191 
L 5.95725 0.7755 5.95735 0.7755 1 P 8191 
L 5.95735 0.7755 5.95745 0.7755 1 P 8191 
L 5.95745 0.7755 5.9635 0.7755 1 P 0 
L 5.95663996 0.80553002 5.95663002 0.80543002 1 P 8191 
L 5.95663002 0.80543002 5.95661998 0.80531998 1 P 8191 
L 5.95668002 0.8057 5.95665 0.80561998 1 P 8191 
L 5.95665 0.80561998 5.95663996 0.80553002 1 P 8191 
L 5.95468002 0.80565 5.95463996 0.80573996 1 P 8191 
L 5.95475 0.80531998 5.95473996 0.80543996 1 P 8191 
L 5.95473996 0.80543996 5.95471998 0.80553996 1 P 8191 
L 5.95471998 0.80553996 5.95468002 0.80565 1 P 8191 
L 5.95391998 0.79871004 5.95403002 0.79871998 1 P 8191 
L 5.95403002 0.79871998 5.95413996 0.79873996 1 P 8191 
L 5.95413996 0.79873996 5.95423996 0.79878002 1 P 8191 
L 5.95423996 0.79878002 5.95433002 0.79881998 1 P 8191 
L 5.95433002 0.79881998 5.95443002 0.79888002 1 P 8191 
L 5.95443002 0.79888002 5.95451004 0.79895 1 P 8191 
L 5.95451004 0.79895 5.95456998 0.79903002 1 P 8191 
L 5.95456998 0.79903002 5.95463996 0.79911998 1 P 8191 
L 5.95463996 0.79911998 5.95468002 0.79921998 1 P 8191 
L 5.95468002 0.79921998 5.95471998 0.79931998 1 P 8191 
L 5.95471998 0.79931998 5.95473996 0.79943002 1 P 8191 
L 5.95473996 0.79943002 5.95475 0.79953996 1 P 8191 
L 5.95475 0.79953996 5.95475 0.80531998 1 P 8191 
L 5.95991998 0.81785 5.95758002 0.8157 1 P 8191 
L 5.95771004 0.81073002 5.95973996 0.81281998 1 P 8191 
L 5.95576998 0.8085 5.95771004 0.81073002 1 P 8191 
L 5.95725 0.80613996 5.95716004 0.80611998 1 P 8191 
L 5.95745 0.80616004 5.95735 0.80615 1 P 8191 
L 5.95735 0.80615 5.95725 0.80613996 1 P 8191 
L 5.9635 0.80616004 5.95745 0.80616004 1 P 0 
L 5.95671998 0.80578002 5.95668002 0.8057 1 P 8191 
L 5.957 0.80606004 5.95691998 0.80601998 1 P 8191 
L 5.95691998 0.80601998 5.95686004 0.80598002 1 P 8191 
L 5.95686004 0.80598002 5.9568 0.80591998 1 P 8191 
L 5.9568 0.80591998 5.95676004 0.80586004 1 P 8191 
L 5.95676004 0.80586004 5.95671998 0.80578002 1 P 8191 
L 5.95716004 0.80611998 5.95708002 0.8061 1 P 8191 
L 5.95708002 0.8061 5.957 0.80606004 1 P 8191 
L 5.95758002 0.8157 5.95536998 0.81341998 1 P 8191 
L 5.95536998 0.81341998 5.95328996 0.81103002 1 P 8191 
L 5.95413996 0.80613002 5.95403002 0.80615 1 P 8191 
L 5.95403002 0.80615 5.95391998 0.80616004 1 P 8191 
L 5.95443002 0.80598002 5.95433002 0.80605 1 P 8191 
L 5.95433002 0.80605 5.95423996 0.80608996 1 P 8191 
L 5.95423996 0.80608996 5.95413996 0.80613002 1 P 8191 
L 5.95463996 0.80573996 5.95456998 0.80583002 1 P 8191 
L 5.95456998 0.80583002 5.95451004 0.80591004 1 P 8191 
L 5.95451004 0.80591004 5.95443002 0.80598002 1 P 8191 
L 5.95133996 0.8085 5.95576998 0.8085 1 P 8191 
L 5.95328996 0.81103002 5.95133996 0.8085 1 P 8191 
L 5.93131998 0.80553002 5.93131998 0.80543002 1 P 8191 
L 5.93131998 0.80543002 5.93131004 0.80531998 1 P 8191 
L 5.93136998 0.8057 5.93135 0.80561998 1 P 8191 
L 5.93135 0.80561998 5.93131998 0.80553002 1 P 8191 
L 5.93136998 0.79921998 5.93141998 0.79911998 1 P 8191 
L 5.93141998 0.79911998 5.93148002 0.79903002 1 P 8191 
L 5.93148002 0.79903002 5.93155 0.79895 1 P 8191 
L 5.93155 0.79895 5.93163002 0.79888002 1 P 8191 
L 5.93131004 0.79953996 5.93131998 0.79943002 1 P 8191 
L 5.93131998 0.79943002 5.93133996 0.79931998 1 P 8191 
L 5.93133996 0.79931998 5.93136998 0.79921998 1 P 8191 
L 5.93131004 0.80531998 5.93131004 0.79953996 1 P 8191 
L 5.93163002 0.79888002 5.93171998 0.79881998 1 P 8191 
L 5.93171998 0.79881998 5.93181998 0.79878002 1 P 8191 
L 5.93181998 0.79878002 5.93191998 0.79873996 1 P 8191 
L 5.93191998 0.79873996 5.93203002 0.79871998 1 P 8191 
L 5.93203002 0.79871998 5.93213996 0.79871004 1 P 8191 
L 5.93213996 0.79871004 5.93836004 0.79871004 1 P 0 
L 5.93193996 0.80613996 5.93185 0.80611998 1 P 8191 
L 5.93213996 0.80616004 5.93203996 0.80615 1 P 8191 
L 5.93203996 0.80615 5.93193996 0.80613996 1 P 8191 
L 5.95391998 0.80616004 5.93213996 0.80616004 1 P 0 
L 5.9314 0.80578002 5.93136998 0.8057 1 P 8191 
L 5.93161004 0.80601998 5.93155 0.80598002 1 P 8191 
L 5.93155 0.80598002 5.93148996 0.80591998 1 P 8191 
L 5.93148996 0.80591998 5.93143996 0.80586004 1 P 8191 
L 5.93143996 0.80586004 5.9314 0.80578002 1 P 8191 
L 5.93168002 0.80606004 5.93161004 0.80601998 1 P 8191 
L 5.93185 0.80611998 5.93176004 0.8061 1 P 8191 
L 5.93176004 0.8061 5.93168002 0.80606004 1 P 8191 
L 5.949 0.75078996 5.94781998 0.7534 1 P 8191 
L 5.94781998 0.7534 5.94676004 0.75606004 1 P 8191 
L 5.94303996 0.75781998 5.94403996 0.75493996 1 P 8191 
L 5.94403996 0.75493996 5.9452 0.75211004 1 P 8191 
L 5.9452 0.75211004 5.9465 0.74933996 1 P 8191 
L 5.97076004 0.69673002 5.97083996 0.69658996 1 P 8191 
L 5.97063002 0.69703002 5.97068002 0.69686998 1 P 8191 
L 5.97068002 0.69686998 5.97076004 0.69673002 1 P 8191 
L 5.97058996 0.69736004 5.9706 0.69718996 1 P 8191 
L 5.9706 0.69718996 5.97063002 0.69703002 1 P 8191 
L 5.97058996 0.70921998 5.97058996 0.69736004 1 P 0 
L 5.97083996 0.69658996 5.97096004 0.69646004 1 P 8191 
L 5.97096004 0.69646004 5.97108002 0.69636004 1 P 8191 
L 5.97108002 0.69636004 5.97121998 0.69626004 1 P 8191 
L 5.97121998 0.69626004 5.97136004 0.69618996 1 P 8191 
L 5.97136004 0.69618996 5.97151998 0.69613996 1 P 8191 
L 5.97151998 0.69613996 5.97168002 0.6961 1 P 8191 
L 5.97168002 0.6961 5.97185 0.6961 1 P 8191 
L 5.97185 0.6961 5.98508002 0.6961 1 P 0 
L 5.96595 0.71091998 5.96616004 0.71113996 1 P 8191 
L 5.96616004 0.71113996 5.96638996 0.71133996 1 P 8191 
L 5.96638996 0.71133996 5.96663996 0.7115 1 P 8191 
L 5.96663996 0.7115 5.96691998 0.71163996 1 P 8191 
L 5.96691998 0.71163996 5.9672 0.71173996 1 P 8191 
L 5.96531998 0.70921998 5.96533996 0.70953002 1 P 8191 
L 5.96533996 0.70953002 5.9654 0.70981998 1 P 8191 
L 5.9654 0.70981998 5.96548002 0.71011004 1 P 8191 
L 5.96548002 0.71011004 5.9656 0.71038996 1 P 8191 
L 5.9656 0.71038996 5.96576004 0.71066004 1 P 8191 
L 5.96576004 0.71066004 5.96595 0.71091998 1 P 8191 
L 5.96776004 0.72951998 5.96541004 0.73116004 1 P 8191 
L 5.96436004 0.72861998 5.96691004 0.7269 1 P 8191 
L 5.96691004 0.7269 5.96953002 0.72533996 1 P 8191 
L 5.96541004 0.73116004 5.96313996 0.73293996 1 P 8191 
L 5.9619 0.73046004 5.96436004 0.72861998 1 P 8191 
L 5.96313996 0.73293996 5.96096998 0.73481998 1 P 8191 
L 5.97015 0.71066004 5.9703 0.71038996 1 P 8191 
L 5.97043002 0.71011004 5.97051004 0.70981998 1 P 8191 
L 5.97051004 0.70981998 5.97056004 0.70953002 1 P 8191 
L 5.9703 0.71038996 5.97043002 0.71011004 1 P 8191 
L 5.97056004 0.70953002 5.97058996 0.70921998 1 P 8191 
L 5.9675 0.71181998 5.9678 0.71185 1 P 8191 
L 5.9678 0.71185 5.96811004 0.71185 1 P 8191 
L 5.96811004 0.71185 5.9684 0.71181998 1 P 8191 
L 5.9684 0.71181998 5.9687 0.71173996 1 P 8191 
L 5.9687 0.71173996 5.969 0.71163996 1 P 8191 
L 5.969 0.71163996 5.96926998 0.7115 1 P 8191 
L 5.96926998 0.7115 5.96951998 0.71133996 1 P 8191 
L 5.96951998 0.71133996 5.96976004 0.71113996 1 P 8191 
L 5.96976004 0.71113996 5.96996004 0.71091998 1 P 8191 
L 5.96996004 0.71091998 5.97015 0.71066004 1 P 8191 
L 5.9672 0.71173996 5.9675 0.71181998 1 P 8191 
L 5.98333002 0.72253002 5.9806 0.72333996 1 P 8191 
L 5.98076004 0.72056998 5.98371004 0.71976004 1 P 8191 
L 5.9806 0.72333996 5.97791998 0.7243 1 P 8191 
L 5.97786998 0.72153002 5.98076004 0.72056998 1 P 8191 
L 5.97791998 0.7243 5.97528002 0.72538996 1 P 8191 
L 5.97503002 0.72265 5.97786998 0.72153002 1 P 8191 
L 5.97271004 0.72663002 5.9702 0.72801998 1 P 8191 
L 5.97528002 0.72538996 5.97271004 0.72663002 1 P 8191 
L 5.97225 0.72391004 5.97503002 0.72265 1 P 8191 
L 5.9702 0.72801998 5.96776004 0.72951998 1 P 8191 
L 5.96953002 0.72533996 5.97225 0.72391004 1 P 8191 
L 5.96523002 0.70223996 5.96528002 0.70238996 1 P 8191 
L 5.96528002 0.70238996 5.96531004 0.70255 1 P 8191 
L 5.96531004 0.70255 5.96531998 0.70273002 1 P 8191 
L 5.96531998 0.70273002 5.96531998 0.70921998 1 P 0 
L 5.96438996 0.7015 5.96453996 0.70156004 1 P 8191 
L 5.96453996 0.70156004 5.96468996 0.70163002 1 P 8191 
L 5.96468996 0.70163002 5.96483002 0.70171998 1 P 8191 
L 5.96483002 0.70171998 5.96496004 0.70183002 1 P 8191 
L 5.96496004 0.70183002 5.96506004 0.70195 1 P 8191 
L 5.96506004 0.70195 5.96516004 0.7021 1 P 8191 
L 5.96516004 0.7021 5.96523002 0.70223996 1 P 8191 
L 5.96406004 0.70146004 5.96423002 0.70146998 1 P 8191 
L 5.96423002 0.70146998 5.96438996 0.7015 1 P 8191 
L 5.96096998 0.73481998 5.95891004 0.73681004 1 P 8191 
L 5.95955 0.73243002 5.9619 0.73046004 1 P 8191 
L 5.96176004 0.74253996 5.96191004 0.74246998 1 P 8191 
L 5.96191004 0.74246998 5.96205 0.74241004 1 P 8191 
L 5.96205 0.74241004 5.96221004 0.74235 1 P 8191 
L 5.96238002 0.7423 5.96255 0.74226004 1 P 8191 
L 5.96221004 0.74235 5.96238002 0.7423 1 P 8191 
L 5.96255 0.74226004 5.96273002 0.74223996 1 P 8191 
L 5.96273002 0.74223996 5.96291004 0.74221998 1 P 8191 
L 5.96291004 0.74221998 5.9631 0.7422 1 P 8191 
L 5.9631 0.7422 5.9633 0.74218996 1 P 8191 
L 5.9633 0.74218996 5.97998996 0.74218996 1 P 0 
L 5.98076004 0.7427 5.9808 0.7428 1 P 8191 
L 5.9808 0.7428 5.98081004 0.74291004 1 P 8191 
L 5.98081004 0.74291004 5.98081998 0.74301998 1 P 8191 
L 5.98081998 0.74301998 5.98081998 0.74881004 1 P 8191 
L 5.97998996 0.74218996 5.98011004 0.7422 1 P 8191 
L 5.98011004 0.7422 5.98021004 0.74221998 1 P 8191 
L 5.98021004 0.74221998 5.98031998 0.74226004 1 P 8191 
L 5.98031998 0.74226004 5.98041004 0.7423 1 P 8191 
L 5.98041004 0.7423 5.9805 0.74236004 1 P 8191 
L 5.9805 0.74236004 5.98058002 0.74243002 1 P 8191 
L 5.98058002 0.74243002 5.98065 0.74251004 1 P 8191 
L 5.98065 0.74251004 5.98071004 0.7426 1 P 8191 
L 5.98071004 0.7426 5.98076004 0.7427 1 P 8191 
L 5.98065 0.7493 5.98058996 0.74936998 1 P 8191 
L 5.98081998 0.74881004 5.98081004 0.74891998 1 P 8191 
L 5.98081004 0.74891998 5.9808 0.74901998 1 P 8191 
L 5.9808 0.74901998 5.98076004 0.74911004 1 P 8191 
L 5.98076004 0.74911004 5.98071004 0.74921004 1 P 8191 
L 5.98071004 0.74921004 5.98065 0.7493 1 P 8191 
L 5.98896998 0.69736004 5.98898996 0.69718996 1 P 8191 
L 5.98898996 0.69718996 5.98901998 0.69703002 1 P 8191 
L 5.98896998 0.70528996 5.98896998 0.69736004 1 P 0 
L 5.98915 0.69673002 5.98923996 0.69658996 1 P 8191 
L 5.98923996 0.69658996 5.98933996 0.69646004 1 P 8191 
L 5.98901998 0.69703002 5.98906998 0.69686998 1 P 8191 
L 5.98906998 0.69686998 5.98915 0.69673002 1 P 8191 
L 5.98933996 0.69646004 5.98946998 0.69636004 1 P 8191 
L 5.98946998 0.69636004 5.9896 0.69626004 1 P 8191 
L 5.9896 0.69626004 5.98976004 0.69618996 1 P 8191 
L 5.98976004 0.69618996 5.98991004 0.69613996 1 P 8191 
L 5.98991004 0.69613996 5.99006998 0.6961 1 P 8191 
L 5.99006998 0.6961 5.99023996 0.6961 1 P 8191 
L 5.99023996 0.6961 6.0166 0.6961 1 P 0 
L 5.98598002 0.69646004 5.98608002 0.69658996 1 P 8191 
L 5.98608002 0.69658996 5.98616998 0.69673002 1 P 8191 
L 5.98616998 0.69673002 5.98625 0.69686998 1 P 8191 
L 5.98625 0.69686998 5.9863 0.69703002 1 P 8191 
L 5.9863 0.69703002 5.98633002 0.69718996 1 P 8191 
L 5.98633002 0.69718996 5.98635 0.69736004 1 P 8191 
L 5.98635 0.69736004 5.98635 0.70528996 1 P 0 
L 5.98508002 0.6961 5.98525 0.6961 1 P 8191 
L 5.98525 0.6961 5.98541004 0.69613996 1 P 8191 
L 5.98541004 0.69613996 5.98556004 0.69618996 1 P 8191 
L 5.98556004 0.69618996 5.98571004 0.69626004 1 P 8191 
L 5.98571004 0.69626004 5.98585 0.69636004 1 P 8191 
L 5.98585 0.69636004 5.98598002 0.69646004 1 P 8191 
L 5.99586004 0.71816004 5.99896004 0.71816998 1 P 8191 
L 5.99278002 0.71831004 5.99586004 0.71816004 1 P 8191 
L 5.98973002 0.71863002 5.99278002 0.71831004 1 P 8191 
L 5.9875 0.70658002 5.98766004 0.7066 1 P 8191 
L 5.98766004 0.7066 5.98781998 0.70658002 1 P 8191 
L 5.98781998 0.70658002 5.98796998 0.70655 1 P 8191 
L 5.98796998 0.70655 5.98811998 0.70648996 1 P 8191 
L 5.98811998 0.70648996 5.98828002 0.7064 1 P 8191 
L 5.98828002 0.7064 5.98843996 0.70628996 1 P 8191 
L 5.98843996 0.70628996 5.98856998 0.70616998 1 P 8191 
L 5.98856998 0.70616998 5.98868996 0.70601998 1 P 8191 
L 5.9867 0.71911998 5.98973002 0.71863002 1 P 8191 
L 5.98663002 0.70601998 5.98675 0.70616998 1 P 8191 
L 5.98675 0.70616998 5.98688002 0.70628996 1 P 8191 
L 5.98688002 0.70628996 5.98703996 0.7064 1 P 8191 
L 5.98703996 0.7064 5.9872 0.70648996 1 P 8191 
L 5.9872 0.70648996 5.98735 0.70655 1 P 8191 
L 5.98735 0.70655 5.9875 0.70658002 1 P 8191 
L 5.98371004 0.71976004 5.9867 0.71911998 1 P 8191 
L 5.99751998 0.72071004 5.99463002 0.72078002 1 P 8191 
L 5.99463002 0.72078002 5.99176004 0.72098002 1 P 8191 
L 5.99176004 0.72098002 5.98891998 0.72135 1 P 8191 
L 5.98891998 0.72135 5.98611004 0.72186004 1 P 8191 
L 5.98611004 0.72186004 5.98333002 0.72253002 1 P 8191 
L 5.98868996 0.70601998 5.9888 0.70586998 1 P 8191 
L 5.98896004 0.70543002 5.98896998 0.70528996 1 P 8191 
L 5.98888002 0.70571998 5.98893002 0.70558002 1 P 8191 
L 5.98893002 0.70558002 5.98896004 0.70543002 1 P 8191 
L 5.9888 0.70586998 5.98888002 0.70571998 1 P 8191 
L 5.98635 0.70528996 5.98636004 0.70543002 1 P 8191 
L 5.98636004 0.70543002 5.98638996 0.70558002 1 P 8191 
L 5.98638996 0.70558002 5.98643996 0.70571998 1 P 8191 
L 5.98643996 0.70571998 5.98651998 0.70586998 1 P 8191 
L 5.98651998 0.70586998 5.98663002 0.70601998 1 P 8191 
L 5.99201004 0.7427 5.99203996 0.7428 1 P 8191 
L 5.99203996 0.7428 5.99206004 0.7429 1 P 8191 
L 5.99206004 0.7429 5.99206998 0.74301998 1 P 8191 
L 5.99206998 0.74301998 5.99206998 0.7509 1 P 0 
L 5.99128002 0.74223002 5.9914 0.74225 1 P 8191 
L 5.9914 0.74225 5.99151004 0.74226004 1 P 8191 
L 5.99151004 0.74226004 5.9916 0.7423 1 P 8191 
L 5.9916 0.7423 5.99168996 0.74233996 1 P 8191 
L 5.99168996 0.74233996 5.99178002 0.74238996 1 P 8191 
L 5.99178002 0.74238996 5.99185 0.74246004 1 P 8191 
L 5.99185 0.74246004 5.99191998 0.74253002 1 P 8191 
L 5.99191998 0.74253002 5.99196004 0.74261004 1 P 8191 
L 5.99196004 0.74261004 5.99201004 0.7427 1 P 8191 
L 5.9846 0.74246004 5.98468002 0.74238996 1 P 8191 
L 5.98476004 0.74233996 5.98486004 0.7423 1 P 8191 
L 5.98486004 0.7423 5.98496004 0.74226004 1 P 8191 
L 5.98468002 0.74238996 5.98476004 0.74233996 1 P 8191 
L 5.98496004 0.74226004 5.98508002 0.74225 1 P 8191 
L 5.98508002 0.74225 5.9852 0.74223002 1 P 8191 
L 5.9852 0.74223002 5.99128002 0.74223002 1 P 0 
L 5.98436004 0.75373996 5.98436004 0.74301998 1 P 0 
L 5.98436004 0.74301998 5.98436998 0.74291004 1 P 8191 
L 5.98436998 0.74291004 5.9844 0.74281004 1 P 8191 
L 5.9844 0.74281004 5.98443002 0.74271004 1 P 8191 
L 5.98448002 0.74261998 5.98453002 0.74253996 1 P 8191 
L 5.98453002 0.74253996 5.9846 0.74246004 1 P 8191 
L 5.98443002 0.74271004 5.98448002 0.74261998 1 P 8191 
L 6.0176 0.69658002 6.0177 0.69673002 1 P 8191 
L 6.0177 0.69673002 6.01776998 0.69686998 1 P 8191 
L 6.01776998 0.69686998 6.01781998 0.69701998 1 P 8191 
L 6.01781998 0.69701998 6.01785 0.69718996 1 P 8191 
L 6.01785 0.69718996 6.01786998 0.69735 1 P 8191 
L 6.01786998 0.69735 6.01786998 0.71048002 1 P 0 
L 6.0166 0.6961 6.01676998 0.6961 1 P 8191 
L 6.01676998 0.6961 6.01693002 0.69613996 1 P 8191 
L 6.01693002 0.69613996 6.01708002 0.69618996 1 P 8191 
L 6.01708002 0.69618996 6.01723996 0.69626004 1 P 8191 
L 6.01723996 0.69626004 6.01736998 0.69636004 1 P 8191 
L 6.01736998 0.69636004 6.0175 0.69646004 1 P 8191 
L 6.0175 0.69646004 6.0176 0.69658002 1 P 8191 
L 6.01923996 0.71186004 6.04548002 0.71181998 1 P 0 
L 6.01853002 0.71168002 6.01868996 0.71175 1 P 8191 
L 6.01868996 0.71175 6.01886998 0.71181004 1 P 8191 
L 6.01886998 0.71181004 6.01903996 0.71183996 1 P 8191 
L 6.01903996 0.71183996 6.01923996 0.71186004 1 P 8191 
L 6.02716004 0.72981998 6.02475 0.72828002 1 P 8191 
L 6.02475 0.72828002 6.02225 0.72688996 1 P 8191 
L 6.02251998 0.72406004 6.02523002 0.7255 1 P 8191 
L 6.02225 0.72688996 6.01968996 0.72561998 1 P 8191 
L 6.01976004 0.72278002 6.02251998 0.72406004 1 P 8191 
L 6.04548002 0.71181998 6.11928002 0.71181998 1 P 0 
L 6.0395 0.73698002 6.04151998 0.73933002 1 P 8191 
L 6.04151998 0.73933002 6.03788996 0.73933002 1 P 8191 
L 6.03738996 0.73473996 6.0395 0.73698002 1 P 8191 
L 6.03788996 0.73933002 6.03593996 0.73718996 1 P 8191 
L 6.03593996 0.73718996 6.03388996 0.73518002 1 P 8191 
L 6.03516004 0.73263996 6.03738996 0.73473996 1 P 8191 
L 6.03388996 0.73518002 6.03175 0.73326998 1 P 8191 
L 6.03283002 0.73066004 6.03516004 0.73263996 1 P 8191 
L 6.03175 0.73326998 6.0295 0.73148002 1 P 8191 
L 6.03038002 0.72878996 6.03283002 0.73066004 1 P 8191 
L 6.02783996 0.72706998 6.03038002 0.72878996 1 P 8191 
L 6.0295 0.73148002 6.02716004 0.72981998 1 P 8191 
L 6.02523002 0.7255 6.02783996 0.72706998 1 P 8191 
L 6.01796004 0.71103002 6.01803996 0.71118996 1 P 8191 
L 6.01803996 0.71118996 6.01813996 0.71133996 1 P 8191 
L 6.01813996 0.71133996 6.01825 0.71146998 1 P 8191 
L 6.01825 0.71146998 6.01838996 0.71158002 1 P 8191 
L 6.01838996 0.71158002 6.01853002 0.71168002 1 P 8191 
L 6.01786998 0.71048002 6.01788002 0.71068002 1 P 8191 
L 6.01788002 0.71068002 6.01791998 0.71086004 1 P 8191 
L 6.01791998 0.71086004 6.01796004 0.71103002 1 P 8191 
L 6.01968996 0.72561998 6.01708002 0.7245 1 P 8191 
L 6.01691998 0.72163996 6.01976004 0.72278002 1 P 8191 
L 6.01708002 0.7245 6.01441004 0.72351004 1 P 8191 
L 6.01403002 0.72066004 6.01691998 0.72163996 1 P 8191 
L 6.01441004 0.72351004 6.01168002 0.72268002 1 P 8191 
L 6.01108996 0.71983996 6.01403002 0.72066004 1 P 8191 
L 6.02086998 0.74265 6.02088996 0.74273002 1 P 8191 
L 6.02088996 0.74273002 6.02091998 0.74281998 1 P 8191 
L 6.02091998 0.74281998 6.02091998 0.74291998 1 P 8191 
L 6.02091998 0.74291998 6.02093002 0.74301998 1 P 8191 
L 6.02093002 0.74301998 6.02093002 0.75116998 1 P 0 
L 6.0201 0.74218996 6.0202 0.74218996 1 P 8191 
L 6.0202 0.74218996 6.0203 0.74221004 1 P 8191 
L 6.0203 0.74221004 6.02038996 0.74221998 1 P 8191 
L 6.02038996 0.74221998 6.02048002 0.74225 1 P 8191 
L 6.02048002 0.74225 6.02056004 0.74228002 1 P 8191 
L 6.02056004 0.74228002 6.02063002 0.74233002 1 P 8191 
L 6.02063002 0.74233002 6.02068996 0.74238002 1 P 8191 
L 6.02068996 0.74238002 6.02075 0.74241998 1 P 8191 
L 6.02075 0.74241998 6.0208 0.74248996 1 P 8191 
L 6.0208 0.74248996 6.02083996 0.74256998 1 P 8191 
L 6.02083996 0.74256998 6.02086998 0.74265 1 P 8191 
L 6.04323002 0.74291998 6.04323996 0.74281998 1 P 8191 
L 6.04321998 0.74301998 6.04323002 0.74291998 1 P 8191 
L 6.04321998 0.77201998 6.04321998 0.74301998 1 P 0 
L 6.04323996 0.74281998 6.04325 0.74273002 1 P 8191 
L 6.04325 0.74273002 6.04328002 0.74265 1 P 8191 
L 6.04328002 0.74265 6.04331004 0.74256998 1 P 8191 
L 6.04331004 0.74256998 6.04336004 0.74248996 1 P 8191 
L 6.04336004 0.74248996 6.0434 0.74241998 1 P 8191 
L 6.0434 0.74241998 6.04346004 0.74238002 1 P 8191 
L 6.04346004 0.74238002 6.04351998 0.74233002 1 P 8191 
L 6.04351998 0.74233002 6.0436 0.74228002 1 P 8191 
L 6.0436 0.74228002 6.04368002 0.74225 1 P 8191 
L 6.04368002 0.74225 6.04376004 0.74221998 1 P 8191 
L 6.04376004 0.74221998 6.04385 0.74221004 1 P 8191 
L 6.04385 0.74221004 6.04395 0.74218996 1 P 8191 
L 6.04395 0.74218996 6.04405 0.74218996 1 P 8191 
L 6.04405 0.74218996 6.06301998 0.74218996 1 P 0 
L 6.04001998 0.74266998 6.04 0.74273996 1 P 8191 
L 6.04 0.74273996 6.03998002 0.74281998 1 P 8191 
L 6.03998002 0.74281998 6.03995 0.74288996 1 P 8191 
L 6.03951004 0.74218996 6.03958996 0.74218996 1 P 8191 
L 6.03958996 0.74218996 6.03966998 0.74221004 1 P 8191 
L 6.03966998 0.74221004 6.03973996 0.74221998 1 P 8191 
L 6.03973996 0.74221998 6.03981004 0.74225 1 P 8191 
L 6.03981004 0.74225 6.03986998 0.74228002 1 P 8191 
L 6.03986998 0.74228002 6.03991998 0.74231998 1 P 8191 
L 6.03991998 0.74231998 6.03996004 0.74236004 1 P 8191 
L 6.03996004 0.74236004 6.04 0.74241004 1 P 8191 
L 6.04 0.74241004 6.04001998 0.74246998 1 P 8191 
L 6.04001998 0.74246998 6.04003002 0.74253996 1 P 8191 
L 6.04003002 0.74253996 6.04003002 0.7426 1 P 8191 
L 6.04003002 0.7426 6.04001998 0.74266998 1 P 8191 
L 6.03995 0.74288996 6.03451004 0.75196004 1 P 0 
L 6.03131998 0.74288996 6.0314 0.74276004 1 P 8191 
L 6.0314 0.74276004 6.0315 0.74265 1 P 8191 
L 6.0315 0.74265 6.03161004 0.74253996 1 P 8191 
L 6.03161004 0.74253996 6.03175 0.74243996 1 P 8191 
L 6.03175 0.74243996 6.0319 0.74235 1 P 8191 
L 6.0319 0.74235 6.03206004 0.74228002 1 P 8191 
L 6.03206004 0.74228002 6.03221004 0.74223002 1 P 8191 
L 6.03221004 0.74223002 6.03238002 0.7422 1 P 8191 
L 6.03238002 0.7422 6.03253996 0.74218996 1 P 8191 
L 6.03253996 0.74218996 6.03951004 0.74218996 1 P 0 
L 6.0264 0.75121998 6.03131998 0.74288996 1 P 0 
L 6.0134 0.74241998 6.01346004 0.74238002 1 P 8191 
L 6.01346004 0.74238002 6.01351998 0.74233002 1 P 8191 
L 6.01351998 0.74233002 6.0136 0.74228002 1 P 8191 
L 6.0136 0.74228002 6.01368002 0.74225 1 P 8191 
L 6.01368002 0.74225 6.01376004 0.74221998 1 P 8191 
L 6.01376004 0.74221998 6.01385 0.74221004 1 P 8191 
L 6.01385 0.74221004 6.01395 0.74218996 1 P 8191 
L 6.01395 0.74218996 6.01405 0.74218996 1 P 8191 
L 6.01405 0.74218996 6.0201 0.74218996 1 P 0 
L 6.01321998 0.77201998 6.01321998 0.74301998 1 P 0 
L 6.01321998 0.74301998 6.01323002 0.74291998 1 P 8191 
L 6.01323002 0.74291998 6.01323996 0.74281998 1 P 8191 
L 6.01323996 0.74281998 6.01326004 0.74273002 1 P 8191 
L 6.01326004 0.74273002 6.01328002 0.74265 1 P 8191 
L 6.01328002 0.74265 6.01331998 0.74256998 1 P 8191 
L 6.01331998 0.74256998 6.01336004 0.74248996 1 P 8191 
L 6.01336004 0.74248996 6.0134 0.74241998 1 P 8191 
L 6.01006004 0.74271004 6.01008996 0.74281004 1 P 8191 
L 6.01008996 0.74281004 6.01011004 0.74291004 1 P 8191 
L 6.01011004 0.74291004 6.01011998 0.74301998 1 P 8191 
L 6.01011998 0.74301998 6.01011998 0.76693996 1 P 0 
L 6.00928996 0.74223002 6.0094 0.74225 1 P 8191 
L 6.0094 0.74225 6.00951998 0.74226004 1 P 8191 
L 6.00951998 0.74226004 6.00961998 0.7423 1 P 8191 
L 6.00961998 0.7423 6.00971998 0.74233996 1 P 8191 
L 6.00971998 0.74233996 6.0098 0.74238996 1 P 8191 
L 6.0098 0.74238996 6.00988002 0.74246004 1 P 8191 
L 6.00988002 0.74246004 6.00995 0.74253996 1 P 8191 
L 6.00995 0.74253996 6.01001004 0.74261998 1 P 8191 
L 6.01001004 0.74261998 6.01006004 0.74271004 1 P 8191 
L 6.00508002 0.71868002 6.00811004 0.71918002 1 P 8191 
L 6.00203002 0.71833996 6.00508002 0.71868002 1 P 8191 
L 5.99896004 0.71816998 6.00203002 0.71833996 1 P 8191 
L 6.00611004 0.72143996 6.00326004 0.72105 1 P 8191 
L 6.00326004 0.72105 6.0004 0.72081004 1 P 8191 
L 6.0004 0.72081004 5.99751998 0.72071004 1 P 8191 
L 6.00241998 0.7429 6.00243996 0.7428 1 P 8191 
L 6.00243996 0.7428 6.00246998 0.7427 1 P 8191 
L 6.00241004 0.74301998 6.00241998 0.7429 1 P 8191 
L 6.00241004 0.7509 6.00241004 0.74301998 1 P 0 
L 6.00251998 0.74261004 6.00256004 0.74253002 1 P 8191 
L 6.00246998 0.7427 6.00251998 0.74261004 1 P 8191 
L 6.00256004 0.74253002 6.00263002 0.74246004 1 P 8191 
L 6.00263002 0.74246004 6.0027 0.74238996 1 P 8191 
L 6.0027 0.74238996 6.00278002 0.74233996 1 P 8191 
L 6.00278002 0.74233996 6.00288002 0.7423 1 P 8191 
L 6.00288002 0.7423 6.00296998 0.74226004 1 P 8191 
L 6.00296998 0.74226004 6.00308002 0.74225 1 P 8191 
L 6.00308002 0.74225 6.0032 0.74223002 1 P 8191 
L 6.0032 0.74223002 6.00928996 0.74223002 1 P 0 
L 6.01168002 0.72268002 6.00891998 0.72198002 1 P 8191 
L 6.00811004 0.71918002 6.01108996 0.71983996 1 P 8191 
L 6.00891998 0.72198002 6.00611004 0.72143996 1 P 8191 
L 6.06301998 0.74218996 6.06321998 0.7422 1 P 8191 
L 6.06321998 0.7422 6.06341998 0.74221998 1 P 8191 
L 6.06863002 0.74656998 6.0687 0.74675 1 P 8191 
L 6.0687 0.74675 6.06876004 0.74693002 1 P 8191 
L 6.06876004 0.74693002 6.06881004 0.7471 1 P 8191 
L 6.06881004 0.7471 6.06886004 0.74726998 1 P 8191 
L 6.06886004 0.74726998 6.0689 0.74745 1 P 8191 
L 6.0689 0.74745 6.06893002 0.74761998 1 P 8191 
L 6.06893002 0.74761998 6.06896004 0.74778002 1 P 8191 
L 6.06896004 0.74778002 6.06896998 0.74793996 1 P 8191 
L 6.06896998 0.74793996 6.06898002 0.7481 1 P 8191 
L 6.06341998 0.74221998 6.06361004 0.74223996 1 P 8191 
L 6.06361004 0.74223996 6.06378996 0.74226998 1 P 8191 
L 6.06378996 0.74226998 6.06396004 0.7423 1 P 8191 
L 6.06396004 0.7423 6.06413996 0.74235 1 P 8191 
L 6.06413996 0.74235 6.0643 0.74241004 1 P 8191 
L 6.0643 0.74241004 6.06445 0.74246998 1 P 8191 
L 6.06445 0.74246998 6.0646 0.74253996 1 P 8191 
L 6.0646 0.74253996 6.06863002 0.74656998 1 P 8191 
L 6.06898002 0.7481 6.06898002 0.76693996 1 P 0 
L 6.08163002 0.73626998 6.08138996 0.73703002 1 P 8191 
L 6.08193996 0.73553996 6.08163002 0.73626998 1 P 8191 
L 6.08231004 0.73483002 6.08193996 0.73553996 1 P 8191 
L 6.08273002 0.73416998 6.08231004 0.73483002 1 P 8191 
L 6.08963996 0.73025 6.08885 0.73035 1 P 8191 
L 6.09043996 0.73021004 6.08963996 0.73025 1 P 8191 
L 6.11768002 0.73021004 6.09043996 0.73021004 1 P 0 
L 6.08646004 0.73111004 6.08571004 0.7315 1 P 8191 
L 6.08726004 0.73078002 6.08646004 0.73111004 1 P 8191 
L 6.08806998 0.73053002 6.08726004 0.73078002 1 P 8191 
L 6.08885 0.73035 6.08806998 0.73053002 1 P 8191 
L 6.08321004 0.73353996 6.08273002 0.73416998 1 P 8191 
L 6.08375 0.73296998 6.08321004 0.73353996 1 P 8191 
L 6.08435 0.73241998 6.08375 0.73296998 1 P 8191 
L 6.085 0.73193996 6.08435 0.73241998 1 P 8191 
L 6.08571004 0.7315 6.085 0.73193996 1 P 8191 
L 6.08193996 0.74328002 6.08231004 0.74398002 1 P 8191 
L 6.08231004 0.74398002 6.08273002 0.74465 1 P 8191 
L 6.08138996 0.74178002 6.08163002 0.74253996 1 P 8191 
L 6.08163002 0.74253996 6.08193996 0.74328002 1 P 8191 
L 6.08571004 0.74731998 6.08646004 0.7477 1 P 8191 
L 6.08646004 0.7477 6.08726004 0.74801998 1 P 8191 
L 6.08375 0.74585 6.08435 0.74638002 1 P 8191 
L 6.08435 0.74638002 6.085 0.74688002 1 P 8191 
L 6.085 0.74688002 6.08571004 0.74731998 1 P 8191 
L 6.08273002 0.74465 6.08321004 0.74526998 1 P 8191 
L 6.08321004 0.74526998 6.08375 0.74585 1 P 8191 
L 6.08885 0.74846004 6.08963996 0.74856998 1 P 8191 
L 6.08963996 0.74856998 6.09043996 0.7486 1 P 8191 
L 6.09043996 0.7486 6.13248002 0.7486 1 P 0 
L 6.08726004 0.74801998 6.08806998 0.74828002 1 P 8191 
L 6.08806998 0.74828002 6.08885 0.74846004 1 P 8191 
L 6.08138996 0.73703002 6.08121004 0.73781998 1 P 8191 
L 6.08121004 0.73781998 6.08111004 0.73861004 1 P 8191 
L 6.08111004 0.73861004 6.08106998 0.73941004 1 P 8191 
L 6.08106998 0.73941004 6.08111004 0.7402 1 P 8191 
L 6.08111004 0.7402 6.08121004 0.741 1 P 8191 
L 6.08121004 0.741 6.08138996 0.74178002 1 P 8191 
L 5.93111998 0.69871998 5.93111998 0.71058996 1 P 0 
L 5.9465 0.74933996 5.94796004 0.74665 1 P 8191 
L 5.95351998 0.71186004 5.95368996 0.71183996 1 P 8191 
L 5.95368996 0.71183996 5.95385 0.71181004 1 P 8191 
L 5.95385 0.71181004 5.95401004 0.71175 1 P 8191 
L 5.95401004 0.71175 5.95416004 0.71168996 1 P 8191 
L 5.95416004 0.71168996 5.9543 0.71158996 1 P 8191 
L 5.9543 0.71158996 5.95441998 0.71148002 1 P 8191 
L 5.95441998 0.71148002 5.95451998 0.71136004 1 P 8191 
L 5.95451998 0.71136004 5.95461998 0.71121998 1 P 8191 
L 5.95461998 0.71121998 5.95468996 0.71106998 1 P 8191 
L 5.95468996 0.71106998 5.95475 0.71091998 1 P 8191 
L 5.95475 0.71091998 5.95478002 0.71076004 1 P 8191 
L 5.95478002 0.71076004 5.95478996 0.71058996 1 P 8191 
L 5.95891004 0.73681004 5.95695 0.73891998 1 P 8191 
L 5.95731004 0.73453002 5.95955 0.73243002 1 P 8191 
L 5.95695 0.73891998 5.95511004 0.74111998 1 P 8191 
L 5.95316998 0.73908002 5.95518002 0.73675 1 P 8191 
L 5.95518002 0.73675 5.95731004 0.73453002 1 P 8191 
L 5.9513 0.7415 5.95316998 0.73908002 1 P 8191 
L 5.95571998 0.7015 5.95588002 0.70146998 1 P 8191 
L 5.95588002 0.70146998 5.95605 0.70146004 1 P 8191 
L 5.95605 0.70146004 5.96406004 0.70146004 1 P 0 
L 5.9548 0.70255 5.95483996 0.70238996 1 P 8191 
L 5.95483996 0.70238996 5.95488996 0.70223996 1 P 8191 
L 5.95478996 0.70273002 5.9548 0.70255 1 P 8191 
L 5.95478996 0.71058996 5.95478996 0.70273002 1 P 0 
L 5.95488996 0.70223996 5.95496004 0.7021 1 P 8191 
L 5.95505 0.70195 5.95516004 0.70183002 1 P 8191 
L 5.95516004 0.70183002 5.95528002 0.70171998 1 P 8191 
L 5.95496004 0.7021 5.95505 0.70195 1 P 8191 
L 5.95543002 0.70163002 5.95556998 0.70156004 1 P 8191 
L 5.95528002 0.70171998 5.95543002 0.70163002 1 P 8191 
L 5.95556998 0.70156004 5.95571998 0.7015 1 P 8191 
L 5.95746004 0.74735 5.9575 0.74718002 1 P 8191 
L 5.9575 0.74718002 5.95755 0.74701998 1 P 8191 
L 5.95743996 0.74753996 5.95746004 0.74735 1 P 8191 
L 5.9574 0.74791004 5.95741004 0.74771998 1 P 8191 
L 5.95741004 0.74771998 5.95743996 0.74753996 1 P 8191 
L 5.95738996 0.7481 5.9574 0.74791004 1 P 8191 
L 5.95766998 0.74671004 5.95773996 0.74656998 1 P 8191 
L 5.95773996 0.74656998 5.96176004 0.74253996 1 P 8191 
L 5.95755 0.74701998 5.9576 0.74686004 1 P 8191 
L 5.9576 0.74686004 5.95766998 0.74671004 1 P 8191 
L 5.95511004 0.74111998 5.95338996 0.74341998 1 P 8191 
L 5.9518 0.7458 5.95033002 0.74826004 1 P 8191 
L 5.95338996 0.74341998 5.9518 0.7458 1 P 8191 
L 5.94796004 0.74665 5.94956004 0.74403996 1 P 8191 
L 5.94956004 0.74403996 5.9513 0.7415 1 P 8191 
L 5.95738996 0.76693996 5.95738996 0.7481 1 P 0 
L 5.95033002 0.74826004 5.949 0.75078996 1 P 8191 
L 5.93116004 0.71091998 5.93121998 0.71106998 1 P 8191 
L 5.93121998 0.71106998 5.93128996 0.71121998 1 P 8191 
L 5.93128996 0.71121998 5.93138996 0.71136004 1 P 8191 
L 5.93138996 0.71136004 5.93148996 0.71148002 1 P 8191 
L 5.93148996 0.71148002 5.93161004 0.71158996 1 P 8191 
L 5.93161004 0.71158996 5.93176004 0.71168996 1 P 8191 
L 5.93176004 0.71168996 5.9319 0.71175 1 P 8191 
L 5.9319 0.71175 5.93206004 0.71181004 1 P 8191 
L 5.93206004 0.71181004 5.93221998 0.71183996 1 P 8191 
L 5.93221998 0.71183996 5.93238996 0.71186004 1 P 8191 
L 5.93238996 0.71186004 5.95351998 0.71186004 1 P 0 
L 5.93111998 0.71058996 5.93113002 0.71076004 1 P 8191 
L 5.93113002 0.71076004 5.93116004 0.71091998 1 P 8191 
L 5.9211 0.75833996 5.92116998 0.75786004 1 P 8191 
L 5.92116998 0.75786004 5.9212 0.75735 1 P 8191 
L 5.92116998 0.75685 5.9211 0.75636004 1 P 8191 
L 5.9212 0.75735 5.92116998 0.75685 1 P 8191 
L 5.91858996 0.76186004 5.91901004 0.7616 1 P 8191 
L 5.91901004 0.7616 5.9194 0.76128996 1 P 8191 
L 5.9194 0.76128996 5.91976004 0.76095 1 P 8191 
L 5.91976004 0.76095 5.92008002 0.76058002 1 P 8191 
L 5.92008002 0.76058002 5.92036998 0.76016998 1 P 8191 
L 5.92036998 0.76016998 5.92061998 0.75973996 1 P 8191 
L 5.92061998 0.75973996 5.92083002 0.75928996 1 P 8191 
L 5.92083002 0.75928996 5.92098996 0.75881998 1 P 8191 
L 5.92098996 0.75881998 5.9211 0.75833996 1 P 8191 
L 5.92098996 0.75588002 5.92083002 0.75541998 1 P 8191 
L 5.9211 0.75636004 5.92098996 0.75588002 1 P 8191 
L 5.91815 0.7621 5.91858996 0.76186004 1 P 8191 
L 5.91256998 0.76128996 5.91296004 0.7616 1 P 8191 
L 5.91296004 0.7616 5.91336998 0.76186004 1 P 8191 
L 5.91336998 0.76186004 5.91381004 0.7621 1 P 8191 
L 5.9116 0.76016998 5.91188002 0.76058002 1 P 8191 
L 5.91188002 0.76058002 5.91221004 0.76095 1 P 8191 
L 5.91221004 0.76095 5.91256998 0.76128996 1 P 8191 
L 5.91076004 0.75735 5.9108 0.75786004 1 P 8191 
L 5.9108 0.75786004 5.91086004 0.75833996 1 P 8191 
L 5.91086004 0.75833996 5.91098002 0.75881998 1 P 8191 
L 5.91098002 0.75881998 5.91113996 0.75928996 1 P 8191 
L 5.91113996 0.75928996 5.91135 0.75973996 1 P 8191 
L 5.91135 0.75973996 5.9116 0.76016998 1 P 8191 
L 5.91086004 0.75635 5.9108 0.75685 1 P 8191 
L 5.9108 0.75685 5.91076004 0.75735 1 P 8191 
L 5.91113996 0.75541004 5.91098002 0.75588002 1 P 8191 
L 5.91098002 0.75588002 5.91086004 0.75635 1 P 8191 
L 5.90816004 0.76861998 5.9238 0.76861998 1 P 0 
L 5.90816004 0.77121998 5.90816004 0.76861998 1 P 8191 
L 5.9238 0.76518002 5.90816004 0.76518002 1 P 0 
L 5.90491998 0.77121998 5.90816004 0.77121998 1 P 8191 
L 5.90816004 0.76518002 5.90816004 0.76256998 1 P 8191 
L 5.90816004 0.76256998 5.90491998 0.76256998 1 P 8191 
L 5.89338996 0.77121998 5.89966004 0.77121998 1 P 0 
L 5.89338996 0.78165 5.89338996 0.77121998 1 P 0 
L 5.89966004 0.76256998 5.89338996 0.76256998 1 P 0 
L 5.90478996 0.83353996 5.90463002 0.83425 1 P 8191 
L 5.90491998 0.8321 5.90488002 0.83281998 1 P 8191 
L 5.90488002 0.83281998 5.90478996 0.83353996 1 P 8191 
L 5.89895 0.83378002 5.89916004 0.83345 1 P 8191 
L 5.89871004 0.83408996 5.89895 0.83378002 1 P 8191 
L 5.89916004 0.83345 5.89933996 0.8331 1 P 8191 
L 5.89948002 0.83273002 5.89958002 0.83236004 1 P 8191 
L 5.89933996 0.8331 5.89948002 0.83273002 1 P 8191 
L 5.89963996 0.83198002 5.89966004 0.83158996 1 P 8191 
L 5.89958002 0.83236004 5.89963996 0.83198002 1 P 8191 
L 5.9238 0.78426004 5.90816004 0.78426004 1 P 0 
L 5.90816004 0.78426004 5.90816004 0.78165 1 P 8191 
L 5.90816004 0.78165 5.90491998 0.78165 1 P 8191 
L 5.89966004 0.78165 5.89338996 0.78165 1 P 0 
L 5.9238 0.76861998 5.9238 0.78426004 1 P 0 
L 5.91815 0.77168996 5.91768996 0.7715 1 P 8191 
L 5.91858996 0.77191998 5.91815 0.77168996 1 P 8191 
L 5.91623996 0.77121998 5.91573002 0.77121998 1 P 8191 
L 5.91671998 0.77126998 5.91623996 0.77121998 1 P 8191 
L 5.91721004 0.77136998 5.91671998 0.77126998 1 P 8191 
L 5.91768996 0.7715 5.91721004 0.77136998 1 P 8191 
L 5.91381004 0.77168996 5.91336998 0.77191998 1 P 8191 
L 5.91428002 0.7715 5.91381004 0.77168996 1 P 8191 
L 5.91475 0.77136998 5.91428002 0.7715 1 P 8191 
L 5.91523996 0.77126998 5.91475 0.77136998 1 P 8191 
L 5.91573002 0.77121998 5.91523996 0.77126998 1 P 8191 
L 5.91016998 0.76861998 5.91016998 0.76518002 1 P 8191 
L 5.91573002 0.76256004 5.91623996 0.76256004 1 P 8191 
L 5.91623996 0.76256004 5.91671998 0.76251004 1 P 8191 
L 5.91671998 0.76251004 5.91721004 0.76241998 1 P 8191 
L 5.91721004 0.76241998 5.91768996 0.76228002 1 P 8191 
L 5.91768996 0.76228002 5.91815 0.7621 1 P 8191 
L 5.91381004 0.7621 5.91428002 0.76228002 1 P 8191 
L 5.91428002 0.76228002 5.91475 0.76241998 1 P 8191 
L 5.91475 0.76241998 5.91523996 0.76251004 1 P 8191 
L 5.91523996 0.76251004 5.91573002 0.76256004 1 P 8191 
L 5.92116998 0.77593002 5.9211 0.77543996 1 P 8191 
L 5.9212 0.77643002 5.92116998 0.77593002 1 P 8191 
L 5.92116998 0.77693996 5.9212 0.77643002 1 P 8191 
L 5.92098996 0.77496004 5.92083002 0.7745 1 P 8191 
L 5.9211 0.77543996 5.92098996 0.77496004 1 P 8191 
L 5.91901004 0.77218002 5.91858996 0.77191998 1 P 8191 
L 5.9194 0.7725 5.91901004 0.77218002 1 P 8191 
L 5.91976004 0.77283996 5.9194 0.7725 1 P 8191 
L 5.92008002 0.77321004 5.91976004 0.77283996 1 P 8191 
L 5.92036998 0.77361998 5.92008002 0.77321004 1 P 8191 
L 5.92061998 0.77403996 5.92036998 0.77361998 1 P 8191 
L 5.92083002 0.7745 5.92061998 0.77403996 1 P 8191 
L 5.91296004 0.77218002 5.91256998 0.7725 1 P 8191 
L 5.91336998 0.77191998 5.91296004 0.77218002 1 P 8191 
L 5.91086004 0.77543996 5.9108 0.77593002 1 P 8191 
L 5.9108 0.77593002 5.91076004 0.77643002 1 P 8191 
L 5.91076004 0.77643002 5.9108 0.77693996 1 P 8191 
L 5.91113996 0.7745 5.91098002 0.77496004 1 P 8191 
L 5.91098002 0.77496004 5.91086004 0.77543996 1 P 8191 
L 5.9116 0.77361998 5.91135 0.77403996 1 P 8191 
L 5.91135 0.77403996 5.91113996 0.7745 1 P 8191 
L 5.91188002 0.77321004 5.9116 0.77361998 1 P 8191 
L 5.91221004 0.77283002 5.91188002 0.77321004 1 P 8191 
L 5.91256998 0.7725 5.91221004 0.77283002 1 P 8191 
L 5.9211 0.77743002 5.92116998 0.77693996 1 P 8191 
L 5.91858996 0.78095 5.91901004 0.78068002 1 P 8191 
L 5.91901004 0.78068002 5.9194 0.78038002 1 P 8191 
L 5.9194 0.78038002 5.91976004 0.78003002 1 P 8191 
L 5.91976004 0.78003002 5.92008002 0.77966004 1 P 8191 
L 5.92008002 0.77966004 5.92036998 0.77926004 1 P 8191 
L 5.92036998 0.77926004 5.92061998 0.77881998 1 P 8191 
L 5.92083002 0.77838002 5.92098996 0.7779 1 P 8191 
L 5.92061998 0.77881998 5.92083002 0.77838002 1 P 8191 
L 5.92098996 0.7779 5.9211 0.77743002 1 P 8191 
L 5.91573002 0.78163996 5.91623996 0.78163996 1 P 8191 
L 5.91623996 0.78163996 5.91671998 0.7816 1 P 8191 
L 5.91671998 0.7816 5.91721004 0.7815 1 P 8191 
L 5.91721004 0.7815 5.91768996 0.78136004 1 P 8191 
L 5.91768996 0.78136004 5.91815 0.78118002 1 P 8191 
L 5.91815 0.78118002 5.91858996 0.78095 1 P 8191 
L 5.91256998 0.78038002 5.91296004 0.78068002 1 P 8191 
L 5.91296004 0.78068002 5.91336998 0.78095 1 P 8191 
L 5.91336998 0.78095 5.91381004 0.78118002 1 P 8191 
L 5.91381004 0.78118002 5.91428002 0.78136004 1 P 8191 
L 5.91428002 0.78136004 5.91475 0.7815 1 P 8191 
L 5.91475 0.7815 5.91523996 0.7816 1 P 8191 
L 5.91523996 0.7816 5.91573002 0.78163996 1 P 8191 
L 5.91016998 0.84056998 5.91016998 0.78426004 1 P 0 
L 5.91086004 0.77743002 5.91098002 0.7779 1 P 8191 
L 5.91098002 0.7779 5.91113996 0.77838002 1 P 8191 
L 5.91113996 0.77838002 5.91135 0.77881998 1 P 8191 
L 5.91135 0.77881998 5.9116 0.77926004 1 P 8191 
L 5.9116 0.77926004 5.91188002 0.77966004 1 P 8191 
L 5.91188002 0.77966004 5.91221004 0.78003002 1 P 8191 
L 5.91221004 0.78003002 5.91256998 0.78038002 1 P 8191 
L 5.9108 0.77693996 5.91086004 0.77743002 1 P 8191 
L 5.91016998 0.84056998 5.87863996 0.84056998 1 P 0 
L 5.87863996 0.83531004 5.89593996 0.83531004 1 P 0 
L 5.90463002 0.83425 5.9044 0.83496004 1 P 8191 
L 5.90411004 0.83566998 5.90376004 0.83633996 1 P 8191 
L 5.9044 0.83496004 5.90411004 0.83566998 1 P 8191 
L 5.90376004 0.83633996 5.90336998 0.83696998 1 P 8191 
L 5.89813002 0.8346 5.89843002 0.83436004 1 P 8191 
L 5.89843002 0.83436004 5.89871004 0.83408996 1 P 8191 
L 5.90188996 0.83858002 5.90131004 0.83901998 1 P 8191 
L 5.90243996 0.83808996 5.90188996 0.83858002 1 P 8191 
L 5.90291998 0.83753996 5.90243996 0.83808996 1 P 8191 
L 5.90336998 0.83696998 5.90291998 0.83753996 1 P 8191 
L 5.89931004 0.84006004 5.89858996 0.84028002 1 P 8191 
L 5.90001004 0.83976004 5.89931004 0.84006004 1 P 8191 
L 5.90068002 0.83941998 5.90001004 0.83976004 1 P 8191 
L 5.90131004 0.83901998 5.90068002 0.83941998 1 P 8191 
L 5.89716004 0.84053996 5.89643996 0.84056998 1 P 8191 
L 5.89788002 0.84043996 5.89716004 0.84053996 1 P 8191 
L 5.89858996 0.84028002 5.89788002 0.84043996 1 P 8191 
L 5.89593996 0.83531004 5.89633002 0.8353 1 P 8191 
L 5.89633002 0.8353 5.8967 0.83523002 1 P 8191 
L 5.8967 0.83523002 5.89708002 0.83513996 1 P 8191 
L 5.89708002 0.83513996 5.89743996 0.83498996 1 P 8191 
L 5.89743996 0.83498996 5.8978 0.83481998 1 P 8191 
L 5.8978 0.83481998 5.89813002 0.8346 1 P 8191 
L 6.18795 0.84056998 5.91016998 0.84056998 1 P 0 
L 5.90491998 0.75213996 5.90816004 0.75213996 1 P 8191 
L 5.89338996 0.75213996 5.89966004 0.75213996 1 P 0 
L 5.89338996 0.76256998 5.89338996 0.75213996 1 P 0 
L 5.90816004 0.74953002 5.9238 0.74953002 1 P 0 
L 5.90816004 0.75213996 5.90816004 0.74953002 1 P 8191 
L 5.92061998 0.75496004 5.92036998 0.75453002 1 P 8191 
L 5.92083002 0.75541998 5.92061998 0.75496004 1 P 8191 
L 5.91901004 0.7531 5.91858996 0.75283002 1 P 8191 
L 5.9194 0.75341004 5.91901004 0.7531 1 P 8191 
L 5.91976004 0.75375 5.9194 0.75341004 1 P 8191 
L 5.92008002 0.75413002 5.91976004 0.75375 1 P 8191 
L 5.92036998 0.75453002 5.92008002 0.75413002 1 P 8191 
L 5.91623996 0.75213996 5.91573002 0.75213996 1 P 8191 
L 5.91671998 0.75218002 5.91623996 0.75213996 1 P 8191 
L 5.91721004 0.75228002 5.91671998 0.75218002 1 P 8191 
L 5.91768996 0.75241998 5.91721004 0.75228002 1 P 8191 
L 5.91815 0.75261004 5.91768996 0.75241998 1 P 8191 
L 5.91858996 0.75283002 5.91815 0.75261004 1 P 8191 
L 5.91296004 0.7531 5.91256998 0.75341004 1 P 8191 
L 5.91336998 0.75283002 5.91296004 0.7531 1 P 8191 
L 5.91381004 0.75261004 5.91336998 0.75283002 1 P 8191 
L 5.91428002 0.75241998 5.91381004 0.75261004 1 P 8191 
L 5.91475 0.75228002 5.91428002 0.75241998 1 P 8191 
L 5.91523996 0.75218002 5.91475 0.75228002 1 P 8191 
L 5.91573002 0.75213996 5.91523996 0.75218002 1 P 8191 
L 5.9116 0.75453002 5.91135 0.75496004 1 P 8191 
L 5.91135 0.75496004 5.91113996 0.75541004 1 P 8191 
L 5.91188002 0.75413002 5.9116 0.75453002 1 P 8191 
L 5.91221004 0.75375 5.91188002 0.75413002 1 P 8191 
L 5.91256998 0.75341004 5.91221004 0.75375 1 P 8191 
L 5.9238 0.74953002 5.9238 0.76518002 1 P 0 
L 5.87863996 0.67941998 6.18795 0.67941998 1 P 0 
L 5.87863996 0.84056998 5.87863996 0.67941998 1 P 0 
L 5.90491998 0.67941998 5.90491998 0.8321 1 P 0 
L 5.89966004 0.83158996 5.89966004 0.67941998 1 P 0 
L 5.90816004 0.71136004 5.9238 0.71136004 1 P 0 
L 5.90816004 0.71396998 5.90816004 0.71136004 1 P 8191 
L 5.90491998 0.71396998 5.90816004 0.71396998 1 P 8191 
L 5.90816004 0.73043996 5.9238 0.73043996 1 P 0 
L 5.90816004 0.73305 5.90816004 0.73043996 1 P 8191 
L 5.9238 0.727 5.90816004 0.727 1 P 0 
L 5.90816004 0.727 5.90816004 0.72438996 1 P 8191 
L 5.90491998 0.73305 5.90816004 0.73305 1 P 8191 
L 5.90816004 0.72438996 5.90491998 0.72438996 1 P 8191 
L 5.89338996 0.71396998 5.89966004 0.71396998 1 P 0 
L 5.89338996 0.72438996 5.89338996 0.71396998 1 P 0 
L 5.89338996 0.73305 5.89966004 0.73305 1 P 0 
L 5.89338996 0.74348002 5.89338996 0.73305 1 P 0 
L 5.89966004 0.72438996 5.89338996 0.72438996 1 P 0 
L 5.9238 0.74608996 5.90816004 0.74608996 1 P 0 
L 5.90816004 0.74608996 5.90816004 0.74348002 1 P 8191 
L 5.90816004 0.74348002 5.90491998 0.74348002 1 P 8191 
L 5.89966004 0.74348002 5.89338996 0.74348002 1 P 0 
L 5.91016998 0.69871998 5.93111998 0.69871998 1 P 0 
L 5.91016998 0.71136004 5.91016998 0.69871998 1 P 0 
L 5.92116998 0.71868002 5.9211 0.71818002 1 P 8191 
L 5.9212 0.71918002 5.92116998 0.71868002 1 P 8191 
L 5.9238 0.71136004 5.9238 0.727 1 P 0 
L 5.92083002 0.71723996 5.92061998 0.71678996 1 P 8191 
L 5.92098996 0.71771004 5.92083002 0.71723996 1 P 8191 
L 5.9211 0.71818002 5.92098996 0.71771004 1 P 8191 
L 5.91901004 0.71493996 5.91858996 0.71466004 1 P 8191 
L 5.9194 0.71523996 5.91901004 0.71493996 1 P 8191 
L 5.91976004 0.71558002 5.9194 0.71523996 1 P 8191 
L 5.92008002 0.71596004 5.91976004 0.71558002 1 P 8191 
L 5.92036998 0.71636004 5.92008002 0.71596004 1 P 8191 
L 5.92061998 0.71678996 5.92036998 0.71636004 1 P 8191 
L 5.91623996 0.71398002 5.91573002 0.71398002 1 P 8191 
L 5.91671998 0.71401998 5.91623996 0.71398002 1 P 8191 
L 5.91721004 0.71411004 5.91671998 0.71401998 1 P 8191 
L 5.91768996 0.71426004 5.91721004 0.71411004 1 P 8191 
L 5.91815 0.71443996 5.91768996 0.71426004 1 P 8191 
L 5.91858996 0.71466004 5.91815 0.71443996 1 P 8191 
L 5.91296004 0.71493996 5.91256998 0.71523996 1 P 8191 
L 5.91336998 0.71466004 5.91296004 0.71493996 1 P 8191 
L 5.91381004 0.71443996 5.91336998 0.71466004 1 P 8191 
L 5.91428002 0.71426004 5.91381004 0.71443996 1 P 8191 
L 5.91475 0.71411004 5.91428002 0.71426004 1 P 8191 
L 5.91523996 0.71401998 5.91475 0.71411004 1 P 8191 
L 5.91573002 0.71398002 5.91523996 0.71401998 1 P 8191 
L 5.91086004 0.71818002 5.9108 0.71868002 1 P 8191 
L 5.9108 0.71868002 5.91076004 0.71918002 1 P 8191 
L 5.91113996 0.71723996 5.91098002 0.71771004 1 P 8191 
L 5.91098002 0.71771004 5.91086004 0.71818002 1 P 8191 
L 5.91135 0.71678996 5.91113996 0.71723996 1 P 8191 
L 5.9116 0.71636004 5.91135 0.71678996 1 P 8191 
L 5.91188002 0.71596004 5.9116 0.71636004 1 P 8191 
L 5.91221004 0.71558002 5.91188002 0.71596004 1 P 8191 
L 5.91256998 0.71523996 5.91221004 0.71558002 1 P 8191 
L 5.92116998 0.73776004 5.9211 0.73726998 1 P 8191 
L 5.9212 0.73826004 5.92116998 0.73776004 1 P 8191 
L 5.9211 0.73926004 5.92116998 0.73876998 1 P 8191 
L 5.92116998 0.73876998 5.9212 0.73826004 1 P 8191 
L 5.9238 0.73043996 5.9238 0.74608996 1 P 0 
L 5.9211 0.72018002 5.92116998 0.71968996 1 P 8191 
L 5.92116998 0.71968996 5.9212 0.71918002 1 P 8191 
L 5.92098996 0.73973996 5.9211 0.73926004 1 P 8191 
L 5.9194 0.73433002 5.91901004 0.73401998 1 P 8191 
L 5.91976004 0.73466004 5.9194 0.73433002 1 P 8191 
L 5.92008002 0.73503996 5.91976004 0.73466004 1 P 8191 
L 5.92036998 0.73545 5.92008002 0.73503996 1 P 8191 
L 5.92061998 0.73586998 5.92036998 0.73545 1 P 8191 
L 5.92083002 0.73633002 5.92061998 0.73586998 1 P 8191 
L 5.92098996 0.73678996 5.92083002 0.73633002 1 P 8191 
L 5.9211 0.73726998 5.92098996 0.73678996 1 P 8191 
L 5.91901004 0.73401998 5.91858996 0.73375 1 P 8191 
L 5.91858996 0.7237 5.91901004 0.72343002 1 P 8191 
L 5.91901004 0.72343002 5.9194 0.72311998 1 P 8191 
L 5.9194 0.72311998 5.91976004 0.72278002 1 P 8191 
L 5.91976004 0.72278002 5.92008002 0.72241004 1 P 8191 
L 5.92008002 0.72241004 5.92036998 0.722 1 P 8191 
L 5.92036998 0.722 5.92061998 0.72158002 1 P 8191 
L 5.92083002 0.72111998 5.92098996 0.72066004 1 P 8191 
L 5.92061998 0.72158002 5.92083002 0.72111998 1 P 8191 
L 5.92098996 0.72066004 5.9211 0.72018002 1 P 8191 
L 5.91623996 0.73306004 5.91573002 0.73306004 1 P 8191 
L 5.91671998 0.7331 5.91623996 0.73306004 1 P 8191 
L 5.91721004 0.7332 5.91671998 0.7331 1 P 8191 
L 5.91768996 0.73333996 5.91721004 0.7332 1 P 8191 
L 5.91815 0.73351998 5.91768996 0.73333996 1 P 8191 
L 5.91858996 0.73375 5.91815 0.73351998 1 P 8191 
L 5.91573002 0.72438996 5.91623996 0.72438996 1 P 8191 
L 5.91623996 0.72438996 5.91671998 0.72433996 1 P 8191 
L 5.91671998 0.72433996 5.91721004 0.72425 1 P 8191 
L 5.91721004 0.72425 5.91768996 0.72411004 1 P 8191 
L 5.91768996 0.72411004 5.91815 0.72393002 1 P 8191 
L 5.91815 0.72393002 5.91858996 0.7237 1 P 8191 
L 5.91296004 0.73401998 5.91256998 0.73433002 1 P 8191 
L 5.91336998 0.73375 5.91296004 0.73401998 1 P 8191 
L 5.91381004 0.73351998 5.91336998 0.73375 1 P 8191 
L 5.91428002 0.73333996 5.91381004 0.73351998 1 P 8191 
L 5.91475 0.7332 5.91428002 0.73333996 1 P 8191 
L 5.91523996 0.7331 5.91475 0.7332 1 P 8191 
L 5.91573002 0.73306004 5.91523996 0.7331 1 P 8191 
L 5.91256998 0.72311998 5.91296004 0.72343002 1 P 8191 
L 5.91296004 0.72343002 5.91336998 0.7237 1 P 8191 
L 5.91336998 0.7237 5.91381004 0.72393002 1 P 8191 
L 5.91381004 0.72393002 5.91428002 0.72411004 1 P 8191 
L 5.91428002 0.72411004 5.91475 0.72425 1 P 8191 
L 5.91475 0.72425 5.91523996 0.72433996 1 P 8191 
L 5.91523996 0.72433996 5.91573002 0.72438996 1 P 8191 
L 5.91086004 0.73726998 5.9108 0.73776004 1 P 8191 
L 5.9108 0.73776004 5.91076004 0.73826004 1 P 8191 
L 5.91076004 0.73826004 5.9108 0.73876998 1 P 8191 
L 5.9108 0.73876998 5.91086004 0.73926004 1 P 8191 
L 5.91086004 0.73926004 5.91098002 0.73973996 1 P 8191 
L 5.91113996 0.73633002 5.91098002 0.73678996 1 P 8191 
L 5.91098002 0.73678996 5.91086004 0.73726998 1 P 8191 
L 5.9116 0.73545 5.91135 0.73586998 1 P 8191 
L 5.91135 0.73586998 5.91113996 0.73633002 1 P 8191 
L 5.91188002 0.73503996 5.9116 0.73545 1 P 8191 
L 5.91221004 0.73466004 5.91188002 0.73503996 1 P 8191 
L 5.91256998 0.73433002 5.91221004 0.73466004 1 P 8191 
L 5.91016998 0.73043996 5.91016998 0.727 1 P 8191 
L 5.91221004 0.72278002 5.91256998 0.72311998 1 P 8191 
L 5.9108 0.71968996 5.91086004 0.72018002 1 P 8191 
L 5.91086004 0.72018002 5.91098002 0.72066004 1 P 8191 
L 5.91098002 0.72066004 5.91113996 0.72111998 1 P 8191 
L 5.91113996 0.72111998 5.91135 0.72158002 1 P 8191 
L 5.91135 0.72158002 5.9116 0.722 1 P 8191 
L 5.9116 0.722 5.91188002 0.72241004 1 P 8191 
L 5.91188002 0.72241004 5.91221004 0.72278002 1 P 8191 
L 5.91076004 0.71918002 5.9108 0.71968996 1 P 8191 
L 5.91858996 0.74278002 5.91901004 0.74251004 1 P 8191 
L 5.91901004 0.74251004 5.9194 0.74221004 1 P 8191 
L 5.9194 0.74221004 5.91976004 0.74186004 1 P 8191 
L 5.91976004 0.74186004 5.92008002 0.74148996 1 P 8191 
L 5.92008002 0.74148996 5.92036998 0.74108996 1 P 8191 
L 5.92036998 0.74108996 5.92061998 0.74066004 1 P 8191 
L 5.92061998 0.74066004 5.92083002 0.7402 1 P 8191 
L 5.92083002 0.7402 5.92098996 0.73973996 1 P 8191 
L 5.91573002 0.74346998 5.91623996 0.74346998 1 P 8191 
L 5.91623996 0.74346998 5.91671998 0.74343002 1 P 8191 
L 5.91671998 0.74343002 5.91721004 0.74333996 1 P 8191 
L 5.91721004 0.74333996 5.91768996 0.74318996 1 P 8191 
L 5.91768996 0.74318996 5.91815 0.74301004 1 P 8191 
L 5.91815 0.74301004 5.91858996 0.74278002 1 P 8191 
L 5.91336998 0.74278002 5.91381004 0.74301004 1 P 8191 
L 5.91381004 0.74301004 5.91428002 0.74318996 1 P 8191 
L 5.91428002 0.74318996 5.91475 0.74333996 1 P 8191 
L 5.91475 0.74333996 5.91523996 0.74343002 1 P 8191 
L 5.91523996 0.74343002 5.91573002 0.74346998 1 P 8191 
L 5.91256998 0.74221004 5.91296004 0.74251004 1 P 8191 
L 5.91296004 0.74251004 5.91336998 0.74278002 1 P 8191 
L 5.91016998 0.74953002 5.91016998 0.74608996 1 P 8191 
L 5.91113996 0.74021004 5.91135 0.74066004 1 P 8191 
L 5.91135 0.74066004 5.9116 0.74108996 1 P 8191 
L 5.9116 0.74108996 5.91188002 0.74148996 1 P 8191 
L 5.91188002 0.74148996 5.91221004 0.74186004 1 P 8191 
L 5.91221004 0.74186004 5.91256998 0.74221004 1 P 8191 
L 5.91098002 0.73973996 5.91113996 0.74021004 1 P 8191 
L 3.85 2.825 3.85 2.805 1 P 0 
L 3.85 2.805 3.88 2.805 1 P 0 
L 3.89 2.79 3.89 2.65 1 P 0 
L 3.675 3.055 3.775 3.055 1 P 0 
L 3.775 3.055 3.775 3.05 1 P 0 
L 3.81 3.045 3.825 3.045 1 P 0 
L 3.825 3.045 3.825 2.945 1 P 0 
L 3.825 2.905 3.825 2.825 1 P 0 
L 3.825 2.825 3.85 2.825 1 P 0 
L 3.89 2.65 3.785 2.65 1 P 0 
L 3.785 2.65 3.785 2.675 1 P 0 
L 3.785 2.675 3.78 2.675 1 P 0 
L 3.53 3.595 3.53 3.75 1 P 0 
L 3.63 3.05 3.64 3.05 1 P 0 
L 3.545 2.915 3.545 2.98 1 P 0 
L 3.545 2.98 3.63 2.98 1 P 0 
L 3.63 2.98 3.63 3.05 1 P 0 
L 3.66 2.695 3.55 2.695 1 P 0 
L 3.55 2.695 3.55 2.73 1 P 0 
L 3.5 2.595 3.51 2.595 1 P 0 
L 3.53 2.585 3.555 2.585 1 P 0 
L 3.605 2.545 3.575 2.545 1 P 0 
L 3.575 2.545 3.575 2.57 1 P 0 
L 3.57 2.485 3.605 2.485 1 P 0 
L 3.605 2.485 3.605 2.545 1 P 0 
L 3.53 3.75 3.465 3.75 1 P 0 
L 3.465 3.75 3.465 3.77 1 P 0 
L 3.35 2.585 3.37 2.585 1 P 0 
L 3.4 2.585 3.42 2.585 1 P 0 
L 3.45 2.585 3.455 2.585 1 P 0 
L 3.455 2.585 3.455 2.595 1 P 0 
L 3.455 2.595 3.465 2.595 1 P 0 
L 3.33 2.19 3.325 2.19 1 P 0 
L 3.33 2.15 3.33 2.19 1 P 0 
L 3.38 3.915 3.275 3.915 1 P 0 
L 3.275 3.915 3.275 3.895 1 P 0 
L 3.275 3.895 3.225 3.895 1 P 0 
L 3.29 3.595 3.53 3.595 1 P 0 
L 3.225 3.895 3.225 3.68 1 P 0 
L 3.29 3.48 3.29 3.595 1 P 0 
L 3.24 3.14 3.24 3.055 1 P 0 
L 3.24 3.055 3.2 3.055 1 P 0 
L 3.2 3.055 3.2 2.985 1 P 0 
L 3.255 2.585 3.265 2.585 1 P 0 
L 3.3 2.585 3.32 2.585 1 P 0 
L 3.23 2.58 3.23 2.375 1 P 0 
L 3.53 2.48 3.255 2.48 1 P 0 
L 3.255 2.48 3.255 2.585 1 P 0 
L 3.23 2.35 3.23 2.29 1 P 0 
L 3.23 2.26 3.23 2.225 1 P 0 
L 3.235 2.19 3.29 2.19 1 P 0 
L 3.225 3.68 3.095 3.68 1 P 0 
L 3.095 3.68 3.095 3.48 1 P 0 
L 3.095 3.48 3.29 3.48 1 P 0 
L 2.975 2.875 2.975 2.97 1 P 0 
L 2.975 2.875 3.11 2.875 1 P 0 
L 3.11 2.605 3.095 2.645 1 P 0 
L 3.11 2.605 3.135 2.645 1 P 0 
L 3.11 2.875 3.11 2.605 1 P 0 
L 3.1 2.595 3.21 2.595 1 P 0 
L 3.31 2.135 3.1 2.135 1 P 0 
L 3.1 2.135 3.1 2.595 1 P 0 
L 2.805 3.825 2.805 3.395 1 P 0 
L 2.915 3.14 3.24 3.14 1 P 0 
L 2.87 3.14 2.915 3.14 1 P 0 
L 2.845 2.97 2.845 3.355 1 P 0 
L 2.975 2.97 2.845 2.97 1 P 0 
L 3.2 2.985 2.87 2.985 1 P 0 
L 2.87 2.985 2.87 3.14 1 P 0 
L 2.845 3.355 2.7 3.355 1 P 0 
L 2.7 3.355 2.7 2.875 1 P 0 
L 2.7 2.875 2.975 2.875 1 P 0 
L 2.505 3.825 2.805 3.825 1 P 0 
L 2.465 3.825 2.505 3.825 1 P 0 
L 2.47 3.72 2.55 3.72 1 P 0 
L 2.55 3.72 2.55 3.825 1 P 0 
L 2.805 3.395 2.465 3.395 1 P 0 
L 2.465 3.395 2.465 3.825 1 P 0 
L 3.63806634 2.72603356 3.6396 2.72758317 1 P 0 ;0,1=0,2=0.000000
L 3.6396 2.72758317 3.6407498 2.73016594 1 P 0 ;0,1=0,2=0.000000
L 3.6407498 2.73016594 3.64151703 2.73378376 1 P 0 ;0,1=0,2=0.000000
L 3.64151703 2.73378376 3.6407498 2.73688307 1 P 0 ;0,1=0,2=0.000000
L 3.6407498 2.73688307 3.63921673 2.73894931 1 P 0 ;0,1=0,2=0.000000
L 3.63921673 2.73894931 3.63653327 2.7405 1 P 0 ;0,1=0,2=0.000000
L 3.63653327 2.7405 3.62618337 2.7405 1 P 0 ;0,1=0,2=0.000000
L 3.62618337 2.7405 3.62618337 2.7095 1 P 0 ;0,1=0,2=0.000000
L 3.62618337 2.7095 3.63883356 2.7095 1 P 0 ;0,1=0,2=0.000000
L 3.63883356 2.7095 3.64151703 2.71156614 1 P 0 ;0,1=0,2=0.000000
L 3.64151703 2.71156614 3.64305 2.71466644 1 P 0 ;0,1=0,2=0.000000
L 3.64305 2.71466644 3.64381654 2.71828327 1 P 0 ;0,1=0,2=0.000000
L 3.64381654 2.71828327 3.64305 2.72189921 1 P 0 ;0,1=0,2=0.000000
L 3.64305 2.72189921 3.6407498 2.72499951 1 P 0 ;0,1=0,2=0.000000
L 3.6407498 2.72499951 3.63806634 2.72603356 1 P 0 ;0,1=0,2=0.000000
L 3.63806634 2.72603356 3.62618337 2.72603356 1 P 0 ;0,1=0,2=0.000000
L 3.57541624 2.5045 3.58499961 2.5355 1 P 0 ;0,1=1,2=0.000000
L 3.58499961 2.5355 3.59458366 2.5045 1 P 0 ;0,1=1,2=0.000000
L 3.59113307 2.51534951 3.57886614 2.51534951 1 P 0 ;0,1=1,2=0.000000
L 3.20041624 3.0695 3.20999961 3.1005 1 P 0 ;0,1=1,2=0.000000
L 3.20999961 3.1005 3.21958366 3.0695 1 P 0 ;0,1=1,2=0.000000
L 3.21613307 3.08034951 3.20386614 3.08034951 1 P 0 ;0,1=1,2=0.000000
L 2.51306634 3.76103356 2.5146 3.76258317 1 P 0 ;0,1=0,2=0.000000
L 2.5146 3.76258317 2.5157498 3.76516594 1 P 0 ;0,1=0,2=0.000000
L 2.5157498 3.76516594 2.51651703 3.76878376 1 P 0 ;0,1=0,2=0.000000
L 2.51651703 3.76878376 2.5157498 3.77188307 1 P 0 ;0,1=0,2=0.000000
L 2.5157498 3.77188307 2.51421673 3.77394931 1 P 0 ;0,1=0,2=0.000000
L 2.51421673 3.77394931 2.51153327 3.7755 1 P 0 ;0,1=0,2=0.000000
L 2.51153327 3.7755 2.50118337 3.7755 1 P 0 ;0,1=0,2=0.000000
L 2.50118337 3.7755 2.50118337 3.7445 1 P 0 ;0,1=0,2=0.000000
L 2.50118337 3.7445 2.51383356 3.7445 1 P 0 ;0,1=0,2=0.000000
L 2.51383356 3.7445 2.51651703 3.74656614 1 P 0 ;0,1=0,2=0.000000
L 2.51651703 3.74656614 2.51805 3.74966644 1 P 0 ;0,1=0,2=0.000000
L 2.51805 3.74966644 2.51881654 3.75328327 1 P 0 ;0,1=0,2=0.000000
L 2.51881654 3.75328327 2.51805 3.75689921 1 P 0 ;0,1=0,2=0.000000
L 2.51805 3.75689921 2.5157498 3.75999951 1 P 0 ;0,1=0,2=0.000000
L 2.5157498 3.75999951 2.51306634 3.76103356 1 P 0 ;0,1=0,2=0.000000
L 2.51306634 3.76103356 2.50118337 3.76103356 1 P 0 ;0,1=0,2=0.000000
L 6.61296998 1.84558996 6.61296998 1.19566998 1 P 0 
L 5.9405 1.84558996 6.61296998 1.84558996 1 P 0 
L 6.61296998 1.19566998 5.9405 1.19566998 1 P 0 
L 5.9405 1.19566998 5.9405 1.84558996 1 P 0 
L 6.1505 1.85499961 6.1195 1.85499961 1 P 0 ;0,1=2,2=270.000000
L 6.1195 1.85499961 6.1256997 1.8503999 1 P 0 ;0,1=2,2=270.000000
L 6.1505 1.8503999 6.1505 1.85959931 1 P 0 ;0,1=2,2=270.000000
L 6.14949961 1.1445 6.14949961 1.1755 1 P 0 ;0,1=3,2=0.000000
L 6.14949961 1.1755 6.1448999 1.1693003 1 P 0 ;0,1=3,2=0.000000
L 6.1448999 1.1445 6.15409931 1.1445 1 P 0 ;0,1=3,2=0.000000
L 6.18049961 1.1445 6.18049961 1.1755 1 P 0 ;0,1=3,2=0.000000
L 6.18049961 1.1755 6.1758999 1.1693003 1 P 0 ;0,1=3,2=0.000000
L 6.1758999 1.1445 6.18509931 1.1445 1 P 0 ;0,1=3,2=0.000000
L 5.99966654 1.85771644 5.99656722 1.86001663 1 P 0 ;0,1=4,2=270.000000
L 5.99656722 1.86001663 5.99501663 1.8627001 1 P 0 ;0,1=4,2=270.000000
L 5.99501663 1.8627001 5.9945 1.86576683 1 P 0 ;0,1=4,2=270.000000
L 5.9945 1.86576683 5.99553317 1.8696 1 P 0 ;0,1=4,2=270.000000
L 5.99553317 1.8696 5.99811693 1.87228346 1 P 0 ;0,1=4,2=270.000000
L 5.99811693 1.87228346 6.00121624 1.87305 1 P 0 ;0,1=4,2=270.000000
L 6.00121624 1.87305 6.00431742 1.87266673 1 P 0 ;0,1=4,2=270.000000
L 6.00431742 1.87266673 6.0069002 1.87113307 1 P 0 ;0,1=4,2=270.000000
L 6.0069002 1.87113307 6.01206673 1.86346663 1 P 0 ;0,1=4,2=270.000000
L 6.01206673 1.86346663 6.01568356 1.86001663 1 P 0 ;0,1=4,2=270.000000
L 6.01568356 1.86001663 6.02085108 1.85771644 1 P 0 ;0,1=4,2=270.000000
L 6.02085108 1.85771644 6.0255 1.8569499 1 P 0 ;0,1=4,2=270.000000
L 6.0255 1.8569499 6.0255 1.87305 1 P 0 ;0,1=4,2=270.000000
L 5.87930039 1.47683317 5.88240069 1.4787501 1 P 0 ;0,1=5,2=270.000000
L 5.88240069 1.4787501 5.88446693 1.48104961 1 P 0 ;0,1=5,2=270.000000
L 5.88446693 1.48104961 5.8855 1.48373307 1 P 0 ;0,1=5,2=270.000000
L 5.8855 1.48373307 5.88446693 1.4867998 1 P 0 ;0,1=5,2=270.000000
L 5.88446693 1.4867998 5.88240069 1.4891 1 P 0 ;0,1=5,2=270.000000
L 5.88240069 1.4891 5.87930039 1.4914002 1 P 0 ;0,1=5,2=270.000000
L 5.87930039 1.4914002 5.87516703 1.49216673 1 P 0 ;0,1=5,2=270.000000
L 5.87516703 1.49216673 5.8545 1.49216673 1 P 0 ;0,1=5,2=270.000000
L 5.88085108 1.50706663 5.88343386 1.50936614 1 P 0 ;0,1=5,2=270.000000
L 5.88343386 1.50936614 5.88498346 1.51204961 1 P 0 ;0,1=5,2=270.000000
L 5.88498346 1.51204961 5.8855 1.51549961 1 P 0 ;0,1=5,2=270.000000
L 5.8855 1.51549961 5.88446693 1.5189503 1 P 0 ;0,1=5,2=270.000000
L 5.88446693 1.5189503 5.88240069 1.52163307 1 P 0 ;0,1=5,2=270.000000
L 5.88240069 1.52163307 5.87878386 1.52355 1 P 0 ;0,1=5,2=270.000000
L 5.87878386 1.52355 5.87465049 1.52393327 1 P 0 ;0,1=5,2=270.000000
L 5.87465049 1.52393327 5.87051713 1.52316673 1 P 0 ;0,1=5,2=270.000000
L 5.87051713 1.52316673 5.86793337 1.5212498 1 P 0 ;0,1=5,2=270.000000
L 5.86793337 1.5212498 5.86586713 1.51856634 1 P 0 ;0,1=5,2=270.000000
L 5.86586713 1.51856634 5.86535059 1.51588356 1 P 0 ;0,1=5,2=270.000000
L 5.86535059 1.51588356 5.86586713 1.5132001 1 P 0 ;0,1=5,2=270.000000
L 5.86586713 1.5132001 5.86793337 1.5097501 1 P 0 ;0,1=5,2=270.000000
L 5.86793337 1.5097501 5.8545 1.5108999 1 P 0 ;0,1=5,2=270.000000
L 5.8545 1.5108999 5.8545 1.5212498 1 P 0 ;0,1=5,2=270.000000
L 5.85949961 1.2395 5.85949961 1.2705 1 P 0 ;0,1=6,2=0.000000
L 5.85949961 1.2705 5.8548999 1.2643003 1 P 0 ;0,1=6,2=0.000000
L 5.8548999 1.2395 5.86409931 1.2395 1 P 0 ;0,1=6,2=0.000000
L 5.88321644 1.26533346 5.88551663 1.26843278 1 P 0 ;0,1=6,2=0.000000
L 5.88551663 1.26843278 5.8882001 1.26998337 1 P 0 ;0,1=6,2=0.000000
L 5.8882001 1.26998337 5.89126683 1.2705 1 P 0 ;0,1=6,2=0.000000
L 5.89126683 1.2705 5.8951 1.26946683 1 P 0 ;0,1=6,2=0.000000
L 5.8951 1.26946683 5.89778346 1.26688307 1 P 0 ;0,1=6,2=0.000000
L 5.89778346 1.26688307 5.89855 1.26378376 1 P 0 ;0,1=6,2=0.000000
L 5.89855 1.26378376 5.89816673 1.26068258 1 P 0 ;0,1=6,2=0.000000
L 5.89816673 1.26068258 5.89663307 1.2580998 1 P 0 ;0,1=6,2=0.000000
L 5.89663307 1.2580998 5.88896663 1.25293327 1 P 0 ;0,1=6,2=0.000000
L 5.88896663 1.25293327 5.88551663 1.24931644 1 P 0 ;0,1=6,2=0.000000
L 5.88551663 1.24931644 5.88321644 1.24414892 1 P 0 ;0,1=6,2=0.000000
L 5.88321644 1.24414892 5.8824499 1.2395 1 P 0 ;0,1=6,2=0.000000
L 5.8824499 1.2395 5.89855 1.2395 1 P 0 ;0,1=6,2=0.000000
L 0.51593996 3.54326004 0.51593996 3.28905 1 P 0 
L -0.08476004 3.54326004 0.51593996 3.54326004 1 P 0 
L 0.51593996 3.28905 -0.08476004 3.28905 1 P 0 
L -0.08476004 3.28905 -0.08476004 3.54326004 1 P 0 
L 0.14133317 3.56569961 0.1432501 3.56259931 1 P 0 ;0,1=7,2=0.000000
L 0.1432501 3.56259931 0.14554961 3.56053307 1 P 0 ;0,1=7,2=0.000000
L 0.14554961 3.56053307 0.14823307 3.5595 1 P 0 ;0,1=7,2=0.000000
L 0.14823307 3.5595 0.1512998 3.56053307 1 P 0 ;0,1=7,2=0.000000
L 0.1512998 3.56053307 0.1536 3.56259931 1 P 0 ;0,1=7,2=0.000000
L 0.1536 3.56259931 0.1559002 3.56569961 1 P 0 ;0,1=7,2=0.000000
L 0.1559002 3.56569961 0.15666673 3.56983297 1 P 0 ;0,1=7,2=0.000000
L 0.15666673 3.56983297 0.15666673 3.5905 1 P 0 ;0,1=7,2=0.000000
L 0.17999961 3.5595 0.17999961 3.5905 1 P 0 ;0,1=7,2=0.000000
L 0.17999961 3.5905 0.1753999 3.5843003 1 P 0 ;0,1=7,2=0.000000
L 0.1753999 3.5595 0.18459931 3.5595 1 P 0 ;0,1=7,2=0.000000
L 0.20256663 3.56569961 0.20486614 3.56208278 1 P 0 ;0,1=7,2=0.000000
L 0.20486614 3.56208278 0.20793287 3.56001654 1 P 0 ;0,1=7,2=0.000000
L 0.20793287 3.56001654 0.21138356 3.5595 1 P 0 ;0,1=7,2=0.000000
L 0.21138356 3.5595 0.2144503 3.56001654 1 P 0 ;0,1=7,2=0.000000
L 0.2144503 3.56001654 0.21751703 3.56259931 1 P 0 ;0,1=7,2=0.000000
L 0.21751703 3.56259931 0.21943327 3.56569961 1 P 0 ;0,1=7,2=0.000000
L 0.21943327 3.56569961 0.21981654 3.5687999 1 P 0 ;0,1=7,2=0.000000
L 0.21981654 3.5687999 0.21905 3.57241575 1 P 0 ;0,1=7,2=0.000000
L 0.21905 3.57241575 0.21636654 3.57499951 1 P 0 ;0,1=7,2=0.000000
L 0.21636654 3.57499951 0.21368307 3.57603356 1 P 0 ;0,1=7,2=0.000000
L 0.21368307 3.57603356 0.21023307 3.57603356 1 P 0 ;0,1=7,2=0.000000
L 0.21368307 3.57603356 0.21598327 3.57758317 1 P 0 ;0,1=7,2=0.000000
L 0.21598327 3.57758317 0.2179002 3.58016594 1 P 0 ;0,1=7,2=0.000000
L 0.2179002 3.58016594 0.21866673 3.58326624 1 P 0 ;0,1=7,2=0.000000
L 0.21866673 3.58326624 0.2179002 3.58636654 1 P 0 ;0,1=7,2=0.000000
L 0.2179002 3.58636654 0.21598327 3.58894931 1 P 0 ;0,1=7,2=0.000000
L 0.21598327 3.58894931 0.21253327 3.5905 1 P 0 ;0,1=7,2=0.000000
L 0.21253327 3.5905 0.20908337 3.58998337 1 P 0 ;0,1=7,2=0.000000
L 0.20908337 3.58998337 0.20563337 3.58791624 1 P 0 ;0,1=7,2=0.000000
L 4.03331004 3.5024 4.03331004 3.3836 1 P 0 
L 4.03331004 3.3836 3.92668996 3.3836 1 P 0 
L 3.92668996 3.3836 3.92668996 3.5024 1 P 0 
L 3.92668996 3.5024 4.03331004 3.5024 1 P 0 
S P 0
OB 4.034 3.528 I
OC 4.034 3.528 4.019 3.528 Y
OE
SE
L 4.03993317 3.35991594 4.0417999 3.36283346 1 P 0 ;0,1=8,2=0.000000
L 4.0417999 3.36283346 4.0434 3.3644998 1 P 0 ;0,1=8,2=0.000000
L 4.0434 3.3644998 4.04553337 3.36533297 1 P 0 ;0,1=8,2=0.000000
L 4.04553337 3.36533297 4.0474002 3.3644998 1 P 0 ;0,1=8,2=0.000000
L 4.0474002 3.3644998 4.04873327 3.36283346 1 P 0 ;0,1=8,2=0.000000
L 4.04873327 3.36283346 4.0498001 3.36033327 1 P 0 ;0,1=8,2=0.000000
L 4.0498001 3.36033327 4.05006673 3.35741644 1 P 0 ;0,1=8,2=0.000000
L 4.05006673 3.35741644 4.0498001 3.35491624 1 P 0 ;0,1=8,2=0.000000
L 4.0498001 3.35491624 4.04873327 3.35241604 1 P 0 ;0,1=8,2=0.000000
L 4.04873327 3.35241604 4.04713307 3.35033307 1 P 0 ;0,1=8,2=0.000000
L 4.04713307 3.35033307 4.04526683 3.3495 1 P 0 ;0,1=8,2=0.000000
L 4.04526683 3.3495 4.04313346 3.35033307 1 P 0 ;0,1=8,2=0.000000
L 4.04313346 3.35033307 4.04126663 3.35283258 1 P 0 ;0,1=8,2=0.000000
L 4.04126663 3.35283258 4.0401998 3.35658327 1 P 0 ;0,1=8,2=0.000000
L 4.0401998 3.35658327 4.03993317 3.3607498 1 P 0 ;0,1=8,2=0.000000
L 4.03993317 3.3607498 4.04046634 3.36616614 1 P 0 ;0,1=8,2=0.000000
L 4.04046634 3.36616614 4.04126663 3.36908366 1 P 0 ;0,1=8,2=0.000000
L 4.04126663 3.36908366 4.0425997 3.3719997 1 P 0 ;0,1=8,2=0.000000
L 4.0425997 3.3719997 4.04446654 3.37408337 1 P 0 ;0,1=8,2=0.000000
L 4.04446654 3.37408337 4.04633327 3.3745 1 P 0 ;0,1=8,2=0.000000
L 4.04633327 3.3745 4.0482 3.37366683 1 P 0 ;0,1=8,2=0.000000
L 4.0482 3.37366683 4.04953356 3.37158317 1 P 0 ;0,1=8,2=0.000000
L 3.8845 3.51056663 3.90671673 3.51056663 1 P 0 ;0,1=9,2=270.000000
L 3.90671673 3.51056663 3.91136762 3.5120997 1 P 0 ;0,1=9,2=270.000000
L 3.91136762 3.5120997 3.91446693 3.51516634 1 P 0 ;0,1=9,2=270.000000
L 3.91446693 3.51516634 3.9155 3.51899961 1 P 0 ;0,1=9,2=270.000000
L 3.9155 3.51899961 3.91446693 3.52283356 1 P 0 ;0,1=9,2=270.000000
L 3.91446693 3.52283356 3.91136762 3.5259002 1 P 0 ;0,1=9,2=270.000000
L 3.91136762 3.5259002 3.90671673 3.52743327 1 P 0 ;0,1=9,2=270.000000
L 3.90671673 3.52743327 3.8845 3.52743327 1 P 0 ;0,1=9,2=270.000000
L 3.90930039 3.54156663 3.91291722 3.54386614 1 P 0 ;0,1=9,2=270.000000
L 3.91291722 3.54386614 3.91498346 3.54693287 1 P 0 ;0,1=9,2=270.000000
L 3.91498346 3.54693287 3.9155 3.55038356 1 P 0 ;0,1=9,2=270.000000
L 3.9155 3.55038356 3.91498346 3.5534503 1 P 0 ;0,1=9,2=270.000000
L 3.91498346 3.5534503 3.91240069 3.55651703 1 P 0 ;0,1=9,2=270.000000
L 3.91240069 3.55651703 3.90930039 3.55843327 1 P 0 ;0,1=9,2=270.000000
L 3.90930039 3.55843327 3.9062001 3.55881654 1 P 0 ;0,1=9,2=270.000000
L 3.9062001 3.55881654 3.90258425 3.55805 1 P 0 ;0,1=9,2=270.000000
L 3.90258425 3.55805 3.90000049 3.55536654 1 P 0 ;0,1=9,2=270.000000
L 3.90000049 3.55536654 3.89896644 3.55268307 1 P 0 ;0,1=9,2=270.000000
L 3.89896644 3.55268307 3.89896644 3.54923307 1 P 0 ;0,1=9,2=270.000000
L 3.89896644 3.55268307 3.89741683 3.55498327 1 P 0 ;0,1=9,2=270.000000
L 3.89741683 3.55498327 3.89483406 3.5569002 1 P 0 ;0,1=9,2=270.000000
L 3.89483406 3.5569002 3.89173376 3.55766673 1 P 0 ;0,1=9,2=270.000000
L 3.89173376 3.55766673 3.88863346 3.5569002 1 P 0 ;0,1=9,2=270.000000
L 3.88863346 3.5569002 3.88605069 3.55498327 1 P 0 ;0,1=9,2=270.000000
L 3.88605069 3.55498327 3.8845 3.55153327 1 P 0 ;0,1=9,2=270.000000
L 3.8845 3.55153327 3.88501663 3.54808337 1 P 0 ;0,1=9,2=270.000000
L 3.88501663 3.54808337 3.88708376 3.54463337 1 P 0 ;0,1=9,2=270.000000
L 3.91188415 3.57448287 3.91446693 3.57716634 1 P 0 ;0,1=9,2=270.000000
L 3.91446693 3.57716634 3.9155 3.58023307 1 P 0 ;0,1=9,2=270.000000
L 3.9155 3.58023307 3.91446693 3.5832998 1 P 0 ;0,1=9,2=270.000000
L 3.91446693 3.5832998 3.91136762 3.58598327 1 P 0 ;0,1=9,2=270.000000
L 3.91136762 3.58598327 3.90671673 3.5879002 1 P 0 ;0,1=9,2=270.000000
L 3.90671673 3.5879002 3.90206673 3.58866673 1 P 0 ;0,1=9,2=270.000000
L 3.90206673 3.58866673 3.89638366 3.58866673 1 P 0 ;0,1=9,2=270.000000
L 3.89638366 3.58866673 3.89173376 3.5879002 1 P 0 ;0,1=9,2=270.000000
L 3.89173376 3.5879002 3.8876003 3.58598327 1 P 0 ;0,1=9,2=270.000000
L 3.8876003 3.58598327 3.88553317 3.58368307 1 P 0 ;0,1=9,2=270.000000
L 3.88553317 3.58368307 3.8845 3.58099961 1 P 0 ;0,1=9,2=270.000000
L 3.8845 3.58099961 3.88553317 3.57793287 1 P 0 ;0,1=9,2=270.000000
L 3.88553317 3.57793287 3.8876003 3.57563337 1 P 0 ;0,1=9,2=270.000000
L 3.8876003 3.57563337 3.8906997 3.5740997 1 P 0 ;0,1=9,2=270.000000
L 3.8906997 3.5740997 3.89483406 3.57333317 1 P 0 ;0,1=9,2=270.000000
L 3.89483406 3.57333317 3.8984499 3.5740997 1 P 0 ;0,1=9,2=270.000000
L 3.8984499 3.5740997 3.90206673 3.57601663 1 P 0 ;0,1=9,2=270.000000
L 3.90206673 3.57601663 3.90413396 3.57831683 1 P 0 ;0,1=9,2=270.000000
L 3.90413396 3.57831683 3.90465049 3.58099961 1 P 0 ;0,1=9,2=270.000000
L 3.90465049 3.58099961 3.90361732 3.58406634 1 P 0 ;0,1=9,2=270.000000
L 3.90361732 3.58406634 3.90103366 3.58636654 1 P 0 ;0,1=9,2=270.000000
L 3.90103366 3.58636654 3.89638366 3.58866673 1 P 0 ;0,1=9,2=270.000000
L 3.90413327 3.46949961 3.90573297 3.46658287 1 P 0 ;0,1=10,2=0.000000
L 3.90573297 3.46658287 3.90786634 3.46491654 1 P 0 ;0,1=10,2=0.000000
L 3.90786634 3.46491654 3.91026683 3.4645 1 P 0 ;0,1=10,2=0.000000
L 3.91026683 3.4645 3.9124002 3.46491654 1 P 0 ;0,1=10,2=0.000000
L 3.9124002 3.46491654 3.91453356 3.46699941 1 P 0 ;0,1=10,2=0.000000
L 3.91453356 3.46699941 3.91586663 3.46949961 1 P 0 ;0,1=10,2=0.000000
L 3.91586663 3.46949961 3.91613317 3.4719999 1 P 0 ;0,1=10,2=0.000000
L 3.91613317 3.4719999 3.9156 3.47491594 1 P 0 ;0,1=10,2=0.000000
L 3.9156 3.47491594 3.91373327 3.47699961 1 P 0 ;0,1=10,2=0.000000
L 3.91373327 3.47699961 3.91186644 3.47783346 1 P 0 ;0,1=10,2=0.000000
L 3.91186644 3.47783346 3.90946654 3.47783346 1 P 0 ;0,1=10,2=0.000000
L 3.91186644 3.47783346 3.91346663 3.47908327 1 P 0 ;0,1=10,2=0.000000
L 3.91346663 3.47908327 3.9148001 3.48116614 1 P 0 ;0,1=10,2=0.000000
L 3.9148001 3.48116614 3.91533337 3.48366634 1 P 0 ;0,1=10,2=0.000000
L 3.91533337 3.48366634 3.9148001 3.48616654 1 P 0 ;0,1=10,2=0.000000
L 3.9148001 3.48616654 3.91346663 3.48824941 1 P 0 ;0,1=10,2=0.000000
L 3.91346663 3.48824941 3.91106663 3.4895 1 P 0 ;0,1=10,2=0.000000
L 3.91106663 3.4895 3.90866663 3.48908337 1 P 0 ;0,1=10,2=0.000000
L 3.90866663 3.48908337 3.90626663 3.48741634 1 P 0 ;0,1=10,2=0.000000
L 3.9182 3.3495 3.9182 3.3745 1 P 0 ;0,1=11,2=0.000000
L 3.9182 3.3745 3.90833297 3.35658327 1 P 0 ;0,1=11,2=0.000000
L 3.90833297 3.35658327 3.92166693 3.35658327 1 P 0 ;0,1=11,2=0.000000
L 4.22831004 3.5044 4.22831004 3.3856 1 P 0 
L 4.12168996 3.5044 4.22831004 3.5044 1 P 0 
L 4.12168996 3.3856 4.12168996 3.5044 1 P 0 
L 4.22831004 3.3856 4.12168996 3.3856 1 P 0 
S P 0
OB 4.26 3.52 I
OC 4.26 3.52 4.245 3.52 Y
OE
SE
L 4.21993317 3.36291594 4.2217999 3.36583346 1 P 0 ;0,1=8,2=0.000000
L 4.2217999 3.36583346 4.2234 3.3674998 1 P 0 ;0,1=8,2=0.000000
L 4.2234 3.3674998 4.22553337 3.36833297 1 P 0 ;0,1=8,2=0.000000
L 4.22553337 3.36833297 4.2274002 3.3674998 1 P 0 ;0,1=8,2=0.000000
L 4.2274002 3.3674998 4.22873327 3.36583346 1 P 0 ;0,1=8,2=0.000000
L 4.22873327 3.36583346 4.2298001 3.36333327 1 P 0 ;0,1=8,2=0.000000
L 4.2298001 3.36333327 4.23006673 3.36041644 1 P 0 ;0,1=8,2=0.000000
L 4.23006673 3.36041644 4.2298001 3.35791624 1 P 0 ;0,1=8,2=0.000000
L 4.2298001 3.35791624 4.22873327 3.35541604 1 P 0 ;0,1=8,2=0.000000
L 4.22873327 3.35541604 4.22713307 3.35333307 1 P 0 ;0,1=8,2=0.000000
L 4.22713307 3.35333307 4.22526683 3.3525 1 P 0 ;0,1=8,2=0.000000
L 4.22526683 3.3525 4.22313346 3.35333307 1 P 0 ;0,1=8,2=0.000000
L 4.22313346 3.35333307 4.22126663 3.35583258 1 P 0 ;0,1=8,2=0.000000
L 4.22126663 3.35583258 4.2201998 3.35958327 1 P 0 ;0,1=8,2=0.000000
L 4.2201998 3.35958327 4.21993317 3.3637498 1 P 0 ;0,1=8,2=0.000000
L 4.21993317 3.3637498 4.22046634 3.36916614 1 P 0 ;0,1=8,2=0.000000
L 4.22046634 3.36916614 4.22126663 3.37208366 1 P 0 ;0,1=8,2=0.000000
L 4.22126663 3.37208366 4.2225997 3.3749997 1 P 0 ;0,1=8,2=0.000000
L 4.2225997 3.3749997 4.22446654 3.37708337 1 P 0 ;0,1=8,2=0.000000
L 4.22446654 3.37708337 4.22633327 3.3775 1 P 0 ;0,1=8,2=0.000000
L 4.22633327 3.3775 4.2282 3.37666683 1 P 0 ;0,1=8,2=0.000000
L 4.2282 3.37666683 4.22953356 3.37458317 1 P 0 ;0,1=8,2=0.000000
L 4.2845 3.34056663 4.30671673 3.34056663 1 P 0 ;0,1=12,2=270.000000
L 4.30671673 3.34056663 4.31136762 3.3420997 1 P 0 ;0,1=12,2=270.000000
L 4.31136762 3.3420997 4.31446693 3.34516634 1 P 0 ;0,1=12,2=270.000000
L 4.31446693 3.34516634 4.3155 3.34899961 1 P 0 ;0,1=12,2=270.000000
L 4.3155 3.34899961 4.31446693 3.35283356 1 P 0 ;0,1=12,2=270.000000
L 4.31446693 3.35283356 4.31136762 3.3559002 1 P 0 ;0,1=12,2=270.000000
L 4.31136762 3.3559002 4.30671673 3.35743327 1 P 0 ;0,1=12,2=270.000000
L 4.30671673 3.35743327 4.2845 3.35743327 1 P 0 ;0,1=12,2=270.000000
L 4.3155 3.3846 4.2845 3.3846 1 P 0 ;0,1=12,2=270.000000
L 4.2845 3.3846 4.30671673 3.37041624 1 P 0 ;0,1=12,2=270.000000
L 4.30671673 3.37041624 4.30671673 3.38958366 1 P 0 ;0,1=12,2=270.000000
L 4.2845 3.41099961 4.28553317 3.40793287 1 P 0 ;0,1=12,2=270.000000
L 4.28553317 3.40793287 4.28811693 3.40563337 1 P 0 ;0,1=12,2=270.000000
L 4.28811693 3.40563337 4.29121624 3.4040997 1 P 0 ;0,1=12,2=270.000000
L 4.29121624 3.4040997 4.29535059 3.4029499 1 P 0 ;0,1=12,2=270.000000
L 4.29535059 3.4029499 4.30000049 3.40256663 1 P 0 ;0,1=12,2=270.000000
L 4.30000049 3.40256663 4.30465049 3.4029499 1 P 0 ;0,1=12,2=270.000000
L 4.30465049 3.4029499 4.30878386 3.4040997 1 P 0 ;0,1=12,2=270.000000
L 4.30878386 3.4040997 4.31188415 3.40563337 1 P 0 ;0,1=12,2=270.000000
L 4.31188415 3.40563337 4.31446693 3.40793287 1 P 0 ;0,1=12,2=270.000000
L 4.31446693 3.40793287 4.3155 3.41099961 1 P 0 ;0,1=12,2=270.000000
L 4.3155 3.41099961 4.31446693 3.41406634 1 P 0 ;0,1=12,2=270.000000
L 4.31446693 3.41406634 4.31188415 3.41636654 1 P 0 ;0,1=12,2=270.000000
L 4.31188415 3.41636654 4.30878386 3.4179002 1 P 0 ;0,1=12,2=270.000000
L 4.30878386 3.4179002 4.30465049 3.41905 1 P 0 ;0,1=12,2=270.000000
L 4.30465049 3.41905 4.30000049 3.41943327 1 P 0 ;0,1=12,2=270.000000
L 4.30000049 3.41943327 4.29535059 3.41905 1 P 0 ;0,1=12,2=270.000000
L 4.29535059 3.41905 4.29121624 3.4179002 1 P 0 ;0,1=12,2=270.000000
L 4.29121624 3.4179002 4.28811693 3.41636654 1 P 0 ;0,1=12,2=270.000000
L 4.28811693 3.41636654 4.28553317 3.41406634 1 P 0 ;0,1=12,2=270.000000
L 4.28553317 3.41406634 4.2845 3.41099961 1 P 0 ;0,1=12,2=270.000000
L 4.12413327 3.51749961 4.12573297 3.51458287 1 P 0 ;0,1=10,2=0.000000
L 4.12573297 3.51458287 4.12786634 3.51291654 1 P 0 ;0,1=10,2=0.000000
L 4.12786634 3.51291654 4.13026683 3.5125 1 P 0 ;0,1=10,2=0.000000
L 4.13026683 3.5125 4.1324002 3.51291654 1 P 0 ;0,1=10,2=0.000000
L 4.1324002 3.51291654 4.13453356 3.51499941 1 P 0 ;0,1=10,2=0.000000
L 4.13453356 3.51499941 4.13586663 3.51749961 1 P 0 ;0,1=10,2=0.000000
L 4.13586663 3.51749961 4.13613317 3.5199999 1 P 0 ;0,1=10,2=0.000000
L 4.13613317 3.5199999 4.1356 3.52291594 1 P 0 ;0,1=10,2=0.000000
L 4.1356 3.52291594 4.13373327 3.52499961 1 P 0 ;0,1=10,2=0.000000
L 4.13373327 3.52499961 4.13186644 3.52583346 1 P 0 ;0,1=10,2=0.000000
L 4.13186644 3.52583346 4.12946654 3.52583346 1 P 0 ;0,1=10,2=0.000000
L 4.13186644 3.52583346 4.13346663 3.52708327 1 P 0 ;0,1=10,2=0.000000
L 4.13346663 3.52708327 4.1348001 3.52916614 1 P 0 ;0,1=10,2=0.000000
L 4.1348001 3.52916614 4.13533337 3.53166634 1 P 0 ;0,1=10,2=0.000000
L 4.13533337 3.53166634 4.1348001 3.53416654 1 P 0 ;0,1=10,2=0.000000
L 4.1348001 3.53416654 4.13346663 3.53624941 1 P 0 ;0,1=10,2=0.000000
L 4.13346663 3.53624941 4.13106663 3.5375 1 P 0 ;0,1=10,2=0.000000
L 4.13106663 3.5375 4.12866663 3.53708337 1 P 0 ;0,1=10,2=0.000000
L 4.12866663 3.53708337 4.12626663 3.53541634 1 P 0 ;0,1=10,2=0.000000
L 4.1282 3.3525 4.1282 3.3775 1 P 0 ;0,1=11,2=0.000000
L 4.1282 3.3775 4.11833297 3.35958327 1 P 0 ;0,1=11,2=0.000000
L 4.11833297 3.35958327 4.13166693 3.35958327 1 P 0 ;0,1=11,2=0.000000
L 5.1655 0.9385 5.1655 0.7215 1 P 0 
L 4.8445 0.9385 5.1655 0.9385 1 P 0 
L 5.1655 0.7215 4.8445 0.7215 1 P 0 
L 4.8445 0.7215 4.8445 0.9385 1 P 0 
S P 0
OB 4.85 0.955 I
OC 4.85 0.955 4.835 0.955 Y
OE
SE
L 5.14949961 0.9595 5.14949961 0.9905 1 P 0 ;0,1=13,2=0.000000
L 5.14949961 0.9905 5.1448999 0.9843003 1 P 0 ;0,1=13,2=0.000000
L 5.1448999 0.9595 5.15409931 0.9595 1 P 0 ;0,1=13,2=0.000000
L 5.17321644 0.97241575 5.1758999 0.97603356 1 P 0 ;0,1=13,2=0.000000
L 5.1758999 0.97603356 5.1782001 0.9780998 1 P 0 ;0,1=13,2=0.000000
L 5.1782001 0.9780998 5.18126683 0.97913287 1 P 0 ;0,1=13,2=0.000000
L 5.18126683 0.97913287 5.1839503 0.9780998 1 P 0 ;0,1=13,2=0.000000
L 5.1839503 0.9780998 5.18586654 0.97603356 1 P 0 ;0,1=13,2=0.000000
L 5.18586654 0.97603356 5.1874002 0.97293327 1 P 0 ;0,1=13,2=0.000000
L 5.1874002 0.97293327 5.18778346 0.96931644 1 P 0 ;0,1=13,2=0.000000
L 5.18778346 0.96931644 5.1874002 0.96621614 1 P 0 ;0,1=13,2=0.000000
L 5.1874002 0.96621614 5.18586654 0.96311585 1 P 0 ;0,1=13,2=0.000000
L 5.18586654 0.96311585 5.18356634 0.96053307 1 P 0 ;0,1=13,2=0.000000
L 5.18356634 0.96053307 5.18088356 0.9595 1 P 0 ;0,1=13,2=0.000000
L 5.18088356 0.9595 5.17781683 0.96053307 1 P 0 ;0,1=13,2=0.000000
L 5.17781683 0.96053307 5.17513337 0.96363238 1 P 0 ;0,1=13,2=0.000000
L 5.17513337 0.96363238 5.1735997 0.96828327 1 P 0 ;0,1=13,2=0.000000
L 5.1735997 0.96828327 5.17321644 0.9734498 1 P 0 ;0,1=13,2=0.000000
L 5.17321644 0.9734498 5.17398287 0.98016594 1 P 0 ;0,1=13,2=0.000000
L 5.17398287 0.98016594 5.17513337 0.98378376 1 P 0 ;0,1=13,2=0.000000
L 5.17513337 0.98378376 5.17704961 0.9873997 1 P 0 ;0,1=13,2=0.000000
L 5.17704961 0.9873997 5.17973307 0.98998337 1 P 0 ;0,1=13,2=0.000000
L 5.17973307 0.98998337 5.18241654 0.9905 1 P 0 ;0,1=13,2=0.000000
L 5.18241654 0.9905 5.1851 0.98946683 1 P 0 ;0,1=13,2=0.000000
L 5.1851 0.98946683 5.18701703 0.98688307 1 P 0 ;0,1=13,2=0.000000
L 5.18348287 0.70311585 5.18616634 0.70053307 1 P 0 ;0,1=14,2=0.000000
L 5.18616634 0.70053307 5.18923307 0.6995 1 P 0 ;0,1=14,2=0.000000
L 5.18923307 0.6995 5.1922998 0.70053307 1 P 0 ;0,1=14,2=0.000000
L 5.1922998 0.70053307 5.19498327 0.70363238 1 P 0 ;0,1=14,2=0.000000
L 5.19498327 0.70363238 5.1969002 0.70828327 1 P 0 ;0,1=14,2=0.000000
L 5.1969002 0.70828327 5.19766673 0.71293327 1 P 0 ;0,1=14,2=0.000000
L 5.19766673 0.71293327 5.19766673 0.71861634 1 P 0 ;0,1=14,2=0.000000
L 5.19766673 0.71861634 5.1969002 0.72326624 1 P 0 ;0,1=14,2=0.000000
L 5.1969002 0.72326624 5.19498327 0.7273997 1 P 0 ;0,1=14,2=0.000000
L 5.19498327 0.7273997 5.19268307 0.72946683 1 P 0 ;0,1=14,2=0.000000
L 5.19268307 0.72946683 5.18999961 0.7305 1 P 0 ;0,1=14,2=0.000000
L 5.18999961 0.7305 5.18693287 0.72946683 1 P 0 ;0,1=14,2=0.000000
L 5.18693287 0.72946683 5.18463337 0.7273997 1 P 0 ;0,1=14,2=0.000000
L 5.18463337 0.7273997 5.1830997 0.7243003 1 P 0 ;0,1=14,2=0.000000
L 5.1830997 0.7243003 5.18233317 0.72016594 1 P 0 ;0,1=14,2=0.000000
L 5.18233317 0.72016594 5.1830997 0.7165501 1 P 0 ;0,1=14,2=0.000000
L 5.1830997 0.7165501 5.18501663 0.71293327 1 P 0 ;0,1=14,2=0.000000
L 5.18501663 0.71293327 5.18731683 0.71086604 1 P 0 ;0,1=14,2=0.000000
L 5.18731683 0.71086604 5.18999961 0.71034951 1 P 0 ;0,1=14,2=0.000000
L 5.18999961 0.71034951 5.19306634 0.71138268 1 P 0 ;0,1=14,2=0.000000
L 5.19306634 0.71138268 5.19536654 0.71396634 1 P 0 ;0,1=14,2=0.000000
L 5.19536654 0.71396634 5.19766673 0.71861634 1 P 0 ;0,1=14,2=0.000000
L 4.93056663 0.9905 4.93056663 0.96828327 1 P 0 ;0,1=15,2=0.000000
L 4.93056663 0.96828327 4.9320997 0.96363238 1 P 0 ;0,1=15,2=0.000000
L 4.9320997 0.96363238 4.93516634 0.96053307 1 P 0 ;0,1=15,2=0.000000
L 4.93516634 0.96053307 4.93899961 0.9595 1 P 0 ;0,1=15,2=0.000000
L 4.93899961 0.9595 4.94283356 0.96053307 1 P 0 ;0,1=15,2=0.000000
L 4.94283356 0.96053307 4.9459002 0.96363238 1 P 0 ;0,1=15,2=0.000000
L 4.9459002 0.96363238 4.94743327 0.96828327 1 P 0 ;0,1=15,2=0.000000
L 4.94743327 0.96828327 4.94743327 0.9905 1 P 0 ;0,1=15,2=0.000000
L 4.96156663 0.96569961 4.96386614 0.96208278 1 P 0 ;0,1=15,2=0.000000
L 4.96386614 0.96208278 4.96693287 0.96001654 1 P 0 ;0,1=15,2=0.000000
L 4.96693287 0.96001654 4.97038356 0.9595 1 P 0 ;0,1=15,2=0.000000
L 4.97038356 0.9595 4.9734503 0.96001654 1 P 0 ;0,1=15,2=0.000000
L 4.9734503 0.96001654 4.97651703 0.96259931 1 P 0 ;0,1=15,2=0.000000
L 4.97651703 0.96259931 4.97843327 0.96569961 1 P 0 ;0,1=15,2=0.000000
L 4.97843327 0.96569961 4.97881654 0.9687999 1 P 0 ;0,1=15,2=0.000000
L 4.97881654 0.9687999 4.97805 0.97241575 1 P 0 ;0,1=15,2=0.000000
L 4.97805 0.97241575 4.97536654 0.97499951 1 P 0 ;0,1=15,2=0.000000
L 4.97536654 0.97499951 4.97268307 0.97603356 1 P 0 ;0,1=15,2=0.000000
L 4.97268307 0.97603356 4.96923307 0.97603356 1 P 0 ;0,1=15,2=0.000000
L 4.97268307 0.97603356 4.97498327 0.97758317 1 P 0 ;0,1=15,2=0.000000
L 4.97498327 0.97758317 4.9769002 0.98016594 1 P 0 ;0,1=15,2=0.000000
L 4.9769002 0.98016594 4.97766673 0.98326624 1 P 0 ;0,1=15,2=0.000000
L 4.97766673 0.98326624 4.9769002 0.98636654 1 P 0 ;0,1=15,2=0.000000
L 4.9769002 0.98636654 4.97498327 0.98894931 1 P 0 ;0,1=15,2=0.000000
L 4.97498327 0.98894931 4.97153327 0.9905 1 P 0 ;0,1=15,2=0.000000
L 4.97153327 0.9905 4.96808337 0.98998337 1 P 0 ;0,1=15,2=0.000000
L 4.96808337 0.98998337 4.96463337 0.98791624 1 P 0 ;0,1=15,2=0.000000
L 5.00023307 0.9595 5.00099961 0.96621614 1 P 0 ;0,1=15,2=0.000000
L 5.00099961 0.96621614 5.0021501 0.97189921 1 P 0 ;0,1=15,2=0.000000
L 5.0021501 0.97189921 5.00368307 0.97706663 1 P 0 ;0,1=15,2=0.000000
L 5.00368307 0.97706663 5.0056 0.9827497 1 P 0 ;0,1=15,2=0.000000
L 5.0056 0.9827497 5.00866673 0.9905 1 P 0 ;0,1=15,2=0.000000
L 5.00866673 0.9905 4.99333317 0.9905 1 P 0 ;0,1=15,2=0.000000
L 4.82499961 0.73 4.82768307 0.73051654 1 P 0 ;0,1=16,2=0.000000
L 4.82768307 0.73051654 4.8307498 0.73206614 1 P 0 ;0,1=16,2=0.000000
L 4.8307498 0.73206614 4.83266673 0.73464892 1 P 0 ;0,1=16,2=0.000000
L 4.83266673 0.73464892 4.83343327 0.73826673 1 P 0 ;0,1=16,2=0.000000
L 4.83343327 0.73826673 4.83266673 0.74188268 1 P 0 ;0,1=16,2=0.000000
L 4.83266673 0.74188268 4.83036654 0.74498287 1 P 0 ;0,1=16,2=0.000000
L 4.83036654 0.74498287 4.82691654 0.74653356 1 P 0 ;0,1=16,2=0.000000
L 4.82691654 0.74653356 4.82308337 0.74653356 1 P 0 ;0,1=16,2=0.000000
L 4.82308337 0.74653356 4.82078317 0.74756663 1 P 0 ;0,1=16,2=0.000000
L 4.82078317 0.74756663 4.81886614 0.75014941 1 P 0 ;0,1=16,2=0.000000
L 4.81886614 0.75014941 4.8180997 0.75376624 1 P 0 ;0,1=16,2=0.000000
L 4.8180997 0.75376624 4.8192501 0.75738307 1 P 0 ;0,1=16,2=0.000000
L 4.8192501 0.75738307 4.82193287 0.75996683 1 P 0 ;0,1=16,2=0.000000
L 4.82193287 0.75996683 4.82499961 0.761 1 P 0 ;0,1=16,2=0.000000
L 4.82499961 0.761 4.82806634 0.75996683 1 P 0 ;0,1=16,2=0.000000
L 4.82806634 0.75996683 4.8307498 0.75738307 1 P 0 ;0,1=16,2=0.000000
L 4.8307498 0.75738307 4.8319002 0.75376624 1 P 0 ;0,1=16,2=0.000000
L 4.8319002 0.75376624 4.83113307 0.75014941 1 P 0 ;0,1=16,2=0.000000
L 4.83113307 0.75014941 4.82921673 0.74756663 1 P 0 ;0,1=16,2=0.000000
L 4.82921673 0.74756663 4.82691654 0.74653356 1 P 0 ;0,1=16,2=0.000000
L 4.82691654 0.74653356 4.82308337 0.74653356 1 P 0 ;0,1=16,2=0.000000
L 4.82308337 0.74653356 4.81963337 0.74498287 1 P 0 ;0,1=16,2=0.000000
L 4.81963337 0.74498287 4.81733317 0.74188268 1 P 0 ;0,1=16,2=0.000000
L 4.81733317 0.74188268 4.81656663 0.73826673 1 P 0 ;0,1=16,2=0.000000
L 4.81656663 0.73826673 4.81733317 0.73464892 1 P 0 ;0,1=16,2=0.000000
L 4.81733317 0.73464892 4.8192501 0.73206614 1 P 0 ;0,1=16,2=0.000000
L 4.8192501 0.73206614 4.82231683 0.73051654 1 P 0 ;0,1=16,2=0.000000
L 4.82231683 0.73051654 4.82499961 0.73 1 P 0 ;0,1=16,2=0.000000
L 4.4495 3.2645 4.4495 3.0475 1 P 0 
L 4.1285 3.2645 4.4495 3.2645 1 P 0 
L 4.4495 3.0475 4.1285 3.0475 1 P 0 
L 4.1285 3.0475 4.1285 3.2645 1 P 0 
S P 0
OB 4.145 3.285 I
OC 4.145 3.285 4.13 3.285 Y
OE
SE
L 4.4775 3.2489997 4.4525 3.2489997 1 P 0 ;0,1=13,2=270.000000
L 4.4525 3.2489997 4.4574997 3.2457999 1 P 0 ;0,1=13,2=270.000000
L 4.4775 3.2457999 4.4775 3.25219951 1 P 0 ;0,1=13,2=270.000000
L 4.46708406 3.26593317 4.46416654 3.2677999 1 P 0 ;0,1=13,2=270.000000
L 4.46416654 3.2677999 4.4625002 3.2694 1 P 0 ;0,1=13,2=270.000000
L 4.4625002 3.2694 4.46166703 3.27153337 1 P 0 ;0,1=13,2=270.000000
L 4.46166703 3.27153337 4.4625002 3.2734002 1 P 0 ;0,1=13,2=270.000000
L 4.4625002 3.2734002 4.46416654 3.27473327 1 P 0 ;0,1=13,2=270.000000
L 4.46416654 3.27473327 4.46666673 3.2758001 1 P 0 ;0,1=13,2=270.000000
L 4.46666673 3.2758001 4.46958356 3.27606673 1 P 0 ;0,1=13,2=270.000000
L 4.46958356 3.27606673 4.47208376 3.2758001 1 P 0 ;0,1=13,2=270.000000
L 4.47208376 3.2758001 4.47458396 3.27473327 1 P 0 ;0,1=13,2=270.000000
L 4.47458396 3.27473327 4.47666693 3.27313307 1 P 0 ;0,1=13,2=270.000000
L 4.47666693 3.27313307 4.4775 3.27126683 1 P 0 ;0,1=13,2=270.000000
L 4.4775 3.27126683 4.47666693 3.26913346 1 P 0 ;0,1=13,2=270.000000
L 4.47666693 3.26913346 4.47416742 3.26726663 1 P 0 ;0,1=13,2=270.000000
L 4.47416742 3.26726663 4.47041673 3.2661998 1 P 0 ;0,1=13,2=270.000000
L 4.47041673 3.2661998 4.4662502 3.26593317 1 P 0 ;0,1=13,2=270.000000
L 4.4662502 3.26593317 4.46083386 3.26646634 1 P 0 ;0,1=13,2=270.000000
L 4.46083386 3.26646634 4.45791634 3.26726663 1 P 0 ;0,1=13,2=270.000000
L 4.45791634 3.26726663 4.4550003 3.2685997 1 P 0 ;0,1=13,2=270.000000
L 4.4550003 3.2685997 4.45291663 3.27046654 1 P 0 ;0,1=13,2=270.000000
L 4.45291663 3.27046654 4.4525 3.27233327 1 P 0 ;0,1=13,2=270.000000
L 4.4525 3.27233327 4.45333317 3.2742 1 P 0 ;0,1=13,2=270.000000
L 4.45333317 3.2742 4.45541683 3.27553356 1 P 0 ;0,1=13,2=270.000000
L 4.46346634 3.05391604 4.46533317 3.05183307 1 P 0 ;0,1=14,2=0.000000
L 4.46533317 3.05183307 4.46746654 3.051 1 P 0 ;0,1=14,2=0.000000
L 4.46746654 3.051 4.4695999 3.05183307 1 P 0 ;0,1=14,2=0.000000
L 4.4695999 3.05183307 4.47146663 3.05433258 1 P 0 ;0,1=14,2=0.000000
L 4.47146663 3.05433258 4.4728001 3.05808327 1 P 0 ;0,1=14,2=0.000000
L 4.4728001 3.05808327 4.47333337 3.06183327 1 P 0 ;0,1=14,2=0.000000
L 4.47333337 3.06183327 4.47333337 3.06641634 1 P 0 ;0,1=14,2=0.000000
L 4.47333337 3.06641634 4.4728001 3.07016634 1 P 0 ;0,1=14,2=0.000000
L 4.4728001 3.07016634 4.47146663 3.0734997 1 P 0 ;0,1=14,2=0.000000
L 4.47146663 3.0734997 4.46986644 3.07516683 1 P 0 ;0,1=14,2=0.000000
L 4.46986644 3.07516683 4.4679997 3.076 1 P 0 ;0,1=14,2=0.000000
L 4.4679997 3.076 4.46586634 3.07516683 1 P 0 ;0,1=14,2=0.000000
L 4.46586634 3.07516683 4.46426663 3.0734997 1 P 0 ;0,1=14,2=0.000000
L 4.46426663 3.0734997 4.4631998 3.0710003 1 P 0 ;0,1=14,2=0.000000
L 4.4631998 3.0710003 4.46266654 3.06766614 1 P 0 ;0,1=14,2=0.000000
L 4.46266654 3.06766614 4.4631998 3.0647501 1 P 0 ;0,1=14,2=0.000000
L 4.4631998 3.0647501 4.46453327 3.06183327 1 P 0 ;0,1=14,2=0.000000
L 4.46453327 3.06183327 4.46613346 3.06016614 1 P 0 ;0,1=14,2=0.000000
L 4.46613346 3.06016614 4.4679997 3.05974961 1 P 0 ;0,1=14,2=0.000000
L 4.4679997 3.05974961 4.47013307 3.06058278 1 P 0 ;0,1=14,2=0.000000
L 4.47013307 3.06058278 4.47173327 3.06266644 1 P 0 ;0,1=14,2=0.000000
L 4.47173327 3.06266644 4.47333337 3.06641634 1 P 0 ;0,1=14,2=0.000000
L 4.22056663 3.0355 4.22056663 3.01328327 1 P 0 ;0,1=17,2=0.000000
L 4.22056663 3.01328327 4.2220997 3.00863238 1 P 0 ;0,1=17,2=0.000000
L 4.2220997 3.00863238 4.22516634 3.00553307 1 P 0 ;0,1=17,2=0.000000
L 4.22516634 3.00553307 4.22899961 3.0045 1 P 0 ;0,1=17,2=0.000000
L 4.22899961 3.0045 4.23283356 3.00553307 1 P 0 ;0,1=17,2=0.000000
L 4.23283356 3.00553307 4.2359002 3.00863238 1 P 0 ;0,1=17,2=0.000000
L 4.2359002 3.00863238 4.23743327 3.01328327 1 P 0 ;0,1=17,2=0.000000
L 4.23743327 3.01328327 4.23743327 3.0355 1 P 0 ;0,1=17,2=0.000000
L 4.25156663 3.01069961 4.25386614 3.00708278 1 P 0 ;0,1=17,2=0.000000
L 4.25386614 3.00708278 4.25693287 3.00501654 1 P 0 ;0,1=17,2=0.000000
L 4.25693287 3.00501654 4.26038356 3.0045 1 P 0 ;0,1=17,2=0.000000
L 4.26038356 3.0045 4.2634503 3.00501654 1 P 0 ;0,1=17,2=0.000000
L 4.2634503 3.00501654 4.26651703 3.00759931 1 P 0 ;0,1=17,2=0.000000
L 4.26651703 3.00759931 4.26843327 3.01069961 1 P 0 ;0,1=17,2=0.000000
L 4.26843327 3.01069961 4.26881654 3.0137999 1 P 0 ;0,1=17,2=0.000000
L 4.26881654 3.0137999 4.26805 3.01741575 1 P 0 ;0,1=17,2=0.000000
L 4.26805 3.01741575 4.26536654 3.01999951 1 P 0 ;0,1=17,2=0.000000
L 4.26536654 3.01999951 4.26268307 3.02103356 1 P 0 ;0,1=17,2=0.000000
L 4.26268307 3.02103356 4.25923307 3.02103356 1 P 0 ;0,1=17,2=0.000000
L 4.26268307 3.02103356 4.26498327 3.02258317 1 P 0 ;0,1=17,2=0.000000
L 4.26498327 3.02258317 4.2669002 3.02516594 1 P 0 ;0,1=17,2=0.000000
L 4.2669002 3.02516594 4.26766673 3.02826624 1 P 0 ;0,1=17,2=0.000000
L 4.26766673 3.02826624 4.2669002 3.03136654 1 P 0 ;0,1=17,2=0.000000
L 4.2669002 3.03136654 4.26498327 3.03394931 1 P 0 ;0,1=17,2=0.000000
L 4.26498327 3.03394931 4.26153327 3.0355 1 P 0 ;0,1=17,2=0.000000
L 4.26153327 3.0355 4.25808337 3.03498337 1 P 0 ;0,1=17,2=0.000000
L 4.25808337 3.03498337 4.25463337 3.03291624 1 P 0 ;0,1=17,2=0.000000
L 4.29099961 3.0045 4.29368307 3.00501654 1 P 0 ;0,1=17,2=0.000000
L 4.29368307 3.00501654 4.2967498 3.00656614 1 P 0 ;0,1=17,2=0.000000
L 4.2967498 3.00656614 4.29866673 3.00914892 1 P 0 ;0,1=17,2=0.000000
L 4.29866673 3.00914892 4.29943327 3.01276673 1 P 0 ;0,1=17,2=0.000000
L 4.29943327 3.01276673 4.29866673 3.01638268 1 P 0 ;0,1=17,2=0.000000
L 4.29866673 3.01638268 4.29636654 3.01948287 1 P 0 ;0,1=17,2=0.000000
L 4.29636654 3.01948287 4.29291654 3.02103356 1 P 0 ;0,1=17,2=0.000000
L 4.29291654 3.02103356 4.28908337 3.02103356 1 P 0 ;0,1=17,2=0.000000
L 4.28908337 3.02103356 4.28678317 3.02206663 1 P 0 ;0,1=17,2=0.000000
L 4.28678317 3.02206663 4.28486614 3.02464941 1 P 0 ;0,1=17,2=0.000000
L 4.28486614 3.02464941 4.2840997 3.02826624 1 P 0 ;0,1=17,2=0.000000
L 4.2840997 3.02826624 4.2852501 3.03188307 1 P 0 ;0,1=17,2=0.000000
L 4.2852501 3.03188307 4.28793287 3.03446683 1 P 0 ;0,1=17,2=0.000000
L 4.28793287 3.03446683 4.29099961 3.0355 1 P 0 ;0,1=17,2=0.000000
L 4.29099961 3.0355 4.29406634 3.03446683 1 P 0 ;0,1=17,2=0.000000
L 4.29406634 3.03446683 4.2967498 3.03188307 1 P 0 ;0,1=17,2=0.000000
L 4.2967498 3.03188307 4.2979002 3.02826624 1 P 0 ;0,1=17,2=0.000000
L 4.2979002 3.02826624 4.29713307 3.02464941 1 P 0 ;0,1=17,2=0.000000
L 4.29713307 3.02464941 4.29521673 3.02206663 1 P 0 ;0,1=17,2=0.000000
L 4.29521673 3.02206663 4.29291654 3.02103356 1 P 0 ;0,1=17,2=0.000000
L 4.29291654 3.02103356 4.28908337 3.02103356 1 P 0 ;0,1=17,2=0.000000
L 4.28908337 3.02103356 4.28563337 3.01948287 1 P 0 ;0,1=17,2=0.000000
L 4.28563337 3.01948287 4.28333317 3.01638268 1 P 0 ;0,1=17,2=0.000000
L 4.28333317 3.01638268 4.28256663 3.01276673 1 P 0 ;0,1=17,2=0.000000
L 4.28256663 3.01276673 4.28333317 3.00914892 1 P 0 ;0,1=17,2=0.000000
L 4.28333317 3.00914892 4.2852501 3.00656614 1 P 0 ;0,1=17,2=0.000000
L 4.2852501 3.00656614 4.28831683 3.00501654 1 P 0 ;0,1=17,2=0.000000
L 4.28831683 3.00501654 4.29099961 3.0045 1 P 0 ;0,1=17,2=0.000000
L 4.1089997 3.056 4.11086644 3.05641654 1 P 0 ;0,1=16,2=0.000000
L 4.11086644 3.05641654 4.1129998 3.05766624 1 P 0 ;0,1=16,2=0.000000
L 4.1129998 3.05766624 4.11433337 3.05974911 1 P 0 ;0,1=16,2=0.000000
L 4.11433337 3.05974911 4.11486663 3.06266673 1 P 0 ;0,1=16,2=0.000000
L 4.11486663 3.06266673 4.11433337 3.06558278 1 P 0 ;0,1=16,2=0.000000
L 4.11433337 3.06558278 4.11273327 3.06808297 1 P 0 ;0,1=16,2=0.000000
L 4.11273327 3.06808297 4.11033327 3.06933346 1 P 0 ;0,1=16,2=0.000000
L 4.11033327 3.06933346 4.10766663 3.06933346 1 P 0 ;0,1=16,2=0.000000
L 4.10766663 3.06933346 4.10606654 3.07016663 1 P 0 ;0,1=16,2=0.000000
L 4.10606654 3.07016663 4.10473297 3.07224951 1 P 0 ;0,1=16,2=0.000000
L 4.10473297 3.07224951 4.1041998 3.07516634 1 P 0 ;0,1=16,2=0.000000
L 4.1041998 3.07516634 4.1050001 3.07808317 1 P 0 ;0,1=16,2=0.000000
L 4.1050001 3.07808317 4.10686634 3.08016683 1 P 0 ;0,1=16,2=0.000000
L 4.10686634 3.08016683 4.1089997 3.081 1 P 0 ;0,1=16,2=0.000000
L 4.1089997 3.081 4.11113307 3.08016683 1 P 0 ;0,1=16,2=0.000000
L 4.11113307 3.08016683 4.1129998 3.07808317 1 P 0 ;0,1=16,2=0.000000
L 4.1129998 3.07808317 4.1138001 3.07516634 1 P 0 ;0,1=16,2=0.000000
L 4.1138001 3.07516634 4.11326644 3.07224951 1 P 0 ;0,1=16,2=0.000000
L 4.11326644 3.07224951 4.11193337 3.07016663 1 P 0 ;0,1=16,2=0.000000
L 4.11193337 3.07016663 4.11033327 3.06933346 1 P 0 ;0,1=16,2=0.000000
L 4.11033327 3.06933346 4.10766663 3.06933346 1 P 0 ;0,1=16,2=0.000000
L 4.10766663 3.06933346 4.10526663 3.06808297 1 P 0 ;0,1=16,2=0.000000
L 4.10526663 3.06808297 4.10366654 3.06558278 1 P 0 ;0,1=16,2=0.000000
L 4.10366654 3.06558278 4.10313327 3.06266673 1 P 0 ;0,1=16,2=0.000000
L 4.10313327 3.06266673 4.10366654 3.05974911 1 P 0 ;0,1=16,2=0.000000
L 4.10366654 3.05974911 4.1050001 3.05766624 1 P 0 ;0,1=16,2=0.000000
L 4.1050001 3.05766624 4.10713346 3.05641654 1 P 0 ;0,1=16,2=0.000000
L 4.10713346 3.05641654 4.1089997 3.056 1 P 0 ;0,1=16,2=0.000000
L 4.3155 3.7835 4.3155 3.5665 1 P 0 
L 3.9945 3.7835 4.3155 3.7835 1 P 0 
L 4.3155 3.5665 3.9945 3.5665 1 P 0 
L 3.9945 3.5665 3.9945 3.7835 1 P 0 
S P 0
OB 3.9825 3.7625 I
OC 3.9825 3.7625 3.9675 3.7625 Y
OE
SE
L 4.3239997 3.7625 4.3239997 3.7875 1 P 0 ;0,1=13,2=0.000000
L 4.3239997 3.7875 4.3207999 3.7825003 1 P 0 ;0,1=13,2=0.000000
L 4.3207999 3.7625 4.32719951 3.7625 1 P 0 ;0,1=13,2=0.000000
L 4.34093317 3.77291594 4.3427999 3.77583346 1 P 0 ;0,1=13,2=0.000000
L 4.3427999 3.77583346 4.3444 3.7774998 1 P 0 ;0,1=13,2=0.000000
L 4.3444 3.7774998 4.34653337 3.77833297 1 P 0 ;0,1=13,2=0.000000
L 4.34653337 3.77833297 4.3484002 3.7774998 1 P 0 ;0,1=13,2=0.000000
L 4.3484002 3.7774998 4.34973327 3.77583346 1 P 0 ;0,1=13,2=0.000000
L 4.34973327 3.77583346 4.3508001 3.77333327 1 P 0 ;0,1=13,2=0.000000
L 4.3508001 3.77333327 4.35106673 3.77041644 1 P 0 ;0,1=13,2=0.000000
L 4.35106673 3.77041644 4.3508001 3.76791624 1 P 0 ;0,1=13,2=0.000000
L 4.3508001 3.76791624 4.34973327 3.76541604 1 P 0 ;0,1=13,2=0.000000
L 4.34973327 3.76541604 4.34813307 3.76333307 1 P 0 ;0,1=13,2=0.000000
L 4.34813307 3.76333307 4.34626683 3.7625 1 P 0 ;0,1=13,2=0.000000
L 4.34626683 3.7625 4.34413346 3.76333307 1 P 0 ;0,1=13,2=0.000000
L 4.34413346 3.76333307 4.34226663 3.76583258 1 P 0 ;0,1=13,2=0.000000
L 4.34226663 3.76583258 4.3411998 3.76958327 1 P 0 ;0,1=13,2=0.000000
L 4.3411998 3.76958327 4.34093317 3.7737498 1 P 0 ;0,1=13,2=0.000000
L 4.34093317 3.7737498 4.34146634 3.77916614 1 P 0 ;0,1=13,2=0.000000
L 4.34146634 3.77916614 4.34226663 3.78208366 1 P 0 ;0,1=13,2=0.000000
L 4.34226663 3.78208366 4.3435997 3.7849997 1 P 0 ;0,1=13,2=0.000000
L 4.3435997 3.7849997 4.34546654 3.78708337 1 P 0 ;0,1=13,2=0.000000
L 4.34546654 3.78708337 4.34733327 3.7875 1 P 0 ;0,1=13,2=0.000000
L 4.34733327 3.7875 4.3492 3.78666683 1 P 0 ;0,1=13,2=0.000000
L 4.3492 3.78666683 4.35053356 3.78458317 1 P 0 ;0,1=13,2=0.000000
L 4.33348287 3.55311585 4.33616634 3.55053307 1 P 0 ;0,1=14,2=0.000000
L 4.33616634 3.55053307 4.33923307 3.5495 1 P 0 ;0,1=14,2=0.000000
L 4.33923307 3.5495 4.3422998 3.55053307 1 P 0 ;0,1=14,2=0.000000
L 4.3422998 3.55053307 4.34498327 3.55363238 1 P 0 ;0,1=14,2=0.000000
L 4.34498327 3.55363238 4.3469002 3.55828327 1 P 0 ;0,1=14,2=0.000000
L 4.3469002 3.55828327 4.34766673 3.56293327 1 P 0 ;0,1=14,2=0.000000
L 4.34766673 3.56293327 4.34766673 3.56861634 1 P 0 ;0,1=14,2=0.000000
L 4.34766673 3.56861634 4.3469002 3.57326624 1 P 0 ;0,1=14,2=0.000000
L 4.3469002 3.57326624 4.34498327 3.5773997 1 P 0 ;0,1=14,2=0.000000
L 4.34498327 3.5773997 4.34268307 3.57946683 1 P 0 ;0,1=14,2=0.000000
L 4.34268307 3.57946683 4.33999961 3.5805 1 P 0 ;0,1=14,2=0.000000
L 4.33999961 3.5805 4.33693287 3.57946683 1 P 0 ;0,1=14,2=0.000000
L 4.33693287 3.57946683 4.33463337 3.5773997 1 P 0 ;0,1=14,2=0.000000
L 4.33463337 3.5773997 4.3330997 3.5743003 1 P 0 ;0,1=14,2=0.000000
L 4.3330997 3.5743003 4.33233317 3.57016594 1 P 0 ;0,1=14,2=0.000000
L 4.33233317 3.57016594 4.3330997 3.5665501 1 P 0 ;0,1=14,2=0.000000
L 4.3330997 3.5665501 4.33501663 3.56293327 1 P 0 ;0,1=14,2=0.000000
L 4.33501663 3.56293327 4.33731683 3.56086604 1 P 0 ;0,1=14,2=0.000000
L 4.33731683 3.56086604 4.33999961 3.56034951 1 P 0 ;0,1=14,2=0.000000
L 4.33999961 3.56034951 4.34306634 3.56138268 1 P 0 ;0,1=14,2=0.000000
L 4.34306634 3.56138268 4.34536654 3.56396634 1 P 0 ;0,1=14,2=0.000000
L 4.34536654 3.56396634 4.34766673 3.56861634 1 P 0 ;0,1=14,2=0.000000
L 4.10556663 3.8205 4.10556663 3.79828327 1 P 0 ;0,1=18,2=0.000000
L 4.10556663 3.79828327 4.1070997 3.79363238 1 P 0 ;0,1=18,2=0.000000
L 4.1070997 3.79363238 4.11016634 3.79053307 1 P 0 ;0,1=18,2=0.000000
L 4.11016634 3.79053307 4.11399961 3.7895 1 P 0 ;0,1=18,2=0.000000
L 4.11399961 3.7895 4.11783356 3.79053307 1 P 0 ;0,1=18,2=0.000000
L 4.11783356 3.79053307 4.1209002 3.79363238 1 P 0 ;0,1=18,2=0.000000
L 4.1209002 3.79363238 4.12243327 3.79828327 1 P 0 ;0,1=18,2=0.000000
L 4.12243327 3.79828327 4.12243327 3.8205 1 P 0 ;0,1=18,2=0.000000
L 4.13656663 3.79569961 4.13886614 3.79208278 1 P 0 ;0,1=18,2=0.000000
L 4.13886614 3.79208278 4.14193287 3.79001654 1 P 0 ;0,1=18,2=0.000000
L 4.14193287 3.79001654 4.14538356 3.7895 1 P 0 ;0,1=18,2=0.000000
L 4.14538356 3.7895 4.1484503 3.79001654 1 P 0 ;0,1=18,2=0.000000
L 4.1484503 3.79001654 4.15151703 3.79259931 1 P 0 ;0,1=18,2=0.000000
L 4.15151703 3.79259931 4.15343327 3.79569961 1 P 0 ;0,1=18,2=0.000000
L 4.15343327 3.79569961 4.15381654 3.7987999 1 P 0 ;0,1=18,2=0.000000
L 4.15381654 3.7987999 4.15305 3.80241575 1 P 0 ;0,1=18,2=0.000000
L 4.15305 3.80241575 4.15036654 3.80499951 1 P 0 ;0,1=18,2=0.000000
L 4.15036654 3.80499951 4.14768307 3.80603356 1 P 0 ;0,1=18,2=0.000000
L 4.14768307 3.80603356 4.14423307 3.80603356 1 P 0 ;0,1=18,2=0.000000
L 4.14768307 3.80603356 4.14998327 3.80758317 1 P 0 ;0,1=18,2=0.000000
L 4.14998327 3.80758317 4.1519002 3.81016594 1 P 0 ;0,1=18,2=0.000000
L 4.1519002 3.81016594 4.15266673 3.81326624 1 P 0 ;0,1=18,2=0.000000
L 4.15266673 3.81326624 4.1519002 3.81636654 1 P 0 ;0,1=18,2=0.000000
L 4.1519002 3.81636654 4.14998327 3.81894931 1 P 0 ;0,1=18,2=0.000000
L 4.14998327 3.81894931 4.14653327 3.8205 1 P 0 ;0,1=18,2=0.000000
L 4.14653327 3.8205 4.14308337 3.81998337 1 P 0 ;0,1=18,2=0.000000
L 4.14308337 3.81998337 4.13963337 3.81791624 1 P 0 ;0,1=18,2=0.000000
L 4.17599961 3.8205 4.17293287 3.81946683 1 P 0 ;0,1=18,2=0.000000
L 4.17293287 3.81946683 4.17063337 3.81688307 1 P 0 ;0,1=18,2=0.000000
L 4.17063337 3.81688307 4.1690997 3.81378376 1 P 0 ;0,1=18,2=0.000000
L 4.1690997 3.81378376 4.1679499 3.80964941 1 P 0 ;0,1=18,2=0.000000
L 4.1679499 3.80964941 4.16756663 3.80499951 1 P 0 ;0,1=18,2=0.000000
L 4.16756663 3.80499951 4.1679499 3.80034951 1 P 0 ;0,1=18,2=0.000000
L 4.1679499 3.80034951 4.1690997 3.79621614 1 P 0 ;0,1=18,2=0.000000
L 4.1690997 3.79621614 4.17063337 3.79311585 1 P 0 ;0,1=18,2=0.000000
L 4.17063337 3.79311585 4.17293287 3.79053307 1 P 0 ;0,1=18,2=0.000000
L 4.17293287 3.79053307 4.17599961 3.7895 1 P 0 ;0,1=18,2=0.000000
L 4.17599961 3.7895 4.17906634 3.79053307 1 P 0 ;0,1=18,2=0.000000
L 4.17906634 3.79053307 4.18136654 3.79311585 1 P 0 ;0,1=18,2=0.000000
L 4.18136654 3.79311585 4.1829002 3.79621614 1 P 0 ;0,1=18,2=0.000000
L 4.1829002 3.79621614 4.18405 3.80034951 1 P 0 ;0,1=18,2=0.000000
L 4.18405 3.80034951 4.18443327 3.80499951 1 P 0 ;0,1=18,2=0.000000
L 4.18443327 3.80499951 4.18405 3.80964941 1 P 0 ;0,1=18,2=0.000000
L 4.18405 3.80964941 4.1829002 3.81378376 1 P 0 ;0,1=18,2=0.000000
L 4.1829002 3.81378376 4.18136654 3.81688307 1 P 0 ;0,1=18,2=0.000000
L 4.18136654 3.81688307 4.17906634 3.81946683 1 P 0 ;0,1=18,2=0.000000
L 4.17906634 3.81946683 4.17599961 3.8205 1 P 0 ;0,1=18,2=0.000000
L 3.96999961 3.5595 3.97268307 3.56001654 1 P 0 ;0,1=16,2=0.000000
L 3.97268307 3.56001654 3.9757498 3.56156614 1 P 0 ;0,1=16,2=0.000000
L 3.9757498 3.56156614 3.97766673 3.56414892 1 P 0 ;0,1=16,2=0.000000
L 3.97766673 3.56414892 3.97843327 3.56776673 1 P 0 ;0,1=16,2=0.000000
L 3.97843327 3.56776673 3.97766673 3.57138268 1 P 0 ;0,1=16,2=0.000000
L 3.97766673 3.57138268 3.97536654 3.57448287 1 P 0 ;0,1=16,2=0.000000
L 3.97536654 3.57448287 3.97191654 3.57603356 1 P 0 ;0,1=16,2=0.000000
L 3.97191654 3.57603356 3.96808337 3.57603356 1 P 0 ;0,1=16,2=0.000000
L 3.96808337 3.57603356 3.96578317 3.57706663 1 P 0 ;0,1=16,2=0.000000
L 3.96578317 3.57706663 3.96386614 3.57964941 1 P 0 ;0,1=16,2=0.000000
L 3.96386614 3.57964941 3.9630997 3.58326624 1 P 0 ;0,1=16,2=0.000000
L 3.9630997 3.58326624 3.9642501 3.58688307 1 P 0 ;0,1=16,2=0.000000
L 3.9642501 3.58688307 3.96693287 3.58946683 1 P 0 ;0,1=16,2=0.000000
L 3.96693287 3.58946683 3.96999961 3.5905 1 P 0 ;0,1=16,2=0.000000
L 3.96999961 3.5905 3.97306634 3.58946683 1 P 0 ;0,1=16,2=0.000000
L 3.97306634 3.58946683 3.9757498 3.58688307 1 P 0 ;0,1=16,2=0.000000
L 3.9757498 3.58688307 3.9769002 3.58326624 1 P 0 ;0,1=16,2=0.000000
L 3.9769002 3.58326624 3.97613307 3.57964941 1 P 0 ;0,1=16,2=0.000000
L 3.97613307 3.57964941 3.97421673 3.57706663 1 P 0 ;0,1=16,2=0.000000
L 3.97421673 3.57706663 3.97191654 3.57603356 1 P 0 ;0,1=16,2=0.000000
L 3.97191654 3.57603356 3.96808337 3.57603356 1 P 0 ;0,1=16,2=0.000000
L 3.96808337 3.57603356 3.96463337 3.57448287 1 P 0 ;0,1=16,2=0.000000
L 3.96463337 3.57448287 3.96233317 3.57138268 1 P 0 ;0,1=16,2=0.000000
L 3.96233317 3.57138268 3.96156663 3.56776673 1 P 0 ;0,1=16,2=0.000000
L 3.96156663 3.56776673 3.96233317 3.56414892 1 P 0 ;0,1=16,2=0.000000
L 3.96233317 3.56414892 3.9642501 3.56156614 1 P 0 ;0,1=16,2=0.000000
L 3.9642501 3.56156614 3.96731683 3.56001654 1 P 0 ;0,1=16,2=0.000000
L 3.96731683 3.56001654 3.96999961 3.5595 1 P 0 ;0,1=16,2=0.000000
L 0.704 0.9885 0.846 0.9885 1 P 0 
L 0.846 0.9885 0.846 0.6675 1 P 0 
L 0.846 0.6675 0.704 0.6675 1 P 0 
L 0.704 0.6675 0.704 0.9885 1 P 0 
S P 0
OB 0.885 0.99 I
OC 0.885 0.99 0.87 0.99 Y
OE
SE
L 0.8645 0.86556663 0.88671673 0.86556663 1 P 0 ;0,1=19,2=270.000000
L 0.88671673 0.86556663 0.89136762 0.8670997 1 P 0 ;0,1=19,2=270.000000
L 0.89136762 0.8670997 0.89446693 0.87016634 1 P 0 ;0,1=19,2=270.000000
L 0.89446693 0.87016634 0.8955 0.87399961 1 P 0 ;0,1=19,2=270.000000
L 0.8955 0.87399961 0.89446693 0.87783356 1 P 0 ;0,1=19,2=270.000000
L 0.89446693 0.87783356 0.89136762 0.8809002 1 P 0 ;0,1=19,2=270.000000
L 0.89136762 0.8809002 0.88671673 0.88243327 1 P 0 ;0,1=19,2=270.000000
L 0.88671673 0.88243327 0.8645 0.88243327 1 P 0 ;0,1=19,2=270.000000
L 0.8955 0.90499961 0.8645 0.90499961 1 P 0 ;0,1=19,2=270.000000
L 0.8645 0.90499961 0.8706997 0.9003999 1 P 0 ;0,1=19,2=270.000000
L 0.8955 0.9003999 0.8955 0.90959931 1 P 0 ;0,1=19,2=270.000000
L 0.89188415 0.92948287 0.89446693 0.93216634 1 P 0 ;0,1=19,2=270.000000
L 0.89446693 0.93216634 0.8955 0.93523307 1 P 0 ;0,1=19,2=270.000000
L 0.8955 0.93523307 0.89446693 0.9382998 1 P 0 ;0,1=19,2=270.000000
L 0.89446693 0.9382998 0.89136762 0.94098327 1 P 0 ;0,1=19,2=270.000000
L 0.89136762 0.94098327 0.88671673 0.9429002 1 P 0 ;0,1=19,2=270.000000
L 0.88671673 0.9429002 0.88206673 0.94366673 1 P 0 ;0,1=19,2=270.000000
L 0.88206673 0.94366673 0.87638366 0.94366673 1 P 0 ;0,1=19,2=270.000000
L 0.87638366 0.94366673 0.87173376 0.9429002 1 P 0 ;0,1=19,2=270.000000
L 0.87173376 0.9429002 0.8676003 0.94098327 1 P 0 ;0,1=19,2=270.000000
L 0.8676003 0.94098327 0.86553317 0.93868307 1 P 0 ;0,1=19,2=270.000000
L 0.86553317 0.93868307 0.8645 0.93599961 1 P 0 ;0,1=19,2=270.000000
L 0.8645 0.93599961 0.86553317 0.93293287 1 P 0 ;0,1=19,2=270.000000
L 0.86553317 0.93293287 0.8676003 0.93063337 1 P 0 ;0,1=19,2=270.000000
L 0.8676003 0.93063337 0.8706997 0.9290997 1 P 0 ;0,1=19,2=270.000000
L 0.8706997 0.9290997 0.87483406 0.92833317 1 P 0 ;0,1=19,2=270.000000
L 0.87483406 0.92833317 0.8784499 0.9290997 1 P 0 ;0,1=19,2=270.000000
L 0.8784499 0.9290997 0.88206673 0.93101663 1 P 0 ;0,1=19,2=270.000000
L 0.88206673 0.93101663 0.88413396 0.93331683 1 P 0 ;0,1=19,2=270.000000
L 0.88413396 0.93331683 0.88465049 0.93599961 1 P 0 ;0,1=19,2=270.000000
L 0.88465049 0.93599961 0.88361732 0.93906634 1 P 0 ;0,1=19,2=270.000000
L 0.88361732 0.93906634 0.88103366 0.94136654 1 P 0 ;0,1=19,2=270.000000
L 0.88103366 0.94136654 0.87638366 0.94366673 1 P 0 ;0,1=19,2=270.000000
L 0.8664997 0.6745 0.86836644 0.67491654 1 P 0 ;0,1=16,2=0.000000
L 0.86836644 0.67491654 0.8704998 0.67616624 1 P 0 ;0,1=16,2=0.000000
L 0.8704998 0.67616624 0.87183337 0.67824911 1 P 0 ;0,1=16,2=0.000000
L 0.87183337 0.67824911 0.87236663 0.68116673 1 P 0 ;0,1=16,2=0.000000
L 0.87236663 0.68116673 0.87183337 0.68408278 1 P 0 ;0,1=16,2=0.000000
L 0.87183337 0.68408278 0.87023327 0.68658297 1 P 0 ;0,1=16,2=0.000000
L 0.87023327 0.68658297 0.86783327 0.68783346 1 P 0 ;0,1=16,2=0.000000
L 0.86783327 0.68783346 0.86516663 0.68783346 1 P 0 ;0,1=16,2=0.000000
L 0.86516663 0.68783346 0.86356654 0.68866663 1 P 0 ;0,1=16,2=0.000000
L 0.86356654 0.68866663 0.86223297 0.69074951 1 P 0 ;0,1=16,2=0.000000
L 0.86223297 0.69074951 0.8616998 0.69366634 1 P 0 ;0,1=16,2=0.000000
L 0.8616998 0.69366634 0.8625001 0.69658317 1 P 0 ;0,1=16,2=0.000000
L 0.8625001 0.69658317 0.86436634 0.69866683 1 P 0 ;0,1=16,2=0.000000
L 0.86436634 0.69866683 0.8664997 0.6995 1 P 0 ;0,1=16,2=0.000000
L 0.8664997 0.6995 0.86863307 0.69866683 1 P 0 ;0,1=16,2=0.000000
L 0.86863307 0.69866683 0.8704998 0.69658317 1 P 0 ;0,1=16,2=0.000000
L 0.8704998 0.69658317 0.8713001 0.69366634 1 P 0 ;0,1=16,2=0.000000
L 0.8713001 0.69366634 0.87076644 0.69074951 1 P 0 ;0,1=16,2=0.000000
L 0.87076644 0.69074951 0.86943337 0.68866663 1 P 0 ;0,1=16,2=0.000000
L 0.86943337 0.68866663 0.86783327 0.68783346 1 P 0 ;0,1=16,2=0.000000
L 0.86783327 0.68783346 0.86516663 0.68783346 1 P 0 ;0,1=16,2=0.000000
L 0.86516663 0.68783346 0.86276663 0.68658297 1 P 0 ;0,1=16,2=0.000000
L 0.86276663 0.68658297 0.86116654 0.68408278 1 P 0 ;0,1=16,2=0.000000
L 0.86116654 0.68408278 0.86063327 0.68116673 1 P 0 ;0,1=16,2=0.000000
L 0.86063327 0.68116673 0.86116654 0.67824911 1 P 0 ;0,1=16,2=0.000000
L 0.86116654 0.67824911 0.8625001 0.67616624 1 P 0 ;0,1=16,2=0.000000
L 0.8625001 0.67616624 0.86463346 0.67491654 1 P 0 ;0,1=16,2=0.000000
L 0.86463346 0.67491654 0.8664997 0.6745 1 P 0 ;0,1=16,2=0.000000
L 0.7147 1.0045 0.7147 1.0295 1 P 0 ;0,1=11,2=0.000000
L 0.7147 1.0295 0.70483297 1.01158327 1 P 0 ;0,1=11,2=0.000000
L 0.70483297 1.01158327 0.71816693 1.01158327 1 P 0 ;0,1=11,2=0.000000
L 0.70063327 0.62324911 0.70223297 0.62116624 1 P 0 ;0,1=20,2=0.000000
L 0.70223297 0.62116624 0.7040997 0.61991654 1 P 0 ;0,1=20,2=0.000000
L 0.7040997 0.61991654 0.7064997 0.6195 1 P 0 ;0,1=20,2=0.000000
L 0.7064997 0.6195 0.7089002 0.62033307 1 P 0 ;0,1=20,2=0.000000
L 0.7089002 0.62033307 0.71076644 0.62199941 1 P 0 ;0,1=20,2=0.000000
L 0.71076644 0.62199941 0.7121 0.62491624 1 P 0 ;0,1=20,2=0.000000
L 0.7121 0.62491624 0.71236663 0.62824961 1 P 0 ;0,1=20,2=0.000000
L 0.71236663 0.62824961 0.71183337 0.63158297 1 P 0 ;0,1=20,2=0.000000
L 0.71183337 0.63158297 0.7104998 0.63366663 1 P 0 ;0,1=20,2=0.000000
L 0.7104998 0.63366663 0.70863307 0.63533297 1 P 0 ;0,1=20,2=0.000000
L 0.70863307 0.63533297 0.70676683 0.63574951 1 P 0 ;0,1=20,2=0.000000
L 0.70676683 0.63574951 0.7049 0.63533297 1 P 0 ;0,1=20,2=0.000000
L 0.7049 0.63533297 0.7025001 0.63366663 1 P 0 ;0,1=20,2=0.000000
L 0.7025001 0.63366663 0.7032999 0.6445 1 P 0 ;0,1=20,2=0.000000
L 0.7032999 0.6445 0.7104998 0.6445 1 P 0 ;0,1=20,2=0.000000
L 1.57668996 3.20656998 1.70331004 3.20656998 1 P 0 
L 1.70331004 3.20656998 1.70331004 3.13343002 1 P 0 
L 1.70331004 3.13343002 1.57668996 3.13343002 1 P 0 
L 1.57668996 3.13343002 1.57668996 3.20656998 1 P 0 
S P 0
OB 1.72331003937 3.133430019685 I
OS 1.70331003937 3.133430019685
OS 1.70331003937 3.206569980315
OS 1.72331003937 3.206569980315
OS 1.72331003937 3.133430019685
OE
SE
L 1.59243327 3.35791624 1.59013307 3.35946683 1 P 0 ;0,1=21,2=0.000000
L 1.59013307 3.35946683 1.5874503 3.3605 1 P 0 ;0,1=21,2=0.000000
L 1.5874503 3.3605 1.58438356 3.3605 1 P 0 ;0,1=21,2=0.000000
L 1.58438356 3.3605 1.58093287 3.35894931 1 P 0 ;0,1=21,2=0.000000
L 1.58093287 3.35894931 1.5782501 3.35636654 1 P 0 ;0,1=21,2=0.000000
L 1.5782501 3.35636654 1.57633317 3.35326624 1 P 0 ;0,1=21,2=0.000000
L 1.57633317 3.35326624 1.57479951 3.3480998 1 P 0 ;0,1=21,2=0.000000
L 1.57479951 3.3480998 1.57441624 3.3434498 1 P 0 ;0,1=21,2=0.000000
L 1.57441624 3.3434498 1.57518337 3.3387999 1 P 0 ;0,1=21,2=0.000000
L 1.57518337 3.3387999 1.57633317 3.33569961 1 P 0 ;0,1=21,2=0.000000
L 1.57633317 3.33569961 1.57863337 3.33259931 1 P 0 ;0,1=21,2=0.000000
L 1.57863337 3.33259931 1.58131683 3.33053307 1 P 0 ;0,1=21,2=0.000000
L 1.58131683 3.33053307 1.58399961 3.3295 1 P 0 ;0,1=21,2=0.000000
L 1.58399961 3.3295 1.58668307 3.3295 1 P 0 ;0,1=21,2=0.000000
L 1.58668307 3.3295 1.58936654 3.33053307 1 P 0 ;0,1=21,2=0.000000
L 1.58936654 3.33053307 1.59166673 3.33208278 1 P 0 ;0,1=21,2=0.000000
L 1.59166673 3.33208278 1.59358366 3.33414892 1 P 0 ;0,1=21,2=0.000000
L 1.60733317 3.3295 1.60733317 3.3605 1 P 0 ;0,1=21,2=0.000000
L 1.60733317 3.3605 1.61691654 3.3605 1 P 0 ;0,1=21,2=0.000000
L 1.61691654 3.3605 1.61998327 3.35894931 1 P 0 ;0,1=21,2=0.000000
L 1.61998327 3.35894931 1.6219002 3.35688307 1 P 0 ;0,1=21,2=0.000000
L 1.6219002 3.35688307 1.62266673 3.3527497 1 P 0 ;0,1=21,2=0.000000
L 1.62266673 3.3527497 1.6219002 3.34861634 1 P 0 ;0,1=21,2=0.000000
L 1.6219002 3.34861634 1.6196 3.34603356 1 P 0 ;0,1=21,2=0.000000
L 1.6196 3.34603356 1.61691654 3.34448287 1 P 0 ;0,1=21,2=0.000000
L 1.61691654 3.34448287 1.60733317 3.34448287 1 P 0 ;0,1=21,2=0.000000
L 1.61691654 3.34448287 1.62266673 3.3295 1 P 0 ;0,1=21,2=0.000000
L 1.63871644 3.35533346 1.64101663 3.35843278 1 P 0 ;0,1=21,2=0.000000
L 1.64101663 3.35843278 1.6437001 3.35998337 1 P 0 ;0,1=21,2=0.000000
L 1.6437001 3.35998337 1.64676683 3.3605 1 P 0 ;0,1=21,2=0.000000
L 1.64676683 3.3605 1.6506 3.35946683 1 P 0 ;0,1=21,2=0.000000
L 1.6506 3.35946683 1.65328346 3.35688307 1 P 0 ;0,1=21,2=0.000000
L 1.65328346 3.35688307 1.65405 3.35378376 1 P 0 ;0,1=21,2=0.000000
L 1.65405 3.35378376 1.65366673 3.35068258 1 P 0 ;0,1=21,2=0.000000
L 1.65366673 3.35068258 1.65213307 3.3480998 1 P 0 ;0,1=21,2=0.000000
L 1.65213307 3.3480998 1.64446663 3.34293327 1 P 0 ;0,1=21,2=0.000000
L 1.64446663 3.34293327 1.64101663 3.33931644 1 P 0 ;0,1=21,2=0.000000
L 1.64101663 3.33931644 1.63871644 3.33414892 1 P 0 ;0,1=21,2=0.000000
L 1.63871644 3.33414892 1.6379499 3.3295 1 P 0 ;0,1=21,2=0.000000
L 1.6379499 3.3295 1.65405 3.3295 1 P 0 ;0,1=21,2=0.000000
L 1.72586663 3.11541634 1.72426644 3.11666683 1 P 0 ;0,1=22,2=0.000000
L 1.72426644 3.11666683 1.7224002 3.1175 1 P 0 ;0,1=22,2=0.000000
L 1.7224002 3.1175 1.72026683 3.1175 1 P 0 ;0,1=22,2=0.000000
L 1.72026683 3.1175 1.71786634 3.11624941 1 P 0 ;0,1=22,2=0.000000
L 1.71786634 3.11624941 1.7160001 3.11416654 1 P 0 ;0,1=22,2=0.000000
L 1.7160001 3.11416654 1.71466654 3.11166634 1 P 0 ;0,1=22,2=0.000000
L 1.71466654 3.11166634 1.71359961 3.1074998 1 P 0 ;0,1=22,2=0.000000
L 1.71359961 3.1074998 1.71333297 3.1037498 1 P 0 ;0,1=22,2=0.000000
L 1.71333297 3.1037498 1.71386673 3.0999999 1 P 0 ;0,1=22,2=0.000000
L 1.71386673 3.0999999 1.71466654 3.09749961 1 P 0 ;0,1=22,2=0.000000
L 1.71466654 3.09749961 1.71626663 3.09499941 1 P 0 ;0,1=22,2=0.000000
L 1.71626663 3.09499941 1.71813346 3.09333307 1 P 0 ;0,1=22,2=0.000000
L 1.71813346 3.09333307 1.7199997 3.0925 1 P 0 ;0,1=22,2=0.000000
L 1.7199997 3.0925 1.72186644 3.0925 1 P 0 ;0,1=22,2=0.000000
L 1.72186644 3.0925 1.72373327 3.09333307 1 P 0 ;0,1=22,2=0.000000
L 1.72373327 3.09333307 1.72533337 3.09458287 1 P 0 ;0,1=22,2=0.000000
L 1.72533337 3.09458287 1.72666693 3.09624911 1 P 0 ;0,1=22,2=0.000000
L 1.53541624 3.1795 1.54499961 3.2105 1 P 0 ;0,1=1,2=0.000000
L 1.54499961 3.2105 1.55458366 3.1795 1 P 0 ;0,1=1,2=0.000000
L 1.55113307 3.19034951 1.53886614 3.19034951 1 P 0 ;0,1=1,2=0.000000
L 1.70331004 3.30656998 1.70331004 3.23343002 1 P 0 
L 1.70331004 3.23343002 1.57668996 3.23343002 1 P 0 
L 1.57668996 3.23343002 1.57668996 3.30656998 1 P 0 
L 1.57668996 3.30656998 1.70331004 3.30656998 1 P 0 
S P 0
OB 1.72331003937 3.233430019685 I
OS 1.70331003937 3.233430019685
OS 1.70331003937 3.306569980315
OS 1.72331003937 3.306569980315
OS 1.72331003937 3.233430019685
OE
SE
L 1.59243327 3.40291624 1.59013307 3.40446683 1 P 0 ;0,1=23,2=0.000000
L 1.59013307 3.40446683 1.5874503 3.4055 1 P 0 ;0,1=23,2=0.000000
L 1.5874503 3.4055 1.58438356 3.4055 1 P 0 ;0,1=23,2=0.000000
L 1.58438356 3.4055 1.58093287 3.40394931 1 P 0 ;0,1=23,2=0.000000
L 1.58093287 3.40394931 1.5782501 3.40136654 1 P 0 ;0,1=23,2=0.000000
L 1.5782501 3.40136654 1.57633317 3.39826624 1 P 0 ;0,1=23,2=0.000000
L 1.57633317 3.39826624 1.57479951 3.3930998 1 P 0 ;0,1=23,2=0.000000
L 1.57479951 3.3930998 1.57441624 3.3884498 1 P 0 ;0,1=23,2=0.000000
L 1.57441624 3.3884498 1.57518337 3.3837999 1 P 0 ;0,1=23,2=0.000000
L 1.57518337 3.3837999 1.57633317 3.38069961 1 P 0 ;0,1=23,2=0.000000
L 1.57633317 3.38069961 1.57863337 3.37759931 1 P 0 ;0,1=23,2=0.000000
L 1.57863337 3.37759931 1.58131683 3.37553307 1 P 0 ;0,1=23,2=0.000000
L 1.58131683 3.37553307 1.58399961 3.3745 1 P 0 ;0,1=23,2=0.000000
L 1.58399961 3.3745 1.58668307 3.3745 1 P 0 ;0,1=23,2=0.000000
L 1.58668307 3.3745 1.58936654 3.37553307 1 P 0 ;0,1=23,2=0.000000
L 1.58936654 3.37553307 1.59166673 3.37708278 1 P 0 ;0,1=23,2=0.000000
L 1.59166673 3.37708278 1.59358366 3.37914892 1 P 0 ;0,1=23,2=0.000000
L 1.60733317 3.3745 1.60733317 3.4055 1 P 0 ;0,1=23,2=0.000000
L 1.60733317 3.4055 1.61691654 3.4055 1 P 0 ;0,1=23,2=0.000000
L 1.61691654 3.4055 1.61998327 3.40394931 1 P 0 ;0,1=23,2=0.000000
L 1.61998327 3.40394931 1.6219002 3.40188307 1 P 0 ;0,1=23,2=0.000000
L 1.6219002 3.40188307 1.62266673 3.3977497 1 P 0 ;0,1=23,2=0.000000
L 1.62266673 3.3977497 1.6219002 3.39361634 1 P 0 ;0,1=23,2=0.000000
L 1.6219002 3.39361634 1.6196 3.39103356 1 P 0 ;0,1=23,2=0.000000
L 1.6196 3.39103356 1.61691654 3.38948287 1 P 0 ;0,1=23,2=0.000000
L 1.61691654 3.38948287 1.60733317 3.38948287 1 P 0 ;0,1=23,2=0.000000
L 1.61691654 3.38948287 1.62266673 3.3745 1 P 0 ;0,1=23,2=0.000000
L 1.64599961 3.3745 1.64599961 3.4055 1 P 0 ;0,1=23,2=0.000000
L 1.64599961 3.4055 1.6413999 3.3993003 1 P 0 ;0,1=23,2=0.000000
L 1.6413999 3.3745 1.65059931 3.3745 1 P 0 ;0,1=23,2=0.000000
L 1.74086663 3.31241634 1.73926644 3.31366683 1 P 0 ;0,1=22,2=0.000000
L 1.73926644 3.31366683 1.7374002 3.3145 1 P 0 ;0,1=22,2=0.000000
L 1.7374002 3.3145 1.73526683 3.3145 1 P 0 ;0,1=22,2=0.000000
L 1.73526683 3.3145 1.73286634 3.31324941 1 P 0 ;0,1=22,2=0.000000
L 1.73286634 3.31324941 1.7310001 3.31116654 1 P 0 ;0,1=22,2=0.000000
L 1.7310001 3.31116654 1.72966654 3.30866634 1 P 0 ;0,1=22,2=0.000000
L 1.72966654 3.30866634 1.72859961 3.3044998 1 P 0 ;0,1=22,2=0.000000
L 1.72859961 3.3044998 1.72833297 3.3007498 1 P 0 ;0,1=22,2=0.000000
L 1.72833297 3.3007498 1.72886673 3.2969999 1 P 0 ;0,1=22,2=0.000000
L 1.72886673 3.2969999 1.72966654 3.29449961 1 P 0 ;0,1=22,2=0.000000
L 1.72966654 3.29449961 1.73126663 3.29199941 1 P 0 ;0,1=22,2=0.000000
L 1.73126663 3.29199941 1.73313346 3.29033307 1 P 0 ;0,1=22,2=0.000000
L 1.73313346 3.29033307 1.7349997 3.2895 1 P 0 ;0,1=22,2=0.000000
L 1.7349997 3.2895 1.73686644 3.2895 1 P 0 ;0,1=22,2=0.000000
L 1.73686644 3.2895 1.73873327 3.29033307 1 P 0 ;0,1=22,2=0.000000
L 1.73873327 3.29033307 1.74033337 3.29158287 1 P 0 ;0,1=22,2=0.000000
L 1.74033337 3.29158287 1.74166693 3.29324911 1 P 0 ;0,1=22,2=0.000000
L 1.53041624 3.2995 1.53999961 3.3305 1 P 0 ;0,1=1,2=0.000000
L 1.53999961 3.3305 1.54958366 3.2995 1 P 0 ;0,1=1,2=0.000000
L 1.54613307 3.31034951 1.53386614 3.31034951 1 P 0 ;0,1=1,2=0.000000
L 6.112 2.352 6.112 2.296 1 P 0 
L 6.008 2.352 6.112 2.352 1 P 0 
L 6.112 2.296 6.008 2.296 1 P 0 
L 6.008 2.296 6.008 2.352 1 P 0 
L 6.02133317 2.4005 6.02133317 2.3695 1 P 0 ;0,1=24,2=0.000000
L 6.02133317 2.3695 6.03666673 2.3695 1 P 0 ;0,1=24,2=0.000000
L 6.05999961 2.3695 6.05999961 2.4005 1 P 0 ;0,1=24,2=0.000000
L 6.05999961 2.4005 6.0553999 2.3943003 1 P 0 ;0,1=24,2=0.000000
L 6.0553999 2.3695 6.06459931 2.3695 1 P 0 ;0,1=24,2=0.000000
L 6.09023307 2.3695 6.09099961 2.37621614 1 P 0 ;0,1=24,2=0.000000
L 6.09099961 2.37621614 6.0921501 2.38189921 1 P 0 ;0,1=24,2=0.000000
L 6.0921501 2.38189921 6.09368307 2.38706663 1 P 0 ;0,1=24,2=0.000000
L 6.09368307 2.38706663 6.0956 2.3927497 1 P 0 ;0,1=24,2=0.000000
L 6.0956 2.3927497 6.09866673 2.4005 1 P 0 ;0,1=24,2=0.000000
L 6.09866673 2.4005 6.08333317 2.4005 1 P 0 ;0,1=24,2=0.000000
L 0.97748002 2.604 0.87348002 2.604 1 P 0 
L 0.87348002 2.604 0.87348002 2.66 1 P 0 
L 0.87348002 2.66 0.97748002 2.66 1 P 0 
L 0.97748002 2.66 0.97748002 2.604 1 P 0 
L 1.00633317 2.6505 1.00633317 2.6195 1 P 0 ;0,1=25,2=0.000000
L 1.00633317 2.6195 1.02166673 2.6195 1 P 0 ;0,1=25,2=0.000000
L 1.04499961 2.6195 1.04499961 2.6505 1 P 0 ;0,1=25,2=0.000000
L 1.04499961 2.6505 1.0403999 2.6443003 1 P 0 ;0,1=25,2=0.000000
L 1.0403999 2.6195 1.04959931 2.6195 1 P 0 ;0,1=25,2=0.000000
L 1.07599961 2.6195 1.07868307 2.62001654 1 P 0 ;0,1=25,2=0.000000
L 1.07868307 2.62001654 1.0817498 2.62156614 1 P 0 ;0,1=25,2=0.000000
L 1.0817498 2.62156614 1.08366673 2.62414892 1 P 0 ;0,1=25,2=0.000000
L 1.08366673 2.62414892 1.08443327 2.62776673 1 P 0 ;0,1=25,2=0.000000
L 1.08443327 2.62776673 1.08366673 2.63138268 1 P 0 ;0,1=25,2=0.000000
L 1.08366673 2.63138268 1.08136654 2.63448287 1 P 0 ;0,1=25,2=0.000000
L 1.08136654 2.63448287 1.07791654 2.63603356 1 P 0 ;0,1=25,2=0.000000
L 1.07791654 2.63603356 1.07408337 2.63603356 1 P 0 ;0,1=25,2=0.000000
L 1.07408337 2.63603356 1.07178317 2.63706663 1 P 0 ;0,1=25,2=0.000000
L 1.07178317 2.63706663 1.06986614 2.63964941 1 P 0 ;0,1=25,2=0.000000
L 1.06986614 2.63964941 1.0690997 2.64326624 1 P 0 ;0,1=25,2=0.000000
L 1.0690997 2.64326624 1.0702501 2.64688307 1 P 0 ;0,1=25,2=0.000000
L 1.0702501 2.64688307 1.07293287 2.64946683 1 P 0 ;0,1=25,2=0.000000
L 1.07293287 2.64946683 1.07599961 2.6505 1 P 0 ;0,1=25,2=0.000000
L 1.07599961 2.6505 1.07906634 2.64946683 1 P 0 ;0,1=25,2=0.000000
L 1.07906634 2.64946683 1.0817498 2.64688307 1 P 0 ;0,1=25,2=0.000000
L 1.0817498 2.64688307 1.0829002 2.64326624 1 P 0 ;0,1=25,2=0.000000
L 1.0829002 2.64326624 1.08213307 2.63964941 1 P 0 ;0,1=25,2=0.000000
L 1.08213307 2.63964941 1.08021673 2.63706663 1 P 0 ;0,1=25,2=0.000000
L 1.08021673 2.63706663 1.07791654 2.63603356 1 P 0 ;0,1=25,2=0.000000
L 1.07791654 2.63603356 1.07408337 2.63603356 1 P 0 ;0,1=25,2=0.000000
L 1.07408337 2.63603356 1.07063337 2.63448287 1 P 0 ;0,1=25,2=0.000000
L 1.07063337 2.63448287 1.06833317 2.63138268 1 P 0 ;0,1=25,2=0.000000
L 1.06833317 2.63138268 1.06756663 2.62776673 1 P 0 ;0,1=25,2=0.000000
L 1.06756663 2.62776673 1.06833317 2.62414892 1 P 0 ;0,1=25,2=0.000000
L 1.06833317 2.62414892 1.0702501 2.62156614 1 P 0 ;0,1=25,2=0.000000
L 1.0702501 2.62156614 1.07331683 2.62001654 1 P 0 ;0,1=25,2=0.000000
L 1.07331683 2.62001654 1.07599961 2.6195 1 P 0 ;0,1=25,2=0.000000
L 3.519 2.588 3.519 2.484 1 P 0 
L 3.463 2.588 3.519 2.588 1 P 0 
L 3.463 2.484 3.463 2.588 1 P 0 
L 3.519 2.484 3.463 2.484 1 P 0 
L 3.0795 3.00133317 3.1105 3.00133317 1 P 0 ;0,1=26,2=270.000000
L 3.1105 3.00133317 3.1105 3.01666673 1 P 0 ;0,1=26,2=270.000000
L 3.1105 3.03999961 3.0795 3.03999961 1 P 0 ;0,1=26,2=270.000000
L 3.0795 3.03999961 3.0856997 3.0353999 1 P 0 ;0,1=26,2=270.000000
L 3.1105 3.0353999 3.1105 3.04459931 1 P 0 ;0,1=26,2=270.000000
L 3.10688415 3.06448287 3.10946693 3.06716634 1 P 0 ;0,1=26,2=270.000000
L 3.10946693 3.06716634 3.1105 3.07023307 1 P 0 ;0,1=26,2=270.000000
L 3.1105 3.07023307 3.10946693 3.0732998 1 P 0 ;0,1=26,2=270.000000
L 3.10946693 3.0732998 3.10636762 3.07598327 1 P 0 ;0,1=26,2=270.000000
L 3.10636762 3.07598327 3.10171673 3.0779002 1 P 0 ;0,1=26,2=270.000000
L 3.10171673 3.0779002 3.09706673 3.07866673 1 P 0 ;0,1=26,2=270.000000
L 3.09706673 3.07866673 3.09138366 3.07866673 1 P 0 ;0,1=26,2=270.000000
L 3.09138366 3.07866673 3.08673376 3.0779002 1 P 0 ;0,1=26,2=270.000000
L 3.08673376 3.0779002 3.0826003 3.07598327 1 P 0 ;0,1=26,2=270.000000
L 3.0826003 3.07598327 3.08053317 3.07368307 1 P 0 ;0,1=26,2=270.000000
L 3.08053317 3.07368307 3.0795 3.07099961 1 P 0 ;0,1=26,2=270.000000
L 3.0795 3.07099961 3.08053317 3.06793287 1 P 0 ;0,1=26,2=270.000000
L 3.08053317 3.06793287 3.0826003 3.06563337 1 P 0 ;0,1=26,2=270.000000
L 3.0826003 3.06563337 3.0856997 3.0640997 1 P 0 ;0,1=26,2=270.000000
L 3.0856997 3.0640997 3.08983406 3.06333317 1 P 0 ;0,1=26,2=270.000000
L 3.08983406 3.06333317 3.0934499 3.0640997 1 P 0 ;0,1=26,2=270.000000
L 3.0934499 3.0640997 3.09706673 3.06601663 1 P 0 ;0,1=26,2=270.000000
L 3.09706673 3.06601663 3.09913396 3.06831683 1 P 0 ;0,1=26,2=270.000000
L 3.09913396 3.06831683 3.09965049 3.07099961 1 P 0 ;0,1=26,2=270.000000
L 3.09965049 3.07099961 3.09861732 3.07406634 1 P 0 ;0,1=26,2=270.000000
L 3.09861732 3.07406634 3.09603366 3.07636654 1 P 0 ;0,1=26,2=270.000000
L 3.09603366 3.07636654 3.09138366 3.07866673 1 P 0 ;0,1=26,2=270.000000
L 1.394 3.62 1.394 3.078 1 P 0 
L 0.852 3.62 1.394 3.62 1 P 0 
L 0.852 3.078 0.852 3.62 1 P 0 
L 1.394 3.078 0.852 3.078 1 P 0 
S P 0
OB 1.303219980315 3.650019980315 I
OC 1.303219980315 3.650019980315 1.283219980315 3.650019980315 Y
OE
SE
L 1.42393317 3.52491594 1.4257999 3.52783346 1 P 0 ;0,1=27,2=0.000000
L 1.4257999 3.52783346 1.4274 3.5294998 1 P 0 ;0,1=27,2=0.000000
L 1.4274 3.5294998 1.42953337 3.53033297 1 P 0 ;0,1=27,2=0.000000
L 1.42953337 3.53033297 1.4314002 3.5294998 1 P 0 ;0,1=27,2=0.000000
L 1.4314002 3.5294998 1.43273327 3.52783346 1 P 0 ;0,1=27,2=0.000000
L 1.43273327 3.52783346 1.4338001 3.52533327 1 P 0 ;0,1=27,2=0.000000
L 1.4338001 3.52533327 1.43406673 3.52241644 1 P 0 ;0,1=27,2=0.000000
L 1.43406673 3.52241644 1.4338001 3.51991624 1 P 0 ;0,1=27,2=0.000000
L 1.4338001 3.51991624 1.43273327 3.51741604 1 P 0 ;0,1=27,2=0.000000
L 1.43273327 3.51741604 1.43113307 3.51533307 1 P 0 ;0,1=27,2=0.000000
L 1.43113307 3.51533307 1.42926683 3.5145 1 P 0 ;0,1=27,2=0.000000
L 1.42926683 3.5145 1.42713346 3.51533307 1 P 0 ;0,1=27,2=0.000000
L 1.42713346 3.51533307 1.42526663 3.51783258 1 P 0 ;0,1=27,2=0.000000
L 1.42526663 3.51783258 1.4241998 3.52158327 1 P 0 ;0,1=27,2=0.000000
L 1.4241998 3.52158327 1.42393317 3.5257498 1 P 0 ;0,1=27,2=0.000000
L 1.42393317 3.5257498 1.42446634 3.53116614 1 P 0 ;0,1=27,2=0.000000
L 1.42446634 3.53116614 1.42526663 3.53408366 1 P 0 ;0,1=27,2=0.000000
L 1.42526663 3.53408366 1.4265997 3.5369997 1 P 0 ;0,1=27,2=0.000000
L 1.4265997 3.5369997 1.42846654 3.53908337 1 P 0 ;0,1=27,2=0.000000
L 1.42846654 3.53908337 1.43033327 3.5395 1 P 0 ;0,1=27,2=0.000000
L 1.43033327 3.5395 1.4322 3.53866683 1 P 0 ;0,1=27,2=0.000000
L 1.4322 3.53866683 1.43353356 3.53658317 1 P 0 ;0,1=27,2=0.000000
L 1.4542 3.5145 1.4542 3.5395 1 P 0 ;0,1=27,2=0.000000
L 1.4542 3.5395 1.44433297 3.52158327 1 P 0 ;0,1=27,2=0.000000
L 1.44433297 3.52158327 1.45766693 3.52158327 1 P 0 ;0,1=27,2=0.000000
L 1.4245 3.36556663 1.44671673 3.36556663 1 P 0 ;0,1=28,2=270.000000
L 1.44671673 3.36556663 1.45136762 3.3670997 1 P 0 ;0,1=28,2=270.000000
L 1.45136762 3.3670997 1.45446693 3.37016634 1 P 0 ;0,1=28,2=270.000000
L 1.45446693 3.37016634 1.4555 3.37399961 1 P 0 ;0,1=28,2=270.000000
L 1.4555 3.37399961 1.45446693 3.37783356 1 P 0 ;0,1=28,2=270.000000
L 1.45446693 3.37783356 1.45136762 3.3809002 1 P 0 ;0,1=28,2=270.000000
L 1.45136762 3.3809002 1.44671673 3.38243327 1 P 0 ;0,1=28,2=270.000000
L 1.44671673 3.38243327 1.4245 3.38243327 1 P 0 ;0,1=28,2=270.000000
L 1.4555 3.40499961 1.4245 3.40499961 1 P 0 ;0,1=28,2=270.000000
L 1.4245 3.40499961 1.4306997 3.4003999 1 P 0 ;0,1=28,2=270.000000
L 1.4555 3.4003999 1.4555 3.40959931 1 P 0 ;0,1=28,2=270.000000
L 1.4555 3.43599961 1.45498346 3.43868307 1 P 0 ;0,1=28,2=270.000000
L 1.45498346 3.43868307 1.45343386 3.4417498 1 P 0 ;0,1=28,2=270.000000
L 1.45343386 3.4417498 1.45085108 3.44366673 1 P 0 ;0,1=28,2=270.000000
L 1.45085108 3.44366673 1.44723327 3.44443327 1 P 0 ;0,1=28,2=270.000000
L 1.44723327 3.44443327 1.44361732 3.44366673 1 P 0 ;0,1=28,2=270.000000
L 1.44361732 3.44366673 1.44051713 3.44136654 1 P 0 ;0,1=28,2=270.000000
L 1.44051713 3.44136654 1.43896644 3.43791654 1 P 0 ;0,1=28,2=270.000000
L 1.43896644 3.43791654 1.43896644 3.43408337 1 P 0 ;0,1=28,2=270.000000
L 1.43896644 3.43408337 1.43793337 3.43178317 1 P 0 ;0,1=28,2=270.000000
L 1.43793337 3.43178317 1.43535059 3.42986614 1 P 0 ;0,1=28,2=270.000000
L 1.43535059 3.42986614 1.43173376 3.4290997 1 P 0 ;0,1=28,2=270.000000
L 1.43173376 3.4290997 1.42811693 3.4302501 1 P 0 ;0,1=28,2=270.000000
L 1.42811693 3.4302501 1.42553317 3.43293287 1 P 0 ;0,1=28,2=270.000000
L 1.42553317 3.43293287 1.4245 3.43599961 1 P 0 ;0,1=28,2=270.000000
L 1.4245 3.43599961 1.42553317 3.43906634 1 P 0 ;0,1=28,2=270.000000
L 1.42553317 3.43906634 1.42811693 3.4417498 1 P 0 ;0,1=28,2=270.000000
L 1.42811693 3.4417498 1.43173376 3.4429002 1 P 0 ;0,1=28,2=270.000000
L 1.43173376 3.4429002 1.43535059 3.44213307 1 P 0 ;0,1=28,2=270.000000
L 1.43535059 3.44213307 1.43793337 3.44021673 1 P 0 ;0,1=28,2=270.000000
L 1.43793337 3.44021673 1.43896644 3.43791654 1 P 0 ;0,1=28,2=270.000000
L 1.43896644 3.43791654 1.43896644 3.43408337 1 P 0 ;0,1=28,2=270.000000
L 1.43896644 3.43408337 1.44051713 3.43063337 1 P 0 ;0,1=28,2=270.000000
L 1.44051713 3.43063337 1.44361732 3.42833317 1 P 0 ;0,1=28,2=270.000000
L 1.44361732 3.42833317 1.44723327 3.42756663 1 P 0 ;0,1=28,2=270.000000
L 1.44723327 3.42756663 1.45085108 3.42833317 1 P 0 ;0,1=28,2=270.000000
L 1.45085108 3.42833317 1.45343386 3.4302501 1 P 0 ;0,1=28,2=270.000000
L 1.45343386 3.4302501 1.45498346 3.43331683 1 P 0 ;0,1=28,2=270.000000
L 1.45498346 3.43331683 1.4555 3.43599961 1 P 0 ;0,1=28,2=270.000000
L 1.4225 3.1622 1.3975 3.1622 1 P 0 ;0,1=29,2=270.000000
L 1.3975 3.1622 1.41541673 3.15233297 1 P 0 ;0,1=29,2=270.000000
L 1.41541673 3.15233297 1.41541673 3.16566693 1 P 0 ;0,1=29,2=270.000000
L 1.41958396 3.17646634 1.42166693 3.17833317 1 P 0 ;0,1=29,2=270.000000
L 1.42166693 3.17833317 1.4225 3.18046654 1 P 0 ;0,1=29,2=270.000000
L 1.4225 3.18046654 1.42166693 3.1825999 1 P 0 ;0,1=29,2=270.000000
L 1.42166693 3.1825999 1.41916742 3.18446663 1 P 0 ;0,1=29,2=270.000000
L 1.41916742 3.18446663 1.41541673 3.1858001 1 P 0 ;0,1=29,2=270.000000
L 1.41541673 3.1858001 1.41166673 3.18633337 1 P 0 ;0,1=29,2=270.000000
L 1.41166673 3.18633337 1.40708366 3.18633337 1 P 0 ;0,1=29,2=270.000000
L 1.40708366 3.18633337 1.40333366 3.1858001 1 P 0 ;0,1=29,2=270.000000
L 1.40333366 3.1858001 1.4000003 3.18446663 1 P 0 ;0,1=29,2=270.000000
L 1.4000003 3.18446663 1.39833317 3.18286644 1 P 0 ;0,1=29,2=270.000000
L 1.39833317 3.18286644 1.3975 3.1809997 1 P 0 ;0,1=29,2=270.000000
L 1.3975 3.1809997 1.39833317 3.17886634 1 P 0 ;0,1=29,2=270.000000
L 1.39833317 3.17886634 1.4000003 3.17726663 1 P 0 ;0,1=29,2=270.000000
L 1.4000003 3.17726663 1.4024997 3.1761998 1 P 0 ;0,1=29,2=270.000000
L 1.4024997 3.1761998 1.40583386 3.17566654 1 P 0 ;0,1=29,2=270.000000
L 1.40583386 3.17566654 1.4087499 3.1761998 1 P 0 ;0,1=29,2=270.000000
L 1.4087499 3.1761998 1.41166673 3.17753327 1 P 0 ;0,1=29,2=270.000000
L 1.41166673 3.17753327 1.41333386 3.17913346 1 P 0 ;0,1=29,2=270.000000
L 1.41333386 3.17913346 1.41375039 3.1809997 1 P 0 ;0,1=29,2=270.000000
L 1.41375039 3.1809997 1.41291722 3.18313307 1 P 0 ;0,1=29,2=270.000000
L 1.41291722 3.18313307 1.41083356 3.18473327 1 P 0 ;0,1=29,2=270.000000
L 1.41083356 3.18473327 1.40708366 3.18633337 1 P 0 ;0,1=29,2=270.000000
L 1.2772 3.0375 1.2772 3.0625 1 P 0 ;0,1=30,2=0.000000
L 1.2772 3.0625 1.26733297 3.04458327 1 P 0 ;0,1=30,2=0.000000
L 1.26733297 3.04458327 1.28066693 3.04458327 1 P 0 ;0,1=30,2=0.000000
L 1.2959997 3.0375 1.29786644 3.03791654 1 P 0 ;0,1=30,2=0.000000
L 1.29786644 3.03791654 1.2999998 3.03916624 1 P 0 ;0,1=30,2=0.000000
L 1.2999998 3.03916624 1.30133337 3.04124911 1 P 0 ;0,1=30,2=0.000000
L 1.30133337 3.04124911 1.30186663 3.04416673 1 P 0 ;0,1=30,2=0.000000
L 1.30186663 3.04416673 1.30133337 3.04708278 1 P 0 ;0,1=30,2=0.000000
L 1.30133337 3.04708278 1.29973327 3.04958297 1 P 0 ;0,1=30,2=0.000000
L 1.29973327 3.04958297 1.29733327 3.05083346 1 P 0 ;0,1=30,2=0.000000
L 1.29733327 3.05083346 1.29466663 3.05083346 1 P 0 ;0,1=30,2=0.000000
L 1.29466663 3.05083346 1.29306654 3.05166663 1 P 0 ;0,1=30,2=0.000000
L 1.29306654 3.05166663 1.29173297 3.05374951 1 P 0 ;0,1=30,2=0.000000
L 1.29173297 3.05374951 1.2911998 3.05666634 1 P 0 ;0,1=30,2=0.000000
L 1.2911998 3.05666634 1.2920001 3.05958317 1 P 0 ;0,1=30,2=0.000000
L 1.2920001 3.05958317 1.29386634 3.06166683 1 P 0 ;0,1=30,2=0.000000
L 1.29386634 3.06166683 1.2959997 3.0625 1 P 0 ;0,1=30,2=0.000000
L 1.2959997 3.0625 1.29813307 3.06166683 1 P 0 ;0,1=30,2=0.000000
L 1.29813307 3.06166683 1.2999998 3.05958317 1 P 0 ;0,1=30,2=0.000000
L 1.2999998 3.05958317 1.3008001 3.05666634 1 P 0 ;0,1=30,2=0.000000
L 1.3008001 3.05666634 1.30026644 3.05374951 1 P 0 ;0,1=30,2=0.000000
L 1.30026644 3.05374951 1.29893337 3.05166663 1 P 0 ;0,1=30,2=0.000000
L 1.29893337 3.05166663 1.29733327 3.05083346 1 P 0 ;0,1=30,2=0.000000
L 1.29733327 3.05083346 1.29466663 3.05083346 1 P 0 ;0,1=30,2=0.000000
L 1.29466663 3.05083346 1.29226663 3.04958297 1 P 0 ;0,1=30,2=0.000000
L 1.29226663 3.04958297 1.29066654 3.04708278 1 P 0 ;0,1=30,2=0.000000
L 1.29066654 3.04708278 1.29013327 3.04416673 1 P 0 ;0,1=30,2=0.000000
L 1.29013327 3.04416673 1.29066654 3.04124911 1 P 0 ;0,1=30,2=0.000000
L 1.29066654 3.04124911 1.2920001 3.03916624 1 P 0 ;0,1=30,2=0.000000
L 1.2920001 3.03916624 1.29413346 3.03791654 1 P 0 ;0,1=30,2=0.000000
L 1.29413346 3.03791654 1.2959997 3.0375 1 P 0 ;0,1=30,2=0.000000
L 0.9639997 3.6275 0.9639997 3.6525 1 P 0 ;0,1=13,2=0.000000
L 0.9639997 3.6525 0.9607999 3.6475003 1 P 0 ;0,1=13,2=0.000000
L 0.9607999 3.6275 0.96719951 3.6275 1 P 0 ;0,1=13,2=0.000000
L 0.98093317 3.63791594 0.9827999 3.64083346 1 P 0 ;0,1=13,2=0.000000
L 0.9827999 3.64083346 0.9844 3.6424998 1 P 0 ;0,1=13,2=0.000000
L 0.9844 3.6424998 0.98653337 3.64333297 1 P 0 ;0,1=13,2=0.000000
L 0.98653337 3.64333297 0.9884002 3.6424998 1 P 0 ;0,1=13,2=0.000000
L 0.9884002 3.6424998 0.98973327 3.64083346 1 P 0 ;0,1=13,2=0.000000
L 0.98973327 3.64083346 0.9908001 3.63833327 1 P 0 ;0,1=13,2=0.000000
L 0.9908001 3.63833327 0.99106673 3.63541644 1 P 0 ;0,1=13,2=0.000000
L 0.99106673 3.63541644 0.9908001 3.63291624 1 P 0 ;0,1=13,2=0.000000
L 0.9908001 3.63291624 0.98973327 3.63041604 1 P 0 ;0,1=13,2=0.000000
L 0.98973327 3.63041604 0.98813307 3.62833307 1 P 0 ;0,1=13,2=0.000000
L 0.98813307 3.62833307 0.98626683 3.6275 1 P 0 ;0,1=13,2=0.000000
L 0.98626683 3.6275 0.98413346 3.62833307 1 P 0 ;0,1=13,2=0.000000
L 0.98413346 3.62833307 0.98226663 3.63083258 1 P 0 ;0,1=13,2=0.000000
L 0.98226663 3.63083258 0.9811998 3.63458327 1 P 0 ;0,1=13,2=0.000000
L 0.9811998 3.63458327 0.98093317 3.6387498 1 P 0 ;0,1=13,2=0.000000
L 0.98093317 3.6387498 0.98146634 3.64416614 1 P 0 ;0,1=13,2=0.000000
L 0.98146634 3.64416614 0.98226663 3.64708366 1 P 0 ;0,1=13,2=0.000000
L 0.98226663 3.64708366 0.9835997 3.6499997 1 P 0 ;0,1=13,2=0.000000
L 0.9835997 3.6499997 0.98546654 3.65208337 1 P 0 ;0,1=13,2=0.000000
L 0.98546654 3.65208337 0.98733327 3.6525 1 P 0 ;0,1=13,2=0.000000
L 0.98733327 3.6525 0.9892 3.65166683 1 P 0 ;0,1=13,2=0.000000
L 0.9892 3.65166683 0.99053356 3.64958317 1 P 0 ;0,1=13,2=0.000000
L 0.94813327 3.04749961 0.94973297 3.04458287 1 P 0 ;0,1=31,2=0.000000
L 0.94973297 3.04458287 0.95186634 3.04291654 1 P 0 ;0,1=31,2=0.000000
L 0.95186634 3.04291654 0.95426683 3.0425 1 P 0 ;0,1=31,2=0.000000
L 0.95426683 3.0425 0.9564002 3.04291654 1 P 0 ;0,1=31,2=0.000000
L 0.9564002 3.04291654 0.95853356 3.04499941 1 P 0 ;0,1=31,2=0.000000
L 0.95853356 3.04499941 0.95986663 3.04749961 1 P 0 ;0,1=31,2=0.000000
L 0.95986663 3.04749961 0.96013317 3.0499999 1 P 0 ;0,1=31,2=0.000000
L 0.96013317 3.0499999 0.9596 3.05291594 1 P 0 ;0,1=31,2=0.000000
L 0.9596 3.05291594 0.95773327 3.05499961 1 P 0 ;0,1=31,2=0.000000
L 0.95773327 3.05499961 0.95586644 3.05583346 1 P 0 ;0,1=31,2=0.000000
L 0.95586644 3.05583346 0.95346654 3.05583346 1 P 0 ;0,1=31,2=0.000000
L 0.95586644 3.05583346 0.95746663 3.05708327 1 P 0 ;0,1=31,2=0.000000
L 0.95746663 3.05708327 0.9588001 3.05916614 1 P 0 ;0,1=31,2=0.000000
L 0.9588001 3.05916614 0.95933337 3.06166634 1 P 0 ;0,1=31,2=0.000000
L 0.95933337 3.06166634 0.9588001 3.06416654 1 P 0 ;0,1=31,2=0.000000
L 0.9588001 3.06416654 0.95746663 3.06624941 1 P 0 ;0,1=31,2=0.000000
L 0.95746663 3.06624941 0.95506663 3.0675 1 P 0 ;0,1=31,2=0.000000
L 0.95506663 3.0675 0.95266663 3.06708337 1 P 0 ;0,1=31,2=0.000000
L 0.95266663 3.06708337 0.95026663 3.06541634 1 P 0 ;0,1=31,2=0.000000
L 0.97013327 3.04749961 0.97173297 3.04458287 1 P 0 ;0,1=31,2=0.000000
L 0.97173297 3.04458287 0.97386634 3.04291654 1 P 0 ;0,1=31,2=0.000000
L 0.97386634 3.04291654 0.97626683 3.0425 1 P 0 ;0,1=31,2=0.000000
L 0.97626683 3.0425 0.9784002 3.04291654 1 P 0 ;0,1=31,2=0.000000
L 0.9784002 3.04291654 0.98053356 3.04499941 1 P 0 ;0,1=31,2=0.000000
L 0.98053356 3.04499941 0.98186663 3.04749961 1 P 0 ;0,1=31,2=0.000000
L 0.98186663 3.04749961 0.98213317 3.0499999 1 P 0 ;0,1=31,2=0.000000
L 0.98213317 3.0499999 0.9816 3.05291594 1 P 0 ;0,1=31,2=0.000000
L 0.9816 3.05291594 0.97973327 3.05499961 1 P 0 ;0,1=31,2=0.000000
L 0.97973327 3.05499961 0.97786644 3.05583346 1 P 0 ;0,1=31,2=0.000000
L 0.97786644 3.05583346 0.97546654 3.05583346 1 P 0 ;0,1=31,2=0.000000
L 0.97786644 3.05583346 0.97946663 3.05708327 1 P 0 ;0,1=31,2=0.000000
L 0.97946663 3.05708327 0.9808001 3.05916614 1 P 0 ;0,1=31,2=0.000000
L 0.9808001 3.05916614 0.98133337 3.06166634 1 P 0 ;0,1=31,2=0.000000
L 0.98133337 3.06166634 0.9808001 3.06416654 1 P 0 ;0,1=31,2=0.000000
L 0.9808001 3.06416654 0.97946663 3.06624941 1 P 0 ;0,1=31,2=0.000000
L 0.97946663 3.06624941 0.97706663 3.0675 1 P 0 ;0,1=31,2=0.000000
L 0.97706663 3.0675 0.97466663 3.06708337 1 P 0 ;0,1=31,2=0.000000
L 0.97466663 3.06708337 0.97226663 3.06541634 1 P 0 ;0,1=31,2=0.000000
L 0.8455 3.4839997 0.8205 3.4839997 1 P 0 ;0,1=32,2=270.000000
L 0.8205 3.4839997 0.8254997 3.4807999 1 P 0 ;0,1=32,2=270.000000
L 0.8455 3.4807999 0.8455 3.48719951 1 P 0 ;0,1=32,2=270.000000
L 0.8455 3.50546654 0.84008376 3.5059997 1 P 0 ;0,1=32,2=270.000000
L 0.84008376 3.5059997 0.83550069 3.5068 1 P 0 ;0,1=32,2=270.000000
L 0.83550069 3.5068 0.83133337 3.50786644 1 P 0 ;0,1=32,2=270.000000
L 0.83133337 3.50786644 0.8267502 3.5092 1 P 0 ;0,1=32,2=270.000000
L 0.8267502 3.5092 0.8205 3.51133337 1 P 0 ;0,1=32,2=270.000000
L 0.8205 3.51133337 0.8205 3.50066654 1 P 0 ;0,1=32,2=270.000000
L 0.81313327 3.18749961 0.81473297 3.18458287 1 P 0 ;0,1=33,2=0.000000
L 0.81473297 3.18458287 0.81686634 3.18291654 1 P 0 ;0,1=33,2=0.000000
L 0.81686634 3.18291654 0.81926683 3.1825 1 P 0 ;0,1=33,2=0.000000
L 0.81926683 3.1825 0.8214002 3.18291654 1 P 0 ;0,1=33,2=0.000000
L 0.8214002 3.18291654 0.82353356 3.18499941 1 P 0 ;0,1=33,2=0.000000
L 0.82353356 3.18499941 0.82486663 3.18749961 1 P 0 ;0,1=33,2=0.000000
L 0.82486663 3.18749961 0.82513317 3.1899999 1 P 0 ;0,1=33,2=0.000000
L 0.82513317 3.1899999 0.8246 3.19291594 1 P 0 ;0,1=33,2=0.000000
L 0.8246 3.19291594 0.82273327 3.19499961 1 P 0 ;0,1=33,2=0.000000
L 0.82273327 3.19499961 0.82086644 3.19583346 1 P 0 ;0,1=33,2=0.000000
L 0.82086644 3.19583346 0.81846654 3.19583346 1 P 0 ;0,1=33,2=0.000000
L 0.82086644 3.19583346 0.82246663 3.19708327 1 P 0 ;0,1=33,2=0.000000
L 0.82246663 3.19708327 0.8238001 3.19916614 1 P 0 ;0,1=33,2=0.000000
L 0.8238001 3.19916614 0.82433337 3.20166634 1 P 0 ;0,1=33,2=0.000000
L 0.82433337 3.20166634 0.8238001 3.20416654 1 P 0 ;0,1=33,2=0.000000
L 0.8238001 3.20416654 0.82246663 3.20624941 1 P 0 ;0,1=33,2=0.000000
L 0.82246663 3.20624941 0.82006663 3.2075 1 P 0 ;0,1=33,2=0.000000
L 0.82006663 3.2075 0.81766663 3.20708337 1 P 0 ;0,1=33,2=0.000000
L 0.81766663 3.20708337 0.81526663 3.20541634 1 P 0 ;0,1=33,2=0.000000
L 0.83593317 3.20333337 0.83753327 3.20583287 1 P 0 ;0,1=33,2=0.000000
L 0.83753327 3.20583287 0.8394 3.20708337 1 P 0 ;0,1=33,2=0.000000
L 0.8394 3.20708337 0.84153337 3.2075 1 P 0 ;0,1=33,2=0.000000
L 0.84153337 3.2075 0.8442 3.20666683 1 P 0 ;0,1=33,2=0.000000
L 0.8442 3.20666683 0.84606673 3.20458317 1 P 0 ;0,1=33,2=0.000000
L 0.84606673 3.20458317 0.8466 3.20208366 1 P 0 ;0,1=33,2=0.000000
L 0.8466 3.20208366 0.84633337 3.19958268 1 P 0 ;0,1=33,2=0.000000
L 0.84633337 3.19958268 0.84526644 3.1974998 1 P 0 ;0,1=33,2=0.000000
L 0.84526644 3.1974998 0.83993327 3.19333327 1 P 0 ;0,1=33,2=0.000000
L 0.83993327 3.19333327 0.83753327 3.19041644 1 P 0 ;0,1=33,2=0.000000
L 0.83753327 3.19041644 0.83593317 3.18624911 1 P 0 ;0,1=33,2=0.000000
L 0.83593317 3.18624911 0.8353999 3.1825 1 P 0 ;0,1=33,2=0.000000
L 0.8353999 3.1825 0.8466 3.1825 1 P 0 ;0,1=33,2=0.000000
L 5.74283002 2.01328996 5.74283002 1.66271998 1 P 0 
L 5.45116998 2.01328996 5.74283002 2.01328996 1 P 0 
L 5.74283002 1.66271998 5.45116998 1.66271998 1 P 0 
L 5.45116998 1.66271998 5.45116998 2.01328996 1 P 0 
L 5.76771644 1.70033346 5.77001663 1.70343278 1 P 0 ;0,1=4,2=0.000000
L 5.77001663 1.70343278 5.7727001 1.70498337 1 P 0 ;0,1=4,2=0.000000
L 5.7727001 1.70498337 5.77576683 1.7055 1 P 0 ;0,1=4,2=0.000000
L 5.77576683 1.7055 5.7796 1.70446683 1 P 0 ;0,1=4,2=0.000000
L 5.7796 1.70446683 5.78228346 1.70188307 1 P 0 ;0,1=4,2=0.000000
L 5.78228346 1.70188307 5.78305 1.69878376 1 P 0 ;0,1=4,2=0.000000
L 5.78305 1.69878376 5.78266673 1.69568258 1 P 0 ;0,1=4,2=0.000000
L 5.78266673 1.69568258 5.78113307 1.6930998 1 P 0 ;0,1=4,2=0.000000
L 5.78113307 1.6930998 5.77346663 1.68793327 1 P 0 ;0,1=4,2=0.000000
L 5.77346663 1.68793327 5.77001663 1.68431644 1 P 0 ;0,1=4,2=0.000000
L 5.77001663 1.68431644 5.76771644 1.67914892 1 P 0 ;0,1=4,2=0.000000
L 5.76771644 1.67914892 5.7669499 1.6745 1 P 0 ;0,1=4,2=0.000000
L 5.7669499 1.6745 5.78305 1.6745 1 P 0 ;0,1=4,2=0.000000
L 5.7549997 1.9625 5.7549997 1.9875 1 P 0 ;0,1=2,2=0.000000
L 5.7549997 1.9875 5.7517999 1.9825003 1 P 0 ;0,1=2,2=0.000000
L 5.7517999 1.9625 5.75819951 1.9625 1 P 0 ;0,1=2,2=0.000000
L 5.45183317 1.6455 5.45183317 1.6145 1 P 0 ;0,1=34,2=0.000000
L 5.45183317 1.6145 5.46716673 1.6145 1 P 0 ;0,1=34,2=0.000000
L 5.48206663 1.61914892 5.48436614 1.61656614 1 P 0 ;0,1=34,2=0.000000
L 5.48436614 1.61656614 5.48704961 1.61501654 1 P 0 ;0,1=34,2=0.000000
L 5.48704961 1.61501654 5.49049961 1.6145 1 P 0 ;0,1=34,2=0.000000
L 5.49049961 1.6145 5.4939503 1.61553307 1 P 0 ;0,1=34,2=0.000000
L 5.4939503 1.61553307 5.49663307 1.61759931 1 P 0 ;0,1=34,2=0.000000
L 5.49663307 1.61759931 5.49855 1.62121614 1 P 0 ;0,1=34,2=0.000000
L 5.49855 1.62121614 5.49893327 1.62534951 1 P 0 ;0,1=34,2=0.000000
L 5.49893327 1.62534951 5.49816673 1.62948287 1 P 0 ;0,1=34,2=0.000000
L 5.49816673 1.62948287 5.4962498 1.63206663 1 P 0 ;0,1=34,2=0.000000
L 5.4962498 1.63206663 5.49356634 1.63413287 1 P 0 ;0,1=34,2=0.000000
L 5.49356634 1.63413287 5.49088356 1.63464941 1 P 0 ;0,1=34,2=0.000000
L 5.49088356 1.63464941 5.4882001 1.63413287 1 P 0 ;0,1=34,2=0.000000
L 5.4882001 1.63413287 5.4847501 1.63206663 1 P 0 ;0,1=34,2=0.000000
L 5.4847501 1.63206663 5.4858999 1.6455 1 P 0 ;0,1=34,2=0.000000
L 5.4858999 1.6455 5.4962498 1.6455 1 P 0 ;0,1=34,2=0.000000
L 4.4645 3.611 4.502 3.611 1 P 0 
L 4.4645 3.656 4.4645 3.611 1 P 0 
L 4.4055 3.656 4.4645 3.656 1 P 0 
L 4.4055 3.611 4.4055 3.656 1 P 0 
L 4.368 3.611 4.4055 3.611 1 P 0 
L 4.502 3.611 4.502 3.494 1 P 0 
L 4.368 3.494 4.368 3.611 1 P 0 
L 4.4275 3.494 4.368 3.494 1 P 0 
L 4.4275 3.539 4.4275 3.494 1 P 0 
L 4.4425 3.539 4.4275 3.539 1 P 0 
L 4.4425 3.494 4.4425 3.539 1 P 0 
L 4.502 3.494 4.4425 3.494 1 P 0 
S P 0
OB 4.40536003937 3.47128996063 I
OC 4.40536003937 3.47128996063 4.39036003937 3.47128996063 Y
OE
SE
L 4.52449961 3.5645 4.52143287 3.56501654 1 P 0 ;0,1=35,2=0.000000
L 4.52143287 3.56501654 4.5187501 3.56708278 1 P 0 ;0,1=35,2=0.000000
L 4.5187501 3.56708278 4.5164499 3.57018297 1 P 0 ;0,1=35,2=0.000000
L 4.5164499 3.57018297 4.51491624 3.5737999 1 P 0 ;0,1=35,2=0.000000
L 4.51491624 3.5737999 4.5141497 3.57793327 1 P 0 ;0,1=35,2=0.000000
L 4.5141497 3.57793327 4.5141497 3.58206663 1 P 0 ;0,1=35,2=0.000000
L 4.5141497 3.58206663 4.51491624 3.5862 1 P 0 ;0,1=35,2=0.000000
L 4.51491624 3.5862 4.5164499 3.58981693 1 P 0 ;0,1=35,2=0.000000
L 4.5164499 3.58981693 4.5187501 3.59291624 1 P 0 ;0,1=35,2=0.000000
L 4.5187501 3.59291624 4.52143287 3.59498337 1 P 0 ;0,1=35,2=0.000000
L 4.52143287 3.59498337 4.52449961 3.5955 1 P 0 ;0,1=35,2=0.000000
L 4.52449961 3.5955 4.52756634 3.59498337 1 P 0 ;0,1=35,2=0.000000
L 4.52756634 3.59498337 4.5302498 3.59291624 1 P 0 ;0,1=35,2=0.000000
L 4.5302498 3.59291624 4.53255 3.58981693 1 P 0 ;0,1=35,2=0.000000
L 4.53255 3.58981693 4.53408366 3.5862 1 P 0 ;0,1=35,2=0.000000
L 4.53408366 3.5862 4.5348502 3.58206663 1 P 0 ;0,1=35,2=0.000000
L 4.5348502 3.58206663 4.5348502 3.57793327 1 P 0 ;0,1=35,2=0.000000
L 4.5348502 3.57793327 4.53408366 3.5737999 1 P 0 ;0,1=35,2=0.000000
L 4.53408366 3.5737999 4.53255 3.57018297 1 P 0 ;0,1=35,2=0.000000
L 4.53255 3.57018297 4.5302498 3.56708278 1 P 0 ;0,1=35,2=0.000000
L 4.5302498 3.56708278 4.52756634 3.56501654 1 P 0 ;0,1=35,2=0.000000
L 4.52756634 3.56501654 4.52449961 3.5645 1 P 0 ;0,1=35,2=0.000000
L 4.52756634 3.57276673 4.53216673 3.5645 1 P 0 ;0,1=35,2=0.000000
L 4.55549961 3.5645 4.55549961 3.5955 1 P 0 ;0,1=35,2=0.000000
L 4.55549961 3.5955 4.5508999 3.5893003 1 P 0 ;0,1=35,2=0.000000
L 4.5508999 3.5645 4.56009931 3.5645 1 P 0 ;0,1=35,2=0.000000
L 4.49271644 3.48033346 4.49501663 3.48343278 1 P 0 ;0,1=4,2=0.000000
L 4.49501663 3.48343278 4.4977001 3.48498337 1 P 0 ;0,1=4,2=0.000000
L 4.4977001 3.48498337 4.50076683 3.4855 1 P 0 ;0,1=4,2=0.000000
L 4.50076683 3.4855 4.5046 3.48446683 1 P 0 ;0,1=4,2=0.000000
L 4.5046 3.48446683 4.50728346 3.48188307 1 P 0 ;0,1=4,2=0.000000
L 4.50728346 3.48188307 4.50805 3.47878376 1 P 0 ;0,1=4,2=0.000000
L 4.50805 3.47878376 4.50766673 3.47568258 1 P 0 ;0,1=4,2=0.000000
L 4.50766673 3.47568258 4.50613307 3.4730998 1 P 0 ;0,1=4,2=0.000000
L 4.50613307 3.4730998 4.49846663 3.46793327 1 P 0 ;0,1=4,2=0.000000
L 4.49846663 3.46793327 4.49501663 3.46431644 1 P 0 ;0,1=4,2=0.000000
L 4.49501663 3.46431644 4.49271644 3.45914892 1 P 0 ;0,1=4,2=0.000000
L 4.49271644 3.45914892 4.4919499 3.4545 1 P 0 ;0,1=4,2=0.000000
L 4.4919499 3.4545 4.50805 3.4545 1 P 0 ;0,1=4,2=0.000000
L 3.16 -0.655 3.16 -1.58 2 P 0 
L 1.36 -0.655 1.36 -1.58 2 P 0 
L 1.36 -1.58 5.06 -1.58 2 P 0 
L 5.06 -1.58 5.06 -0.655 2 P 0 
L 5.06 -0.655 1.36 -0.655 2 P 0 
A 1.559 -1.33655 1.559 -1.33655 1.55268002 -1.33655 1 P 0 N
A 1.54775 -1.205 1.54775 -1.205 1.53883002 -1.205 1 P 0 N
A 1.54763996 -0.99775 1.54763996 -0.99775 1.53871998 -0.99775 1 P 0 N
A 1.54063996 -1.10118002 1.54063996 -1.10118002 1.52603996 -1.10118002 1 P 0 N
A 1.49695 -1.10118002 1.49695 -1.10118002 1.48656998 -1.10118002 1 P 0 N
A 1.45963996 -1.10118002 1.45963996 -1.10118002 1.4533 -1.10118002 1 P 0 N
A 1.52135 -0.98681004 1.52135 -0.98681004 1.51503002 -0.98681004 1 P 0 N
A 1.79433002 -1.43586998 1.79433002 -1.43586998 1.78798996 -1.43586998 1 P 0 N
A 1.79841004 -1.40261004 1.79841004 -1.40261004 1.78798996 -1.40261004 1 P 0 N
A 1.80255 -1.36311004 1.80255 -1.36311004 1.78798996 -1.36311004 1 P 0 N
A 1.80668996 -1.31528002 1.80668996 -1.31528002 1.78798996 -1.31528002 1 P 0 N
A 1.68013002 -1.37456004 1.68013002 -1.37456004 1.67378996 -1.37456004 1 P 0 N
A 1.69321998 -1.35033002 1.69321998 -1.35033002 1.6843 -1.35033002 1 P 0 N
A 1.7108 -1.31738996 1.7108 -1.31738996 1.69798002 -1.31738996 1 P 0 N
A 1.89666998 -1.31511004 1.89666998 -1.31511004 1.88383996 -1.31511004 1 P 0 N
A 1.88198996 -1.16876004 1.88198996 -1.16876004 1.85558996 -1.16876004 1 P 0 N
A 1.87928002 -1.27801998 1.87928002 -1.27801998 1.86343996 -1.27801998 1 P 0 N
A 1.86176998 -1.23075 1.86176998 -1.23075 1.84206004 -1.23075 1 P 0 N
A 1.80978996 -1.25916998 1.80978996 -1.25916998 1.78798996 -1.25916998 1 P 0 N
A 1.74681004 -1.16876004 1.74681004 -1.16876004 1.72041004 -1.16876004 1 P 0 N
A 1.67813002 -1.15513002 1.67813002 -1.15513002 1.65841998 -1.15513002 1 P 0 N
A 1.73018002 -1.27816004 1.73018002 -1.27816004 1.71433996 -1.27816004 1 P 0 N
A 1.75373002 -1.23081004 1.75373002 -1.23081004 1.73405 -1.23081004 1 P 0 N
A 1.65531004 -1.25255 1.65531004 -1.25255 1.63661998 -1.25255 1 P 0 N
A 1.69808996 -1.21291998 1.69808996 -1.21291998 1.67628996 -1.21291998 1 P 0 N
A 1.81438996 -1.1968 1.81438996 -1.1968 1.78798996 -1.1968 1 P 0 N
A 1.6269 -1.1749 1.6269 -1.1749 1.61106004 -1.1749 1 P 0 N
A 1.58461004 -1.19126004 1.58461004 -1.19126004 1.57178002 -1.19126004 1 P 0 N
A 1.5853 -1.31428002 1.5853 -1.31428002 1.57488996 -1.31428002 1 P 0 N
A 1.61735 -1.28638996 1.61735 -1.28638996 1.60276998 -1.28638996 1 P 0 N
A 1.88198996 -1.03361004 1.88198996 -1.03361004 1.85558996 -1.03361004 1 P 0 N
A 1.71881004 -1.10118002 1.71881004 -1.10118002 1.69238996 -1.10118002 1 P 0 N
A 1.65183002 -1.10118002 1.65183002 -1.10118002 1.63003002 -1.10118002 1 P 0 N
A 1.67801998 -1.04738996 1.67801998 -1.04738996 1.65831004 -1.04738996 1 P 0 N
A 1.74681004 -1.03361004 1.74681004 -1.03361004 1.72041004 -1.03361004 1 P 0 N
A 1.69811998 -0.98951004 1.69811998 -0.98951004 1.67631998 -0.98951004 1 P 0 N
A 1.81438996 -1.00556004 1.81438996 -1.00556004 1.78798996 -1.00556004 1 P 0 N
A 1.59258002 -1.10118002 1.59258002 -1.10118002 1.5739 -1.10118002 1 P 0 N
A 1.58451004 -1.01148996 1.58451004 -1.01148996 1.57168002 -1.01148996 1 P 0 N
A 1.62681004 -1.02773996 1.62681004 -1.02773996 1.61096998 -1.02773996 1 P 0 N
A 1.92148002 -1.21285 1.92148002 -1.21285 1.89968002 -1.21285 1 P 0 N
A 1.92148002 -0.98951004 1.92148002 -0.98951004 1.89968002 -0.98951004 1 P 0 N
A 1.80978996 -0.9432 1.80978996 -0.9432 1.78798996 -0.9432 1 P 0 N
A 1.80668996 -0.88708002 1.80668996 -0.88708002 1.78798996 -0.88708002 1 P 0 N
A 1.80255 -0.83923996 1.80255 -0.83923996 1.78798996 -0.83923996 1 P 0 N
A 1.8919 -0.88538002 1.8919 -0.88538002 1.87906998 -0.88538002 1 P 0 N
A 1.87838996 -0.92456998 1.87838996 -0.92456998 1.86255 -0.92456998 1 P 0 N
A 1.65531004 -0.94981004 1.65531004 -0.94981004 1.63661998 -0.94981004 1 P 0 N
A 1.73123002 -0.92378002 1.73123002 -0.92378002 1.71538996 -0.92378002 1 P 0 N
A 1.71216998 -0.88443996 1.71216998 -0.88443996 1.69935 -0.88443996 1 P 0 N
A 1.86225 -0.97178002 1.86225 -0.97178002 1.84253996 -0.97178002 1 P 0 N
A 1.75451998 -0.97123996 1.75451998 -0.97123996 1.73483996 -0.97123996 1 P 0 N
A 1.61741998 -0.91601004 1.61741998 -0.91601004 1.60283996 -0.91601004 1 P 0 N
A 1.5853 -0.88808996 1.5853 -0.88808996 1.57488996 -0.88808996 1 P 0 N
A 1.79841004 -0.79975 1.79841004 -0.79975 1.78798996 -0.79975 1 P 0 N
A 1.79433002 -0.76648002 1.79433002 -0.76648002 1.78798996 -0.76648002 1 P 0 N
A 1.92135 -1.36781004 1.92135 -1.36781004 1.91503996 -1.36781004 1 P 0 N
A 1.91096004 -1.34658002 1.91096004 -1.34658002 1.90203996 -1.34658002 1 P 0 N
A 2.19078996 -1.1806 2.26591004 -1.16473002 2.21741014 -1.12088169 1 P 0 N
A 2.15903002 -1.1402 2.19078996 -1.18061004 2.22093406 -1.12423278 1 P 0 N
A 2.05721004 -1.16178996 2.08853002 -1.16658996 2.08281614 -1.09929134 1 P 0 N
A 2.00546998 -1.13951998 2.03345 -1.17196004 2.07793927 -1.10530069 1 P 0 N
A 2.03346004 -1.17195 2.0847 -1.18461004 2.07891181 -1.09801299 1 P 0 N
A 2.0847 -1.18461998 2.14261004 -1.15663002 2.07348435 -1.08751378 1 P 0 N
A 2.08853996 -1.16658002 2.13313002 -1.14451998 2.06368967 -1.06025512 1 P 0 N
A 1.95808002 -1.25255 1.95808002 -1.25255 1.93938996 -1.25255 1 P 0 N
A 1.98775 -1.28635 1.98775 -1.28635 1.97316998 -1.28635 1 P 0 N
A 2.27411998 -1.11835 2.15906004 -1.11835 2.21658996 -1.11611998 1 P 0 N
L 2.25188002 -1.11418002 2.1807 -1.11418002 1 P 0 
L 2.1807 -1.11418002 2.1807 -1.11398996 1 P 8191 
A 2.25188996 -1.11398996 2.18071004 -1.11398996 2.2163 -1.1124 1 P 0 N
A 2.08028996 -1.03428996 2.02048996 -1.08258996 2.0798126 -1.09486801 1 P 0 N
A 2.13151998 -1.05146004 2.0803 -1.0343 2.0802999 -1.11932195 1 P 0 N
A 2.1315 -1.05146998 2.14175 -1.03951004 2.1356003 -1.04461171 1 P 0 N
A 2.14175 -1.03951004 2.08283002 -1.01613002 2.07772461 -1.11492805 1 P 0 N
A 2.08283996 -1.01611998 2.00698002 -1.05835 2.08064724 -1.10143169 1 P 0 N
L 2.27413002 -1.12868996 2.18073996 -1.12868996 1 P 0 
A 2.18075 -1.12868996 2.19083002 -1.15751998 2.22417795 -1.12968307 1 P 0 N
A 2.19083002 -1.15753002 2.25311004 -1.15211004 2.21927195 -1.12381791 1 P 0 N
L 2.15903996 -1.1402 2.15903996 -1.11835 1 P 0 
A 2.02048996 -1.0826 2.05721998 -1.16181004 2.09087933 -1.0980811 1 P 0 N
A 2.00698996 -1.05836004 2.00546998 -1.13953002 2.09672953 -1.10063967 1 P 0 N
A 2.14258996 -1.15661004 2.13313996 -1.14453002 2.13544892 -1.15246004 1 P 0 N
A 1.95808002 -0.94981004 1.95808002 -0.94981004 1.93938996 -0.94981004 1 P 0 N
A 1.90183996 -0.8525 1.90183996 -0.8525 1.89291004 -0.8525 1 P 0 N
A 1.91108002 -0.82726998 1.91108002 -0.82726998 1.90473996 -0.82726998 1 P 0 N
L 2.32081004 -1.02041004 2.32081004 -1.17625 1 P 0 
A 2.49568002 -1.15528996 2.47898002 -1.16443002 2.4882003 -1.1614502 1 P 0 N
A 2.47896998 -1.16443996 2.50283002 -1.18086004 2.51649242 -1.13546152 1 P 0 N
A 2.50281998 -1.18086998 2.54318002 -1.1834 2.52887392 -1.08843022 1 P 0 N
A 2.52306998 -1.16761004 2.52848996 -1.16771998 2.52673258 -1.12070098 1 P 0 N
A 2.49566004 -1.15528996 2.52306998 -1.1676 2.5255122 -1.12549094 1 P 0 N
A 2.37851998 -1.15753002 2.4408 -1.15211004 2.40696191 -1.12381791 1 P 0 N
A 2.45358002 -1.16471998 2.44078996 -1.1521 2.44541191 -1.16020689 1 P 0 N
A 2.37848002 -1.1806 2.4536 -1.16473002 2.4051001 -1.12088169 1 P 0 N
A 2.34673002 -1.1402 2.37848996 -1.18061004 2.40863406 -1.12423278 1 P 0 N
A 2.2659 -1.16471998 2.25311004 -1.1521 2.25773199 -1.16020689 1 P 0 N
A 2.3006 -1.17626004 2.3208 -1.17626004 2.3107 -1.17386841 1 P 0 N
L 2.30058996 -1.17625 2.30058996 -1.02033996 1 P 0 
A 2.50836998 -1.10106004 2.54306004 -1.11513002 2.56106673 -1.02093386 1 P 0 N
A 2.51081004 -1.07948002 2.50836998 -1.10103996 2.51886093 -1.09130915 1 P 0 N
A 2.53611004 -1.07688996 2.5108 -1.07948996 2.52742205 -1.11680827 1 P 0 N
A 2.56883996 -1.07368002 2.50178002 -1.06358996 2.5273123 -1.12178858 1 P 0 N
A 2.50178996 -1.06358996 2.48536998 -1.08248996 2.52926211 -1.10403986 1 P 0 N
L 2.48536998 -1.0825 2.48536998 -1.09748002 1 P 0 
A 2.48536998 -1.09748002 2.49956004 -1.12031004 2.51189104 -1.09682067 1 P 0 N
A 2.46181004 -1.11835 2.34675 -1.11835 2.40428002 -1.11611998 1 P 0 N
L 2.43956998 -1.11418002 2.36841004 -1.11418002 1 P 0 
L 2.36841004 -1.11418002 2.36841004 -1.11398996 1 P 8191 
A 2.43958002 -1.11398996 2.3684 -1.11398996 2.40398996 -1.1124 1 P 0 N
L 2.43956998 -1.11398996 2.43956998 -1.11418002 1 P 8191 
A 2.49955 -1.1203 2.52723002 -1.12985 2.58163209 -0.92727982 1 P 0 N
A 2.55001998 -1.14328002 2.52723002 -1.12986004 2.51462185 -1.17733228 1 P 0 N
L 2.46181004 -1.12868996 2.36843996 -1.12868996 1 P 0 
A 2.36843996 -1.12868996 2.37851998 -1.15751998 2.41186801 -1.12968307 1 P 0 N
L 2.34675 -1.1402 2.34675 -1.11835 1 P 0 
L 2.46181004 -1.11835 2.46181004 -1.12868996 1 P 0 
L 2.25188002 -1.11398996 2.25188002 -1.11418002 1 P 8191 
A 2.3208 -1.02041004 2.3006 -1.02033996 2.31069163 -1.02276978 1 P 0 N
L 2.27413002 -1.11835 2.27413002 -1.12868996 1 P 0 
A 2.52848996 -1.16771004 2.54891998 -1.15895 2.52774557 -1.13777087 1 P 0 N
A 2.55608002 -1.08618002 2.53611998 -1.07688996 2.5249185 -1.12704419 1 P 0 N
L 2.71926004 -1.06796998 2.71926004 -1.17483996 1 P 0 
A 2.78888996 -1.16296998 2.81508002 -1.16676998 2.8083499 -1.12100167 1 P 0 N
A 2.8151 -1.16675 2.83966004 -1.15211998 2.80521398 -1.12222392 1 P 0 N
A 2.85201004 -1.16508002 2.83966004 -1.15211004 2.84505768 -1.15933514 1 P 0 N
L 2.85201004 -1.16508002 2.84523996 -1.17161004 1 P 0 
A 2.81425 -1.1835 2.84525 -1.17161004 2.81425 -1.13714291 1 P 0 N
L 2.81425 -1.1835 2.79571004 -1.1835 1 P 0 
A 2.75886998 -1.16443002 2.79571998 -1.18351998 2.80278976 -1.12476142 1 P 0 N
A 2.74528996 -1.13568002 2.75888002 -1.16443002 2.80246565 -1.12624016 1 P 0 N
A 2.54316998 -1.1834 2.56906004 -1.1647 2.5305814 -1.13869892 1 P 0 N
A 2.56906004 -1.1647 2.57053996 -1.13728002 2.53763041 -1.14925374 1 P 0 N
A 2.65463996 -1.18351998 2.66863996 -1.17373996 2.65440246 -1.16826969 1 P 0 N
L 2.65463002 -1.1835 2.64165 -1.1835 1 P 0 
A 2.60955 -1.16043002 2.64163996 -1.18351004 2.63911063 -1.15317815 1 P 0 N
A 2.62978002 -1.15461998 2.66001998 -1.16328996 2.6502374 -1.14033868 1 P 0 N
A 2.66863996 -1.17375 2.66001998 -1.16328996 2.66100344 -1.17126132 1 P 0 N
A 2.6962 -1.17483996 2.71926004 -1.17483996 2.70773002 -1.17286427 1 P 0 N
L 2.69618996 -1.17483996 2.69618996 -1.06796998 1 P 0 
A 2.83833002 -1.09275 2.82661998 -1.08201998 2.74555758 -1.18224094 1 P 0 N
A 2.82661998 -1.08198996 2.80036998 -1.07538996 2.80348839 -1.11848878 1 P 0 N
A 2.80036004 -1.07541998 2.76848996 -1.09933002 2.80700217 -1.1174685 1 P 0 N
A 2.76848996 -1.09931998 2.76446004 -1.12066004 2.82315728 -1.120694 1 P 0 N
A 2.74998002 -1.09273996 2.74528996 -1.11838996 2.8498563 -1.12425591 1 P 0 N
A 2.7954 -1.05776998 2.74998996 -1.09273996 2.80799961 -1.12109961 1 P 0 N
L 2.79541004 -1.05776998 2.80918996 -1.05776998 1 P 0 
A 2.85401998 -1.08106004 2.80918996 -1.05776998 2.80626024 -1.1181998 1 P 0 N
A 2.83833002 -1.09273996 2.85403002 -1.08106004 2.84418386 -1.08421683 1 P 0 N
L 2.76445 -1.12066004 2.76445 -1.12943002 1 P 0 
A 2.76446004 -1.12943002 2.76836998 -1.14305 2.80607844 -1.12485364 1 P 0 N
A 2.76836998 -1.14305 2.78891004 -1.16296998 2.80906152 -1.12164144 1 P 0 N
L 2.74528996 -1.13566004 2.74528996 -1.11838996 1 P 0 
A 2.55606004 -1.0862 2.56885 -1.07366998 2.56205354 -1.0795252 1 P 0 N
L 2.60953996 -1.07953996 2.59981998 -1.07953996 1 P 0 
A 2.5993 -1.05931998 2.59981004 -1.07955 2.6022813 -1.06936624 1 P 0 N
L 2.5993 -1.05931998 2.60953996 -1.05931998 1 P 0 
L 2.60953996 -1.05931998 2.60953996 -1.03491998 1 P 0 
A 2.62971998 -1.03418002 2.60953996 -1.03491004 2.61966791 -1.03559478 1 P 0 N
L 2.62971004 -1.03418996 2.62978002 -1.05931998 1 P 0 
L 2.62978002 -1.05931998 2.66008002 -1.05931998 1 P 0 
A 2.66003996 -1.07955 2.66008002 -1.05931998 2.65827421 -1.0694314 1 P 0 N
L 2.66003002 -1.07953996 2.62978002 -1.07953996 1 P 0 
A 2.71926004 -1.06796998 2.6962 -1.06796998 2.70773002 -1.0720561 1 P 0 N
A 2.71968996 -1.02341998 2.71968996 -1.02341998 2.70775 -1.02341998 1 P 0 N
A 2.57053996 -1.13728996 2.54306998 -1.11513002 2.53584449 -1.15219301 1 P 0 N
A 2.54891998 -1.15895 2.55001004 -1.14328002 2.54127923 -1.15054557 1 P 0 N
L 2.60953996 -1.16041004 2.60953996 -1.07953996 1 P 0 
L 2.62978002 -1.07953996 2.62978002 -1.15463002 1 P 0 
L 2.98495 -1.09393996 2.98495 -1.17625 1 P 0 
A 2.96473996 -1.17626998 2.98493996 -1.17626998 2.97483996 -1.17442303 1 P 0 N
L 2.96473002 -1.17625 2.96473002 -1.17226004 1 P 8191 
A 2.94165 -1.1835 2.96471004 -1.17226004 2.93076516 -1.1318935 1 P 0 N
L 2.94165 -1.1835 2.90701004 -1.1835 1 P 0 
A 2.90671004 -1.10841998 2.90703002 -1.18351004 2.9153065 -1.14592904 1 P 0 N
A 2.91853002 -1.12288996 2.91853002 -1.16618996 2.92048209 -1.14453996 1 P 0 N
L 2.91853002 -1.1662 2.94456004 -1.1662 1 P 0 
A 2.94456998 -1.16618996 2.94456998 -1.12288996 2.94406004 -1.14453996 1 P 0 N
A 2.96473002 -1.09686004 2.94741998 -1.07955 2.94874833 -1.09553169 1 P 0 N
L 2.9474 -1.07953996 2.90986998 -1.07953996 1 P 0 
A 2.90986998 -1.07953996 2.89821004 -1.0852 2.92433445 -1.12417766 1 P 0 N
A 2.89111998 -1.07086004 2.8982 -1.0852 2.8969689 -1.07688996 1 P 0 N
A 2.91561998 -1.05931998 2.89111998 -1.07085 2.92146033 -1.103525 1 P 0 N
L 2.91563002 -1.05931998 2.95031004 -1.05931998 1 P 0 
A 2.98496004 -1.09393996 2.95031004 -1.05933002 2.9453438 -1.09895197 1 P 0 N
A 2.92878996 -1.10535 2.9067 -1.10841998 2.93158484 -1.20646998 1 P 0 N
A 2.96471998 -1.10841004 2.92878002 -1.10536004 2.93215738 -1.27883829 1 P 0 N
L 2.96473002 -1.10841004 2.96473002 -1.09686004 1 P 0 
L 2.94456004 -1.12288002 2.91853002 -1.12288002 1 P 0 
L 3.04731004 -1.06001004 3.04191998 -1.07631998 1 P 0 
L 3.04191998 -1.07631998 3.03648002 -1.06001004 1 P 0 
L 3.03648002 -1.06001004 3.03243002 -1.06001004 1 P 8191 
L 3.03243002 -1.06001004 3.02698002 -1.08543996 1 P 0 
L 3.02698002 -1.08543996 3.03226004 -1.08543996 1 P 8191 
L 3.03226004 -1.08543996 3.03501004 -1.06886998 1 P 0 
L 3.03501004 -1.06886998 3.04086004 -1.08543996 1 P 0 
L 3.04086004 -1.08543996 3.04308996 -1.08543996 1 P 8191 
L 3.04308996 -1.08543996 3.04888996 -1.06871004 1 P 0 
L 3.04888996 -1.06871004 3.05171004 -1.08543996 1 P 0 
L 3.05171004 -1.08543996 3.05713002 -1.08543996 1 P 8191 
L 3.05713002 -1.08543996 3.05163996 -1.06001004 1 P 0 
L 3.05163996 -1.06001004 3.04731004 -1.06001004 1 P 8191 
L 3.01066998 -1.06508002 3.00223002 -1.06508002 1 P 0 
L 3.00223002 -1.06508002 3.00223002 -1.06001004 1 P 8191 
L 3.00223002 -1.06001004 3.02461004 -1.06001004 1 P 0 
L 3.02461004 -1.06001004 3.02461004 -1.06508002 1 P 8191 
L 3.02461004 -1.06508002 3.01615 -1.06508002 1 P 0 
L 3.01615 -1.06508002 3.01615 -1.08533996 1 P 0 
L 3.01615 -1.08533996 3.01066998 -1.08533996 1 P 8191 
L 3.01066998 -1.08533996 3.01066998 -1.06508002 1 P 0 
L 3.8183999 -1.32000217 3.82586663 -1.32625089 0 P 0 ;0,1=36,2=0.000000
L 3.82586663 -1.32625089 3.83426654 -1.33 0 P 0 ;0,1=36,2=0.000000
L 3.83426654 -1.33 3.84173337 -1.33 0 P 0 ;0,1=36,2=0.000000
L 3.84173337 -1.33 3.8492001 -1.32625089 0 P 0 ;0,1=36,2=0.000000
L 3.8492001 -1.32625089 3.85480059 -1.32000217 0 P 0 ;0,1=36,2=0.000000
L 3.85480059 -1.32000217 3.8576 -1.31124951 0 P 0 ;0,1=36,2=0.000000
L 3.8576 -1.31124951 3.85573376 -1.30250138 0 P 0 ;0,1=36,2=0.000000
L 3.85573376 -1.30250138 3.85106644 -1.29500069 0 P 0 ;0,1=36,2=0.000000
L 3.85106644 -1.29500069 3.84266644 -1.28999941 0 P 0 ;0,1=36,2=0.000000
L 3.84266644 -1.28999941 3.83146713 -1.2875 0 P 0 ;0,1=36,2=0.000000
L 3.83146713 -1.2875 3.82493346 -1.28250108 0 P 0 ;0,1=36,2=0.000000
L 3.82493346 -1.28250108 3.82213238 -1.27375059 0 P 0 ;0,1=36,2=0.000000
L 3.82213238 -1.27375059 3.82400039 -1.2650002 0 P 0 ;0,1=36,2=0.000000
L 3.82400039 -1.2650002 3.82866604 -1.25875157 0 P 0 ;0,1=36,2=0.000000
L 3.82866604 -1.25875157 3.8351997 -1.255 0 P 0 ;0,1=36,2=0.000000
L 3.8351997 -1.255 3.84173337 -1.255 0 P 0 ;0,1=36,2=0.000000
L 3.84173337 -1.255 3.84826703 -1.25749951 0 P 0 ;0,1=36,2=0.000000
L 3.84826703 -1.25749951 3.85386752 -1.26375049 0 P 0 ;0,1=36,2=0.000000
L 3.9017998 -1.255 3.92419843 -1.255 0 P 0 ;0,1=36,2=0.000000
L 3.91299911 -1.255 3.91299911 -1.33 0 P 0 ;0,1=36,2=0.000000
L 3.9017998 -1.33 3.92419843 -1.33 0 P 0 ;0,1=36,2=0.000000
L 3.96933297 -1.255 3.96933297 -1.33 0 P 0 ;0,1=36,2=0.000000
L 3.96933297 -1.33 4.00666693 -1.33 0 P 0 ;0,1=36,2=0.000000
L 4.04246673 -1.33 4.04246673 -1.255 0 P 0 ;0,1=36,2=0.000000
L 4.07793268 -1.255 4.04246673 -1.30125157 0 P 0 ;0,1=36,2=0.000000
L 4.08353317 -1.33 4.05833346 -1.28000157 0 P 0 ;0,1=36,2=0.000000
L 4.1183999 -1.32000217 4.12586663 -1.32625089 0 P 0 ;0,1=36,2=0.000000
L 4.12586663 -1.32625089 4.13426654 -1.33 0 P 0 ;0,1=36,2=0.000000
L 4.13426654 -1.33 4.14173337 -1.33 0 P 0 ;0,1=36,2=0.000000
L 4.14173337 -1.33 4.1492001 -1.32625089 0 P 0 ;0,1=36,2=0.000000
L 4.1492001 -1.32625089 4.15480059 -1.32000217 0 P 0 ;0,1=36,2=0.000000
L 4.15480059 -1.32000217 4.1576 -1.31124951 0 P 0 ;0,1=36,2=0.000000
L 4.1576 -1.31124951 4.15573376 -1.30250138 0 P 0 ;0,1=36,2=0.000000
L 4.15573376 -1.30250138 4.15106644 -1.29500069 0 P 0 ;0,1=36,2=0.000000
L 4.15106644 -1.29500069 4.14266644 -1.28999941 0 P 0 ;0,1=36,2=0.000000
L 4.14266644 -1.28999941 4.13146713 -1.2875 0 P 0 ;0,1=36,2=0.000000
L 4.13146713 -1.2875 4.12493346 -1.28250108 0 P 0 ;0,1=36,2=0.000000
L 4.12493346 -1.28250108 4.12213238 -1.27375059 0 P 0 ;0,1=36,2=0.000000
L 4.12213238 -1.27375059 4.12400039 -1.2650002 0 P 0 ;0,1=36,2=0.000000
L 4.12400039 -1.2650002 4.12866604 -1.25875157 0 P 0 ;0,1=36,2=0.000000
L 4.12866604 -1.25875157 4.1351997 -1.255 0 P 0 ;0,1=36,2=0.000000
L 4.1351997 -1.255 4.14173337 -1.255 0 P 0 ;0,1=36,2=0.000000
L 4.14173337 -1.255 4.14826703 -1.25749951 0 P 0 ;0,1=36,2=0.000000
L 4.14826703 -1.25749951 4.15386752 -1.26375049 0 P 0 ;0,1=36,2=0.000000
L 4.23353317 -1.26125098 4.22793268 -1.25749951 0 P 0 ;0,1=36,2=0.000000
L 4.22793268 -1.25749951 4.22140069 -1.255 0 P 0 ;0,1=36,2=0.000000
L 4.22140069 -1.255 4.21393396 -1.255 0 P 0 ;0,1=36,2=0.000000
L 4.21393396 -1.255 4.20553228 -1.25875157 0 P 0 ;0,1=36,2=0.000000
L 4.20553228 -1.25875157 4.19900039 -1.2650002 0 P 0 ;0,1=36,2=0.000000
L 4.19900039 -1.2650002 4.19433297 -1.27250089 0 P 0 ;0,1=36,2=0.000000
L 4.19433297 -1.27250089 4.19059872 -1.28500049 0 P 0 ;0,1=36,2=0.000000
L 4.19059872 -1.28500049 4.18966565 -1.29625039 0 P 0 ;0,1=36,2=0.000000
L 4.18966565 -1.29625039 4.19153356 -1.3075003 0 P 0 ;0,1=36,2=0.000000
L 4.19153356 -1.3075003 4.19433297 -1.31500098 0 P 0 ;0,1=36,2=0.000000
L 4.19433297 -1.31500098 4.19993346 -1.32250167 0 P 0 ;0,1=36,2=0.000000
L 4.19993346 -1.32250167 4.20646713 -1.32750059 0 P 0 ;0,1=36,2=0.000000
L 4.20646713 -1.32750059 4.21299911 -1.33 0 P 0 ;0,1=36,2=0.000000
L 4.21299911 -1.33 4.21953278 -1.33 0 P 0 ;0,1=36,2=0.000000
L 4.21953278 -1.33 4.22606644 -1.32750059 0 P 0 ;0,1=36,2=0.000000
L 4.22606644 -1.32750059 4.23166693 -1.32375138 0 P 0 ;0,1=36,2=0.000000
L 4.23166693 -1.32375138 4.23633425 -1.31875246 0 P 0 ;0,1=36,2=0.000000
L 4.26933297 -1.33 4.26933297 -1.255 0 P 0 ;0,1=36,2=0.000000
L 4.26933297 -1.255 4.29266644 -1.255 0 P 0 ;0,1=36,2=0.000000
L 4.29266644 -1.255 4.30013327 -1.25875157 0 P 0 ;0,1=36,2=0.000000
L 4.30013327 -1.25875157 4.30480059 -1.26375049 0 P 0 ;0,1=36,2=0.000000
L 4.30480059 -1.26375049 4.30666693 -1.27375059 0 P 0 ;0,1=36,2=0.000000
L 4.30666693 -1.27375059 4.30480059 -1.28375079 0 P 0 ;0,1=36,2=0.000000
L 4.30480059 -1.28375079 4.2992001 -1.28999941 0 P 0 ;0,1=36,2=0.000000
L 4.2992001 -1.28999941 4.29266644 -1.29375089 0 P 0 ;0,1=36,2=0.000000
L 4.29266644 -1.29375089 4.26933297 -1.29375089 0 P 0 ;0,1=36,2=0.000000
L 4.29266644 -1.29375089 4.30666693 -1.33 0 P 0 ;0,1=36,2=0.000000
L 4.38166693 -1.33 4.34433297 -1.33 0 P 0 ;0,1=36,2=0.000000
L 4.34433297 -1.33 4.34433297 -1.255 0 P 0 ;0,1=36,2=0.000000
L 4.34433297 -1.255 4.38166693 -1.255 0 P 0 ;0,1=36,2=0.000000
L 4.36673337 -1.29124921 4.34433297 -1.29124921 0 P 0 ;0,1=36,2=0.000000
L 4.45666693 -1.33 4.41933297 -1.33 0 P 0 ;0,1=36,2=0.000000
L 4.41933297 -1.33 4.41933297 -1.255 0 P 0 ;0,1=36,2=0.000000
L 4.41933297 -1.255 4.45666693 -1.255 0 P 0 ;0,1=36,2=0.000000
L 4.44173337 -1.29124921 4.41933297 -1.29124921 0 P 0 ;0,1=36,2=0.000000
L 4.49153356 -1.33 4.49153356 -1.255 0 P 0 ;0,1=36,2=0.000000
L 4.49153356 -1.255 4.53446634 -1.33 0 P 0 ;0,1=36,2=0.000000
L 4.53446634 -1.33 4.53446634 -1.255 0 P 0 ;0,1=36,2=0.000000
L 4.66299911 -1.255 4.66299911 -1.33 0 P 0 ;0,1=36,2=0.000000
L 4.64153356 -1.255 4.68446634 -1.255 0 P 0 ;0,1=36,2=0.000000
L 4.73799911 -1.33 4.73053228 -1.3287503 0 P 0 ;0,1=36,2=0.000000
L 4.73053228 -1.3287503 4.72400039 -1.32375138 0 P 0 ;0,1=36,2=0.000000
L 4.72400039 -1.32375138 4.7183999 -1.31625069 0 P 0 ;0,1=36,2=0.000000
L 4.7183999 -1.31625069 4.71466565 -1.3075003 0 P 0 ;0,1=36,2=0.000000
L 4.71466565 -1.3075003 4.71279931 -1.2975001 0 P 0 ;0,1=36,2=0.000000
L 4.71279931 -1.2975001 4.71279931 -1.2875 0 P 0 ;0,1=36,2=0.000000
L 4.71279931 -1.2875 4.71466565 -1.2774998 0 P 0 ;0,1=36,2=0.000000
L 4.71466565 -1.2774998 4.7183999 -1.26874941 0 P 0 ;0,1=36,2=0.000000
L 4.7183999 -1.26874941 4.72400039 -1.26125098 0 P 0 ;0,1=36,2=0.000000
L 4.72400039 -1.26125098 4.73053228 -1.2562498 0 P 0 ;0,1=36,2=0.000000
L 4.73053228 -1.2562498 4.73799911 -1.255 0 P 0 ;0,1=36,2=0.000000
L 4.73799911 -1.255 4.74546585 -1.2562498 0 P 0 ;0,1=36,2=0.000000
L 4.74546585 -1.2562498 4.75199951 -1.26125098 0 P 0 ;0,1=36,2=0.000000
L 4.75199951 -1.26125098 4.7576 -1.26874941 0 P 0 ;0,1=36,2=0.000000
L 4.7576 -1.26874941 4.76133425 -1.2774998 0 P 0 ;0,1=36,2=0.000000
L 4.76133425 -1.2774998 4.76320059 -1.2875 0 P 0 ;0,1=36,2=0.000000
L 4.76320059 -1.2875 4.76320059 -1.2975001 0 P 0 ;0,1=36,2=0.000000
L 4.76320059 -1.2975001 4.76133425 -1.3075003 0 P 0 ;0,1=36,2=0.000000
L 4.76133425 -1.3075003 4.7576 -1.31625069 0 P 0 ;0,1=36,2=0.000000
L 4.7576 -1.31625069 4.75199951 -1.32375138 0 P 0 ;0,1=36,2=0.000000
L 4.75199951 -1.32375138 4.74546585 -1.3287503 0 P 0 ;0,1=36,2=0.000000
L 4.74546585 -1.3287503 4.73799911 -1.33 0 P 0 ;0,1=36,2=0.000000
L 4.79433297 -1.33 4.79433297 -1.255 0 P 0 ;0,1=36,2=0.000000
L 4.79433297 -1.255 4.81673337 -1.255 0 P 0 ;0,1=36,2=0.000000
L 4.81673337 -1.255 4.8242001 -1.25875157 0 P 0 ;0,1=36,2=0.000000
L 4.8242001 -1.25875157 4.82980059 -1.2674997 0 P 0 ;0,1=36,2=0.000000
L 4.82980059 -1.2674997 4.83166693 -1.2774998 0 P 0 ;0,1=36,2=0.000000
L 4.83166693 -1.2774998 4.82980059 -1.2875 0 P 0 ;0,1=36,2=0.000000
L 4.82980059 -1.2875 4.82513327 -1.29500069 0 P 0 ;0,1=36,2=0.000000
L 4.82513327 -1.29500069 4.81673337 -1.29875217 0 P 0 ;0,1=36,2=0.000000
L 4.81673337 -1.29875217 4.79433297 -1.29875217 0 P 0 ;0,1=36,2=0.000000
L 3.36933297 -0.955 3.36933297 -0.88 0 P 0 ;0,1=37,2=0.000000
L 3.36933297 -0.88 3.39173337 -0.88 0 P 0 ;0,1=37,2=0.000000
L 3.39173337 -0.88 3.3992001 -0.88375157 0 P 0 ;0,1=37,2=0.000000
L 3.3992001 -0.88375157 3.40480059 -0.8924997 0 P 0 ;0,1=37,2=0.000000
L 3.40480059 -0.8924997 3.40666693 -0.9024998 0 P 0 ;0,1=37,2=0.000000
L 3.40666693 -0.9024998 3.40480059 -0.9125 0 P 0 ;0,1=37,2=0.000000
L 3.40480059 -0.9125 3.40013327 -0.92000069 0 P 0 ;0,1=37,2=0.000000
L 3.40013327 -0.92000069 3.39173337 -0.92375217 0 P 0 ;0,1=37,2=0.000000
L 3.39173337 -0.92375217 3.36933297 -0.92375217 0 P 0 ;0,1=37,2=0.000000
L 3.44619931 -0.95749941 3.47980059 -0.88 0 P 0 ;0,1=37,2=0.000000
L 3.51653356 -0.955 3.51653356 -0.88 0 P 0 ;0,1=37,2=0.000000
L 3.51653356 -0.88 3.55946634 -0.955 0 P 0 ;0,1=37,2=0.000000
L 3.55946634 -0.955 3.55946634 -0.88 0 P 0 ;0,1=37,2=0.000000
L 3.68799911 -0.95749941 3.68613287 -0.9562497 0 P 0 ;0,1=37,2=0.000000
L 3.68613287 -0.9562497 3.68613287 -0.9537503 0 P 0 ;0,1=37,2=0.000000
L 3.68613287 -0.9537503 3.68799911 -0.95250059 0 P 0 ;0,1=37,2=0.000000
L 3.68799911 -0.95250059 3.68986703 -0.9537503 0 P 0 ;0,1=37,2=0.000000
L 3.68986703 -0.9537503 3.68986703 -0.9562497 0 P 0 ;0,1=37,2=0.000000
L 3.68986703 -0.9562497 3.68799911 -0.95749941 0 P 0 ;0,1=37,2=0.000000
L 3.68799911 -0.92375217 3.68613287 -0.9225001 0 P 0 ;0,1=37,2=0.000000
L 3.68613287 -0.9225001 3.68613287 -0.92000069 0 P 0 ;0,1=37,2=0.000000
L 3.68613287 -0.92000069 3.68799911 -0.91875089 0 P 0 ;0,1=37,2=0.000000
L 3.68799911 -0.91875089 3.68986703 -0.92000069 0 P 0 ;0,1=37,2=0.000000
L 3.68986703 -0.92000069 3.68986703 -0.9225001 0 P 0 ;0,1=37,2=0.000000
L 3.68986703 -0.9225001 3.68799911 -0.92375217 0 P 0 ;0,1=37,2=0.000000
L 3.81933297 -0.955 3.81933297 -0.88 0 P 0 ;0,1=37,2=0.000000
L 3.81933297 -0.88 3.84266644 -0.88 0 P 0 ;0,1=37,2=0.000000
L 3.84266644 -0.88 3.85013327 -0.88375157 0 P 0 ;0,1=37,2=0.000000
L 3.85013327 -0.88375157 3.85480059 -0.88875049 0 P 0 ;0,1=37,2=0.000000
L 3.85480059 -0.88875049 3.85666693 -0.89875059 0 P 0 ;0,1=37,2=0.000000
L 3.85666693 -0.89875059 3.85480059 -0.90875079 0 P 0 ;0,1=37,2=0.000000
L 3.85480059 -0.90875079 3.8492001 -0.91499941 0 P 0 ;0,1=37,2=0.000000
L 3.8492001 -0.91499941 3.84266644 -0.91875089 0 P 0 ;0,1=37,2=0.000000
L 3.84266644 -0.91875089 3.81933297 -0.91875089 0 P 0 ;0,1=37,2=0.000000
L 3.84266644 -0.91875089 3.85666693 -0.955 0 P 0 ;0,1=37,2=0.000000
L 3.9242001 -0.955 3.9242001 -0.88 0 P 0 ;0,1=37,2=0.000000
L 3.9242001 -0.88 3.88966565 -0.93375 0 P 0 ;0,1=37,2=0.000000
L 3.88966565 -0.93375 3.93633425 -0.93375 0 P 0 ;0,1=37,2=0.000000
L 3.98799911 -0.88 3.98053228 -0.88249951 0 P 0 ;0,1=37,2=0.000000
L 3.98053228 -0.88249951 3.97493346 -0.88875049 0 P 0 ;0,1=37,2=0.000000
L 3.97493346 -0.88875049 3.97119931 -0.89624882 0 P 0 ;0,1=37,2=0.000000
L 3.97119931 -0.89624882 3.9683999 -0.90625128 0 P 0 ;0,1=37,2=0.000000
L 3.9683999 -0.90625128 3.96746673 -0.91750118 0 P 0 ;0,1=37,2=0.000000
L 3.96746673 -0.91750118 3.9683999 -0.92875108 0 P 0 ;0,1=37,2=0.000000
L 3.9683999 -0.92875108 3.97119931 -0.93875128 0 P 0 ;0,1=37,2=0.000000
L 3.97119931 -0.93875128 3.97493346 -0.94625187 0 P 0 ;0,1=37,2=0.000000
L 3.97493346 -0.94625187 3.98053228 -0.95250059 0 P 0 ;0,1=37,2=0.000000
L 3.98053228 -0.95250059 3.98799911 -0.955 0 P 0 ;0,1=37,2=0.000000
L 3.98799911 -0.955 3.99546585 -0.95250059 0 P 0 ;0,1=37,2=0.000000
L 3.99546585 -0.95250059 4.00106644 -0.94625187 0 P 0 ;0,1=37,2=0.000000
L 4.00106644 -0.94625187 4.00480059 -0.93875128 0 P 0 ;0,1=37,2=0.000000
L 4.00480059 -0.93875128 4.0076 -0.92875108 0 P 0 ;0,1=37,2=0.000000
L 4.0076 -0.92875108 4.00853317 -0.91750118 0 P 0 ;0,1=37,2=0.000000
L 4.00853317 -0.91750118 4.0076 -0.90625128 0 P 0 ;0,1=37,2=0.000000
L 4.0076 -0.90625128 4.00480059 -0.89624882 0 P 0 ;0,1=37,2=0.000000
L 4.00480059 -0.89624882 4.00106644 -0.88875049 0 P 0 ;0,1=37,2=0.000000
L 4.00106644 -0.88875049 3.99546585 -0.88249951 0 P 0 ;0,1=37,2=0.000000
L 3.99546585 -0.88249951 3.98799911 -0.88 0 P 0 ;0,1=37,2=0.000000
L 4.06299911 -0.88 4.05553228 -0.88249951 0 P 0 ;0,1=37,2=0.000000
L 4.05553228 -0.88249951 4.04993346 -0.88875049 0 P 0 ;0,1=37,2=0.000000
L 4.04993346 -0.88875049 4.04619931 -0.89624882 0 P 0 ;0,1=37,2=0.000000
L 4.04619931 -0.89624882 4.0433999 -0.90625128 0 P 0 ;0,1=37,2=0.000000
L 4.0433999 -0.90625128 4.04246673 -0.91750118 0 P 0 ;0,1=37,2=0.000000
L 4.04246673 -0.91750118 4.0433999 -0.92875108 0 P 0 ;0,1=37,2=0.000000
L 4.0433999 -0.92875108 4.04619931 -0.93875128 0 P 0 ;0,1=37,2=0.000000
L 4.04619931 -0.93875128 4.04993346 -0.94625187 0 P 0 ;0,1=37,2=0.000000
L 4.04993346 -0.94625187 4.05553228 -0.95250059 0 P 0 ;0,1=37,2=0.000000
L 4.05553228 -0.95250059 4.06299911 -0.955 0 P 0 ;0,1=37,2=0.000000
L 4.06299911 -0.955 4.07046585 -0.95250059 0 P 0 ;0,1=37,2=0.000000
L 4.07046585 -0.95250059 4.07606644 -0.94625187 0 P 0 ;0,1=37,2=0.000000
L 4.07606644 -0.94625187 4.07980059 -0.93875128 0 P 0 ;0,1=37,2=0.000000
L 4.07980059 -0.93875128 4.0826 -0.92875108 0 P 0 ;0,1=37,2=0.000000
L 4.0826 -0.92875108 4.08353317 -0.91750118 0 P 0 ;0,1=37,2=0.000000
L 4.08353317 -0.91750118 4.0826 -0.90625128 0 P 0 ;0,1=37,2=0.000000
L 4.0826 -0.90625128 4.07980059 -0.89624882 0 P 0 ;0,1=37,2=0.000000
L 4.07980059 -0.89624882 4.07606644 -0.88875049 0 P 0 ;0,1=37,2=0.000000
L 4.07606644 -0.88875049 4.07046585 -0.88249951 0 P 0 ;0,1=37,2=0.000000
L 4.07046585 -0.88249951 4.06299911 -0.88 0 P 0 ;0,1=37,2=0.000000
L 4.12026614 -0.92375217 4.1267998 -0.91499941 0 P 0 ;0,1=37,2=0.000000
L 4.1267998 -0.91499941 4.1324003 -0.91000049 0 P 0 ;0,1=37,2=0.000000
L 4.1324003 -0.91000049 4.13986703 -0.90750108 0 P 0 ;0,1=37,2=0.000000
L 4.13986703 -0.90750108 4.14640069 -0.91000049 0 P 0 ;0,1=37,2=0.000000
L 4.14640069 -0.91000049 4.15106644 -0.91499941 0 P 0 ;0,1=37,2=0.000000
L 4.15106644 -0.91499941 4.15480059 -0.9225001 0 P 0 ;0,1=37,2=0.000000
L 4.15480059 -0.9225001 4.15573376 -0.93125059 0 P 0 ;0,1=37,2=0.000000
L 4.15573376 -0.93125059 4.15480059 -0.93875128 0 P 0 ;0,1=37,2=0.000000
L 4.15480059 -0.93875128 4.15106644 -0.94625187 0 P 0 ;0,1=37,2=0.000000
L 4.15106644 -0.94625187 4.14546585 -0.95250059 0 P 0 ;0,1=37,2=0.000000
L 4.14546585 -0.95250059 4.13893396 -0.955 0 P 0 ;0,1=37,2=0.000000
L 4.13893396 -0.955 4.13146713 -0.95250059 0 P 0 ;0,1=37,2=0.000000
L 4.13146713 -0.95250059 4.12493346 -0.94500217 0 P 0 ;0,1=37,2=0.000000
L 4.12493346 -0.94500217 4.12119931 -0.93375 0 P 0 ;0,1=37,2=0.000000
L 4.12119931 -0.93375 4.12026614 -0.92125039 0 P 0 ;0,1=37,2=0.000000
L 4.12026614 -0.92125039 4.12213238 -0.90500157 0 P 0 ;0,1=37,2=0.000000
L 4.12213238 -0.90500157 4.12493346 -0.89624882 0 P 0 ;0,1=37,2=0.000000
L 4.12493346 -0.89624882 4.12959921 -0.88750069 0 P 0 ;0,1=37,2=0.000000
L 4.12959921 -0.88750069 4.13613287 -0.8812498 0 P 0 ;0,1=37,2=0.000000
L 4.13613287 -0.8812498 4.14266644 -0.88 0 P 0 ;0,1=37,2=0.000000
L 4.14266644 -0.88 4.1492001 -0.88249951 0 P 0 ;0,1=37,2=0.000000
L 4.1492001 -0.88249951 4.15386752 -0.88875049 0 P 0 ;0,1=37,2=0.000000
L 4.20086663 -0.93000079 4.22513327 -0.93000079 0 P 0 ;0,1=37,2=0.000000
L 4.29546585 -0.91499941 4.2992001 -0.9112502 0 P 0 ;0,1=37,2=0.000000
L 4.2992001 -0.9112502 4.30199951 -0.90500157 0 P 0 ;0,1=37,2=0.000000
L 4.30199951 -0.90500157 4.30386752 -0.89624882 0 P 0 ;0,1=37,2=0.000000
L 4.30386752 -0.89624882 4.30199951 -0.88875049 0 P 0 ;0,1=37,2=0.000000
L 4.30199951 -0.88875049 4.29826703 -0.88375157 0 P 0 ;0,1=37,2=0.000000
L 4.29826703 -0.88375157 4.29173337 -0.88 0 P 0 ;0,1=37,2=0.000000
L 4.29173337 -0.88 4.26653356 -0.88 0 P 0 ;0,1=37,2=0.000000
L 4.26653356 -0.88 4.26653356 -0.955 0 P 0 ;0,1=37,2=0.000000
L 4.26653356 -0.955 4.29733386 -0.955 0 P 0 ;0,1=37,2=0.000000
L 4.29733386 -0.955 4.30386752 -0.95000108 0 P 0 ;0,1=37,2=0.000000
L 4.30386752 -0.95000108 4.3076 -0.94250039 0 P 0 ;0,1=37,2=0.000000
L 4.3076 -0.94250039 4.30946634 -0.93375 0 P 0 ;0,1=37,2=0.000000
L 4.30946634 -0.93375 4.3076 -0.92500187 0 P 0 ;0,1=37,2=0.000000
L 4.3076 -0.92500187 4.30199951 -0.91750118 0 P 0 ;0,1=37,2=0.000000
L 4.30199951 -0.91750118 4.29546585 -0.91499941 0 P 0 ;0,1=37,2=0.000000
L 4.29546585 -0.91499941 4.26653356 -0.91499941 0 P 0 ;0,1=37,2=0.000000
L 4.36299911 -0.88 4.35553228 -0.88249951 0 P 0 ;0,1=37,2=0.000000
L 4.35553228 -0.88249951 4.34993346 -0.88875049 0 P 0 ;0,1=37,2=0.000000
L 4.34993346 -0.88875049 4.34619931 -0.89624882 0 P 0 ;0,1=37,2=0.000000
L 4.34619931 -0.89624882 4.3433999 -0.90625128 0 P 0 ;0,1=37,2=0.000000
L 4.3433999 -0.90625128 4.34246673 -0.91750118 0 P 0 ;0,1=37,2=0.000000
L 4.34246673 -0.91750118 4.3433999 -0.92875108 0 P 0 ;0,1=37,2=0.000000
L 4.3433999 -0.92875108 4.34619931 -0.93875128 0 P 0 ;0,1=37,2=0.000000
L 4.34619931 -0.93875128 4.34993346 -0.94625187 0 P 0 ;0,1=37,2=0.000000
L 4.34993346 -0.94625187 4.35553228 -0.95250059 0 P 0 ;0,1=37,2=0.000000
L 4.35553228 -0.95250059 4.36299911 -0.955 0 P 0 ;0,1=37,2=0.000000
L 4.36299911 -0.955 4.37046585 -0.95250059 0 P 0 ;0,1=37,2=0.000000
L 4.37046585 -0.95250059 4.37606644 -0.94625187 0 P 0 ;0,1=37,2=0.000000
L 4.37606644 -0.94625187 4.37980059 -0.93875128 0 P 0 ;0,1=37,2=0.000000
L 4.37980059 -0.93875128 4.3826 -0.92875108 0 P 0 ;0,1=37,2=0.000000
L 4.3826 -0.92875108 4.38353317 -0.91750118 0 P 0 ;0,1=37,2=0.000000
L 4.38353317 -0.91750118 4.3826 -0.90625128 0 P 0 ;0,1=37,2=0.000000
L 4.3826 -0.90625128 4.37980059 -0.89624882 0 P 0 ;0,1=37,2=0.000000
L 4.37980059 -0.89624882 4.37606644 -0.88875049 0 P 0 ;0,1=37,2=0.000000
L 4.37606644 -0.88875049 4.37046585 -0.88249951 0 P 0 ;0,1=37,2=0.000000
L 4.37046585 -0.88249951 4.36299911 -0.88 0 P 0 ;0,1=37,2=0.000000
L 4.43799911 -0.88 4.43053228 -0.88249951 0 P 0 ;0,1=37,2=0.000000
L 4.43053228 -0.88249951 4.42493346 -0.88875049 0 P 0 ;0,1=37,2=0.000000
L 4.42493346 -0.88875049 4.42119931 -0.89624882 0 P 0 ;0,1=37,2=0.000000
L 4.42119931 -0.89624882 4.4183999 -0.90625128 0 P 0 ;0,1=37,2=0.000000
L 4.4183999 -0.90625128 4.41746673 -0.91750118 0 P 0 ;0,1=37,2=0.000000
L 4.41746673 -0.91750118 4.4183999 -0.92875108 0 P 0 ;0,1=37,2=0.000000
L 4.4183999 -0.92875108 4.42119931 -0.93875128 0 P 0 ;0,1=37,2=0.000000
L 4.42119931 -0.93875128 4.42493346 -0.94625187 0 P 0 ;0,1=37,2=0.000000
L 4.42493346 -0.94625187 4.43053228 -0.95250059 0 P 0 ;0,1=37,2=0.000000
L 4.43053228 -0.95250059 4.43799911 -0.955 0 P 0 ;0,1=37,2=0.000000
L 4.43799911 -0.955 4.44546585 -0.95250059 0 P 0 ;0,1=37,2=0.000000
L 4.44546585 -0.95250059 4.45106644 -0.94625187 0 P 0 ;0,1=37,2=0.000000
L 4.45106644 -0.94625187 4.45480059 -0.93875128 0 P 0 ;0,1=37,2=0.000000
L 4.45480059 -0.93875128 4.4576 -0.92875108 0 P 0 ;0,1=37,2=0.000000
L 4.4576 -0.92875108 4.45853317 -0.91750118 0 P 0 ;0,1=37,2=0.000000
L 4.45853317 -0.91750118 4.4576 -0.90625128 0 P 0 ;0,1=37,2=0.000000
L 4.4576 -0.90625128 4.45480059 -0.89624882 0 P 0 ;0,1=37,2=0.000000
L 4.45480059 -0.89624882 4.45106644 -0.88875049 0 P 0 ;0,1=37,2=0.000000
L 4.45106644 -0.88875049 4.44546585 -0.88249951 0 P 0 ;0,1=37,2=0.000000
L 4.44546585 -0.88249951 4.43799911 -0.88 0 P 0 ;0,1=37,2=0.000000
L 4.51299911 -0.88 4.50553228 -0.88249951 0 P 0 ;0,1=37,2=0.000000
L 4.50553228 -0.88249951 4.49993346 -0.88875049 0 P 0 ;0,1=37,2=0.000000
L 4.49993346 -0.88875049 4.49619931 -0.89624882 0 P 0 ;0,1=37,2=0.000000
L 4.49619931 -0.89624882 4.4933999 -0.90625128 0 P 0 ;0,1=37,2=0.000000
L 4.4933999 -0.90625128 4.49246673 -0.91750118 0 P 0 ;0,1=37,2=0.000000
L 4.49246673 -0.91750118 4.4933999 -0.92875108 0 P 0 ;0,1=37,2=0.000000
L 4.4933999 -0.92875108 4.49619931 -0.93875128 0 P 0 ;0,1=37,2=0.000000
L 4.49619931 -0.93875128 4.49993346 -0.94625187 0 P 0 ;0,1=37,2=0.000000
L 4.49993346 -0.94625187 4.50553228 -0.95250059 0 P 0 ;0,1=37,2=0.000000
L 4.50553228 -0.95250059 4.51299911 -0.955 0 P 0 ;0,1=37,2=0.000000
L 4.51299911 -0.955 4.52046585 -0.95250059 0 P 0 ;0,1=37,2=0.000000
L 4.52046585 -0.95250059 4.52606644 -0.94625187 0 P 0 ;0,1=37,2=0.000000
L 4.52606644 -0.94625187 4.52980059 -0.93875128 0 P 0 ;0,1=37,2=0.000000
L 4.52980059 -0.93875128 4.5326 -0.92875108 0 P 0 ;0,1=37,2=0.000000
L 4.5326 -0.92875108 4.53353317 -0.91750118 0 P 0 ;0,1=37,2=0.000000
L 4.53353317 -0.91750118 4.5326 -0.90625128 0 P 0 ;0,1=37,2=0.000000
L 4.5326 -0.90625128 4.52980059 -0.89624882 0 P 0 ;0,1=37,2=0.000000
L 4.52980059 -0.89624882 4.52606644 -0.88875049 0 P 0 ;0,1=37,2=0.000000
L 4.52606644 -0.88875049 4.52046585 -0.88249951 0 P 0 ;0,1=37,2=0.000000
L 4.52046585 -0.88249951 4.51299911 -0.88 0 P 0 ;0,1=37,2=0.000000
L 4.58799911 -0.955 4.58799911 -0.88 0 P 0 ;0,1=37,2=0.000000
L 4.58799911 -0.88 4.5767998 -0.89499911 0 P 0 ;0,1=37,2=0.000000
L 4.5767998 -0.955 4.59919843 -0.955 0 P 0 ;0,1=37,2=0.000000
L 4.65086663 -0.93000079 4.67513327 -0.93000079 0 P 0 ;0,1=37,2=0.000000
L 4.73799911 -0.88 4.73053228 -0.88249951 0 P 0 ;0,1=37,2=0.000000
L 4.73053228 -0.88249951 4.72493346 -0.88875049 0 P 0 ;0,1=37,2=0.000000
L 4.72493346 -0.88875049 4.72119931 -0.89624882 0 P 0 ;0,1=37,2=0.000000
L 4.72119931 -0.89624882 4.7183999 -0.90625128 0 P 0 ;0,1=37,2=0.000000
L 4.7183999 -0.90625128 4.71746673 -0.91750118 0 P 0 ;0,1=37,2=0.000000
L 4.71746673 -0.91750118 4.7183999 -0.92875108 0 P 0 ;0,1=37,2=0.000000
L 4.7183999 -0.92875108 4.72119931 -0.93875128 0 P 0 ;0,1=37,2=0.000000
L 4.72119931 -0.93875128 4.72493346 -0.94625187 0 P 0 ;0,1=37,2=0.000000
L 4.72493346 -0.94625187 4.73053228 -0.95250059 0 P 0 ;0,1=37,2=0.000000
L 4.73053228 -0.95250059 4.73799911 -0.955 0 P 0 ;0,1=37,2=0.000000
L 4.73799911 -0.955 4.74546585 -0.95250059 0 P 0 ;0,1=37,2=0.000000
L 4.74546585 -0.95250059 4.75106644 -0.94625187 0 P 0 ;0,1=37,2=0.000000
L 4.75106644 -0.94625187 4.75480059 -0.93875128 0 P 0 ;0,1=37,2=0.000000
L 4.75480059 -0.93875128 4.7576 -0.92875108 0 P 0 ;0,1=37,2=0.000000
L 4.7576 -0.92875108 4.75853317 -0.91750118 0 P 0 ;0,1=37,2=0.000000
L 4.75853317 -0.91750118 4.7576 -0.90625128 0 P 0 ;0,1=37,2=0.000000
L 4.7576 -0.90625128 4.75480059 -0.89624882 0 P 0 ;0,1=37,2=0.000000
L 4.75480059 -0.89624882 4.75106644 -0.88875049 0 P 0 ;0,1=37,2=0.000000
L 4.75106644 -0.88875049 4.74546585 -0.88249951 0 P 0 ;0,1=37,2=0.000000
L 4.74546585 -0.88249951 4.73799911 -0.88 0 P 0 ;0,1=37,2=0.000000
L 4.79526614 -0.8924997 4.80086663 -0.88500128 0 P 0 ;0,1=37,2=0.000000
L 4.80086663 -0.88500128 4.8074003 -0.8812498 0 P 0 ;0,1=37,2=0.000000
L 4.8074003 -0.8812498 4.81486703 -0.88 0 P 0 ;0,1=37,2=0.000000
L 4.81486703 -0.88 4.8242001 -0.88249951 0 P 0 ;0,1=37,2=0.000000
L 4.8242001 -0.88249951 4.83073376 -0.88875049 0 P 0 ;0,1=37,2=0.000000
L 4.83073376 -0.88875049 4.8326 -0.89624882 0 P 0 ;0,1=37,2=0.000000
L 4.8326 -0.89624882 4.83166693 -0.90375187 0 P 0 ;0,1=37,2=0.000000
L 4.83166693 -0.90375187 4.82793268 -0.91000049 0 P 0 ;0,1=37,2=0.000000
L 4.82793268 -0.91000049 4.80926654 -0.9225001 0 P 0 ;0,1=37,2=0.000000
L 4.80926654 -0.9225001 4.80086663 -0.93125059 0 P 0 ;0,1=37,2=0.000000
L 4.80086663 -0.93125059 4.79526614 -0.94375246 0 P 0 ;0,1=37,2=0.000000
L 4.79526614 -0.94375246 4.7933999 -0.955 0 P 0 ;0,1=37,2=0.000000
L 4.7933999 -0.955 4.8326 -0.955 0 P 0 ;0,1=37,2=0.000000
L 3.36746673 -1.205 3.36746673 -1.13 0 P 0 ;0,1=38,2=0.000000
L 3.36746673 -1.13 3.38613287 -1.13 0 P 0 ;0,1=38,2=0.000000
L 3.38613287 -1.13 3.39359961 -1.13375157 0 P 0 ;0,1=38,2=0.000000
L 3.39359961 -1.13375157 3.3992001 -1.13875049 0 P 0 ;0,1=38,2=0.000000
L 3.3992001 -1.13875049 3.40386752 -1.14624882 0 P 0 ;0,1=38,2=0.000000
L 3.40386752 -1.14624882 3.4076 -1.15500157 0 P 0 ;0,1=38,2=0.000000
L 3.4076 -1.15500157 3.40853317 -1.16750118 0 P 0 ;0,1=38,2=0.000000
L 3.40853317 -1.16750118 3.4076 -1.18000079 0 P 0 ;0,1=38,2=0.000000
L 3.4076 -1.18000079 3.40386752 -1.18875128 0 P 0 ;0,1=38,2=0.000000
L 3.40386752 -1.18875128 3.3992001 -1.19625187 0 P 0 ;0,1=38,2=0.000000
L 3.3992001 -1.19625187 3.39359961 -1.20125089 0 P 0 ;0,1=38,2=0.000000
L 3.39359961 -1.20125089 3.38613287 -1.205 0 P 0 ;0,1=38,2=0.000000
L 3.38613287 -1.205 3.36746673 -1.205 0 P 0 ;0,1=38,2=0.000000
L 3.47980059 -1.205 3.47980059 -1.15500157 0 P 0 ;0,1=38,2=0.000000
L 3.47980059 -1.1637497 3.47606644 -1.15875079 0 P 0 ;0,1=38,2=0.000000
L 3.47606644 -1.15875079 3.47046585 -1.15625128 0 P 0 ;0,1=38,2=0.000000
L 3.47046585 -1.15625128 3.46393396 -1.15500157 0 P 0 ;0,1=38,2=0.000000
L 3.46393396 -1.15500157 3.4574003 -1.15750108 0 P 0 ;0,1=38,2=0.000000
L 3.4574003 -1.15750108 3.4517998 -1.1625 0 P 0 ;0,1=38,2=0.000000
L 3.4517998 -1.1625 3.44806555 -1.17000069 0 P 0 ;0,1=38,2=0.000000
L 3.44806555 -1.17000069 3.44619931 -1.18000079 0 P 0 ;0,1=38,2=0.000000
L 3.44619931 -1.18000079 3.44806555 -1.19000098 0 P 0 ;0,1=38,2=0.000000
L 3.44806555 -1.19000098 3.4517998 -1.19750167 0 P 0 ;0,1=38,2=0.000000
L 3.4517998 -1.19750167 3.4574003 -1.20250059 0 P 0 ;0,1=38,2=0.000000
L 3.4574003 -1.20250059 3.46393396 -1.205 0 P 0 ;0,1=38,2=0.000000
L 3.46393396 -1.205 3.47046585 -1.2037503 0 P 0 ;0,1=38,2=0.000000
L 3.47046585 -1.2037503 3.47606644 -1.20000108 0 P 0 ;0,1=38,2=0.000000
L 3.47606644 -1.20000108 3.47980059 -1.19500217 0 P 0 ;0,1=38,2=0.000000
L 3.53799911 -1.13 3.53799911 -1.205 0 P 0 ;0,1=38,2=0.000000
L 3.52493346 -1.15500157 3.55106644 -1.15500157 0 P 0 ;0,1=38,2=0.000000
L 3.59900039 -1.17125039 3.62886752 -1.17125039 0 P 0 ;0,1=38,2=0.000000
L 3.62886752 -1.17125039 3.62606644 -1.1625 0 P 0 ;0,1=38,2=0.000000
L 3.62606644 -1.1625 3.62140069 -1.15750108 0 P 0 ;0,1=38,2=0.000000
L 3.62140069 -1.15750108 3.61486703 -1.15500157 0 P 0 ;0,1=38,2=0.000000
L 3.61486703 -1.15500157 3.60833346 -1.15625128 0 P 0 ;0,1=38,2=0.000000
L 3.60833346 -1.15625128 3.60273287 -1.16000049 0 P 0 ;0,1=38,2=0.000000
L 3.60273287 -1.16000049 3.59900039 -1.16875089 0 P 0 ;0,1=38,2=0.000000
L 3.59900039 -1.16875089 3.59713238 -1.17625157 0 P 0 ;0,1=38,2=0.000000
L 3.59713238 -1.17625157 3.59713238 -1.18375 0 P 0 ;0,1=38,2=0.000000
L 3.59713238 -1.18375 3.59900039 -1.19125069 0 P 0 ;0,1=38,2=0.000000
L 3.59900039 -1.19125069 3.60366604 -1.19875138 0 P 0 ;0,1=38,2=0.000000
L 3.60366604 -1.19875138 3.60926654 -1.2037503 0 P 0 ;0,1=38,2=0.000000
L 3.60926654 -1.2037503 3.6158002 -1.205 0 P 0 ;0,1=38,2=0.000000
L 3.6158002 -1.205 3.62233386 -1.20250059 0 P 0 ;0,1=38,2=0.000000
L 3.62233386 -1.20250059 3.62886752 -1.19500217 0 P 0 ;0,1=38,2=0.000000
L 3.68799911 -1.20749941 3.68613287 -1.2062497 0 P 0 ;0,1=38,2=0.000000
L 3.68613287 -1.2062497 3.68613287 -1.2037503 0 P 0 ;0,1=38,2=0.000000
L 3.68613287 -1.2037503 3.68799911 -1.20250059 0 P 0 ;0,1=38,2=0.000000
L 3.68799911 -1.20250059 3.68986703 -1.2037503 0 P 0 ;0,1=38,2=0.000000
L 3.68986703 -1.2037503 3.68986703 -1.2062497 0 P 0 ;0,1=38,2=0.000000
L 3.68986703 -1.2062497 3.68799911 -1.20749941 0 P 0 ;0,1=38,2=0.000000
L 3.68799911 -1.17375217 3.68613287 -1.1725001 0 P 0 ;0,1=38,2=0.000000
L 3.68613287 -1.1725001 3.68613287 -1.17000069 0 P 0 ;0,1=38,2=0.000000
L 3.68613287 -1.17000069 3.68799911 -1.16875089 0 P 0 ;0,1=38,2=0.000000
L 3.68799911 -1.16875089 3.68986703 -1.17000069 0 P 0 ;0,1=38,2=0.000000
L 3.68986703 -1.17000069 3.68986703 -1.1725001 0 P 0 ;0,1=38,2=0.000000
L 3.68986703 -1.1725001 3.68799911 -1.17375217 0 P 0 ;0,1=38,2=0.000000
L 3.82026614 -1.1424997 3.82586663 -1.13500128 0 P 0 ;0,1=38,2=0.000000
L 3.82586663 -1.13500128 3.8324003 -1.1312498 0 P 0 ;0,1=38,2=0.000000
L 3.8324003 -1.1312498 3.83986703 -1.13 0 P 0 ;0,1=38,2=0.000000
L 3.83986703 -1.13 3.8492001 -1.13249951 0 P 0 ;0,1=38,2=0.000000
L 3.8492001 -1.13249951 3.85573376 -1.13875049 0 P 0 ;0,1=38,2=0.000000
L 3.85573376 -1.13875049 3.8576 -1.14624882 0 P 0 ;0,1=38,2=0.000000
L 3.8576 -1.14624882 3.85666693 -1.15375187 0 P 0 ;0,1=38,2=0.000000
L 3.85666693 -1.15375187 3.85293268 -1.16000049 0 P 0 ;0,1=38,2=0.000000
L 3.85293268 -1.16000049 3.83426654 -1.1725001 0 P 0 ;0,1=38,2=0.000000
L 3.83426654 -1.1725001 3.82586663 -1.18125059 0 P 0 ;0,1=38,2=0.000000
L 3.82586663 -1.18125059 3.82026614 -1.19375246 0 P 0 ;0,1=38,2=0.000000
L 3.82026614 -1.19375246 3.8183999 -1.205 0 P 0 ;0,1=38,2=0.000000
L 3.8183999 -1.205 3.8576 -1.205 0 P 0 ;0,1=38,2=0.000000
L 3.91299911 -1.13 3.90553228 -1.13249951 0 P 0 ;0,1=38,2=0.000000
L 3.90553228 -1.13249951 3.89993346 -1.13875049 0 P 0 ;0,1=38,2=0.000000
L 3.89993346 -1.13875049 3.89619931 -1.14624882 0 P 0 ;0,1=38,2=0.000000
L 3.89619931 -1.14624882 3.8933999 -1.15625128 0 P 0 ;0,1=38,2=0.000000
L 3.8933999 -1.15625128 3.89246673 -1.16750118 0 P 0 ;0,1=38,2=0.000000
L 3.89246673 -1.16750118 3.8933999 -1.17875108 0 P 0 ;0,1=38,2=0.000000
L 3.8933999 -1.17875108 3.89619931 -1.18875128 0 P 0 ;0,1=38,2=0.000000
L 3.89619931 -1.18875128 3.89993346 -1.19625187 0 P 0 ;0,1=38,2=0.000000
L 3.89993346 -1.19625187 3.90553228 -1.20250059 0 P 0 ;0,1=38,2=0.000000
L 3.90553228 -1.20250059 3.91299911 -1.205 0 P 0 ;0,1=38,2=0.000000
L 3.91299911 -1.205 3.92046585 -1.20250059 0 P 0 ;0,1=38,2=0.000000
L 3.92046585 -1.20250059 3.92606644 -1.19625187 0 P 0 ;0,1=38,2=0.000000
L 3.92606644 -1.19625187 3.92980059 -1.18875128 0 P 0 ;0,1=38,2=0.000000
L 3.92980059 -1.18875128 3.9326 -1.17875108 0 P 0 ;0,1=38,2=0.000000
L 3.9326 -1.17875108 3.93353317 -1.16750118 0 P 0 ;0,1=38,2=0.000000
L 3.93353317 -1.16750118 3.9326 -1.15625128 0 P 0 ;0,1=38,2=0.000000
L 3.9326 -1.15625128 3.92980059 -1.14624882 0 P 0 ;0,1=38,2=0.000000
L 3.92980059 -1.14624882 3.92606644 -1.13875049 0 P 0 ;0,1=38,2=0.000000
L 3.92606644 -1.13875049 3.92046585 -1.13249951 0 P 0 ;0,1=38,2=0.000000
L 3.92046585 -1.13249951 3.91299911 -1.13 0 P 0 ;0,1=38,2=0.000000
L 3.97026614 -1.1424997 3.97586663 -1.13500128 0 P 0 ;0,1=38,2=0.000000
L 3.97586663 -1.13500128 3.9824003 -1.1312498 0 P 0 ;0,1=38,2=0.000000
L 3.9824003 -1.1312498 3.98986703 -1.13 0 P 0 ;0,1=38,2=0.000000
L 3.98986703 -1.13 3.9992001 -1.13249951 0 P 0 ;0,1=38,2=0.000000
L 3.9992001 -1.13249951 4.00573376 -1.13875049 0 P 0 ;0,1=38,2=0.000000
L 4.00573376 -1.13875049 4.0076 -1.14624882 0 P 0 ;0,1=38,2=0.000000
L 4.0076 -1.14624882 4.00666693 -1.15375187 0 P 0 ;0,1=38,2=0.000000
L 4.00666693 -1.15375187 4.00293268 -1.16000049 0 P 0 ;0,1=38,2=0.000000
L 4.00293268 -1.16000049 3.98426654 -1.1725001 0 P 0 ;0,1=38,2=0.000000
L 3.98426654 -1.1725001 3.97586663 -1.18125059 0 P 0 ;0,1=38,2=0.000000
L 3.97586663 -1.18125059 3.97026614 -1.19375246 0 P 0 ;0,1=38,2=0.000000
L 3.97026614 -1.19375246 3.9683999 -1.205 0 P 0 ;0,1=38,2=0.000000
L 3.9683999 -1.205 4.0076 -1.205 0 P 0 ;0,1=38,2=0.000000
L 4.04526614 -1.1424997 4.05086663 -1.13500128 0 P 0 ;0,1=38,2=0.000000
L 4.05086663 -1.13500128 4.0574003 -1.1312498 0 P 0 ;0,1=38,2=0.000000
L 4.0574003 -1.1312498 4.06486703 -1.13 0 P 0 ;0,1=38,2=0.000000
L 4.06486703 -1.13 4.0742001 -1.13249951 0 P 0 ;0,1=38,2=0.000000
L 4.0742001 -1.13249951 4.08073376 -1.13875049 0 P 0 ;0,1=38,2=0.000000
L 4.08073376 -1.13875049 4.0826 -1.14624882 0 P 0 ;0,1=38,2=0.000000
L 4.0826 -1.14624882 4.08166693 -1.15375187 0 P 0 ;0,1=38,2=0.000000
L 4.08166693 -1.15375187 4.07793268 -1.16000049 0 P 0 ;0,1=38,2=0.000000
L 4.07793268 -1.16000049 4.05926654 -1.1725001 0 P 0 ;0,1=38,2=0.000000
L 4.05926654 -1.1725001 4.05086663 -1.18125059 0 P 0 ;0,1=38,2=0.000000
L 4.05086663 -1.18125059 4.04526614 -1.19375246 0 P 0 ;0,1=38,2=0.000000
L 4.04526614 -1.19375246 4.0433999 -1.205 0 P 0 ;0,1=38,2=0.000000
L 4.0433999 -1.205 4.0826 -1.205 0 P 0 ;0,1=38,2=0.000000
L 4.12586663 -1.18000079 4.15013327 -1.18000079 0 P 0 ;0,1=38,2=0.000000
L 4.21299911 -1.13 4.20553228 -1.13249951 0 P 0 ;0,1=38,2=0.000000
L 4.20553228 -1.13249951 4.19993346 -1.13875049 0 P 0 ;0,1=38,2=0.000000
L 4.19993346 -1.13875049 4.19619931 -1.14624882 0 P 0 ;0,1=38,2=0.000000
L 4.19619931 -1.14624882 4.1933999 -1.15625128 0 P 0 ;0,1=38,2=0.000000
L 4.1933999 -1.15625128 4.19246673 -1.16750118 0 P 0 ;0,1=38,2=0.000000
L 4.19246673 -1.16750118 4.1933999 -1.17875108 0 P 0 ;0,1=38,2=0.000000
L 4.1933999 -1.17875108 4.19619931 -1.18875128 0 P 0 ;0,1=38,2=0.000000
L 4.19619931 -1.18875128 4.19993346 -1.19625187 0 P 0 ;0,1=38,2=0.000000
L 4.19993346 -1.19625187 4.20553228 -1.20250059 0 P 0 ;0,1=38,2=0.000000
L 4.20553228 -1.20250059 4.21299911 -1.205 0 P 0 ;0,1=38,2=0.000000
L 4.21299911 -1.205 4.22046585 -1.20250059 0 P 0 ;0,1=38,2=0.000000
L 4.22046585 -1.20250059 4.22606644 -1.19625187 0 P 0 ;0,1=38,2=0.000000
L 4.22606644 -1.19625187 4.22980059 -1.18875128 0 P 0 ;0,1=38,2=0.000000
L 4.22980059 -1.18875128 4.2326 -1.17875108 0 P 0 ;0,1=38,2=0.000000
L 4.2326 -1.17875108 4.23353317 -1.16750118 0 P 0 ;0,1=38,2=0.000000
L 4.23353317 -1.16750118 4.2326 -1.15625128 0 P 0 ;0,1=38,2=0.000000
L 4.2326 -1.15625128 4.22980059 -1.14624882 0 P 0 ;0,1=38,2=0.000000
L 4.22980059 -1.14624882 4.22606644 -1.13875049 0 P 0 ;0,1=38,2=0.000000
L 4.22606644 -1.13875049 4.22046585 -1.13249951 0 P 0 ;0,1=38,2=0.000000
L 4.22046585 -1.13249951 4.21299911 -1.13 0 P 0 ;0,1=38,2=0.000000
L 4.27026614 -1.1424997 4.27586663 -1.13500128 0 P 0 ;0,1=38,2=0.000000
L 4.27586663 -1.13500128 4.2824003 -1.1312498 0 P 0 ;0,1=38,2=0.000000
L 4.2824003 -1.1312498 4.28986703 -1.13 0 P 0 ;0,1=38,2=0.000000
L 4.28986703 -1.13 4.2992001 -1.13249951 0 P 0 ;0,1=38,2=0.000000
L 4.2992001 -1.13249951 4.30573376 -1.13875049 0 P 0 ;0,1=38,2=0.000000
L 4.30573376 -1.13875049 4.3076 -1.14624882 0 P 0 ;0,1=38,2=0.000000
L 4.3076 -1.14624882 4.30666693 -1.15375187 0 P 0 ;0,1=38,2=0.000000
L 4.30666693 -1.15375187 4.30293268 -1.16000049 0 P 0 ;0,1=38,2=0.000000
L 4.30293268 -1.16000049 4.28426654 -1.1725001 0 P 0 ;0,1=38,2=0.000000
L 4.28426654 -1.1725001 4.27586663 -1.18125059 0 P 0 ;0,1=38,2=0.000000
L 4.27586663 -1.18125059 4.27026614 -1.19375246 0 P 0 ;0,1=38,2=0.000000
L 4.27026614 -1.19375246 4.2683999 -1.205 0 P 0 ;0,1=38,2=0.000000
L 4.2683999 -1.205 4.3076 -1.205 0 P 0 ;0,1=38,2=0.000000
L 4.35086663 -1.18000079 4.37513327 -1.18000079 0 P 0 ;0,1=38,2=0.000000
L 4.42026614 -1.1424997 4.42586663 -1.13500128 0 P 0 ;0,1=38,2=0.000000
L 4.42586663 -1.13500128 4.4324003 -1.1312498 0 P 0 ;0,1=38,2=0.000000
L 4.4324003 -1.1312498 4.43986703 -1.13 0 P 0 ;0,1=38,2=0.000000
L 4.43986703 -1.13 4.4492001 -1.13249951 0 P 0 ;0,1=38,2=0.000000
L 4.4492001 -1.13249951 4.45573376 -1.13875049 0 P 0 ;0,1=38,2=0.000000
L 4.45573376 -1.13875049 4.4576 -1.14624882 0 P 0 ;0,1=38,2=0.000000
L 4.4576 -1.14624882 4.45666693 -1.15375187 0 P 0 ;0,1=38,2=0.000000
L 4.45666693 -1.15375187 4.45293268 -1.16000049 0 P 0 ;0,1=38,2=0.000000
L 4.45293268 -1.16000049 4.43426654 -1.1725001 0 P 0 ;0,1=38,2=0.000000
L 4.43426654 -1.1725001 4.42586663 -1.18125059 0 P 0 ;0,1=38,2=0.000000
L 4.42586663 -1.18125059 4.42026614 -1.19375246 0 P 0 ;0,1=38,2=0.000000
L 4.42026614 -1.19375246 4.4183999 -1.205 0 P 0 ;0,1=38,2=0.000000
L 4.4183999 -1.205 4.4576 -1.205 0 P 0 ;0,1=38,2=0.000000
L 4.49246673 -1.19375246 4.49806555 -1.20000108 0 P 0 ;0,1=38,2=0.000000
L 4.49806555 -1.20000108 4.50459921 -1.2037503 0 P 0 ;0,1=38,2=0.000000
L 4.50459921 -1.2037503 4.51299911 -1.205 0 P 0 ;0,1=38,2=0.000000
L 4.51299911 -1.205 4.52140069 -1.20250059 0 P 0 ;0,1=38,2=0.000000
L 4.52140069 -1.20250059 4.52793268 -1.19750167 0 P 0 ;0,1=38,2=0.000000
L 4.52793268 -1.19750167 4.5326 -1.18875128 0 P 0 ;0,1=38,2=0.000000
L 4.5326 -1.18875128 4.53353317 -1.17875108 0 P 0 ;0,1=38,2=0.000000
L 4.53353317 -1.17875108 4.53166693 -1.16875089 0 P 0 ;0,1=38,2=0.000000
L 4.53166693 -1.16875089 4.52699951 -1.1625 0 P 0 ;0,1=38,2=0.000000
L 4.52699951 -1.1625 4.52046585 -1.15750108 0 P 0 ;0,1=38,2=0.000000
L 4.52046585 -1.15750108 4.51393396 -1.15625128 0 P 0 ;0,1=38,2=0.000000
L 4.51393396 -1.15625128 4.5074003 -1.15750108 0 P 0 ;0,1=38,2=0.000000
L 4.5074003 -1.15750108 4.49900039 -1.1625 0 P 0 ;0,1=38,2=0.000000
L 4.49900039 -1.1625 4.5017998 -1.13 0 P 0 ;0,1=38,2=0.000000
L 4.5017998 -1.13 4.52699951 -1.13 0 P 0 ;0,1=38,2=0.000000
L 3.29433297 -1.255 3.29433297 -1.33 0 P 0 ;0,1=39,2=0.000000
L 3.29433297 -1.33 3.33166693 -1.33 0 P 0 ;0,1=39,2=0.000000
L 3.40480059 -1.33 3.40480059 -1.28000157 0 P 0 ;0,1=39,2=0.000000
L 3.40480059 -1.2887497 3.40106644 -1.28375079 0 P 0 ;0,1=39,2=0.000000
L 3.40106644 -1.28375079 3.39546585 -1.28125128 0 P 0 ;0,1=39,2=0.000000
L 3.39546585 -1.28125128 3.38893396 -1.28000157 0 P 0 ;0,1=39,2=0.000000
L 3.38893396 -1.28000157 3.3824003 -1.28250108 0 P 0 ;0,1=39,2=0.000000
L 3.3824003 -1.28250108 3.3767998 -1.2875 0 P 0 ;0,1=39,2=0.000000
L 3.3767998 -1.2875 3.37306555 -1.29500069 0 P 0 ;0,1=39,2=0.000000
L 3.37306555 -1.29500069 3.37119931 -1.30500079 0 P 0 ;0,1=39,2=0.000000
L 3.37119931 -1.30500079 3.37306555 -1.31500098 0 P 0 ;0,1=39,2=0.000000
L 3.37306555 -1.31500098 3.3767998 -1.32250167 0 P 0 ;0,1=39,2=0.000000
L 3.3767998 -1.32250167 3.3824003 -1.32750059 0 P 0 ;0,1=39,2=0.000000
L 3.3824003 -1.32750059 3.38893396 -1.33 0 P 0 ;0,1=39,2=0.000000
L 3.38893396 -1.33 3.39546585 -1.3287503 0 P 0 ;0,1=39,2=0.000000
L 3.39546585 -1.3287503 3.40106644 -1.32500108 0 P 0 ;0,1=39,2=0.000000
L 3.40106644 -1.32500108 3.40480059 -1.32000217 0 P 0 ;0,1=39,2=0.000000
L 3.4433999 -1.3524997 3.44900039 -1.35499921 0 P 0 ;0,1=39,2=0.000000
L 3.44900039 -1.35499921 3.45646713 -1.3524997 0 P 0 ;0,1=39,2=0.000000
L 3.45646713 -1.3524997 3.46113287 -1.34750079 0 P 0 ;0,1=39,2=0.000000
L 3.46113287 -1.34750079 3.46486703 -1.3412498 0 P 0 ;0,1=39,2=0.000000
L 3.46486703 -1.3412498 3.47046585 -1.32125187 0 P 0 ;0,1=39,2=0.000000
L 3.47046585 -1.32125187 3.4826 -1.28000157 0 P 0 ;0,1=39,2=0.000000
L 3.45273287 -1.28000157 3.47046585 -1.32125187 0 P 0 ;0,1=39,2=0.000000
L 3.52400039 -1.29625039 3.55386752 -1.29625039 0 P 0 ;0,1=39,2=0.000000
L 3.55386752 -1.29625039 3.55106644 -1.2875 0 P 0 ;0,1=39,2=0.000000
L 3.55106644 -1.2875 3.54640069 -1.28250108 0 P 0 ;0,1=39,2=0.000000
L 3.54640069 -1.28250108 3.53986703 -1.28000157 0 P 0 ;0,1=39,2=0.000000
L 3.53986703 -1.28000157 3.53333346 -1.28125128 0 P 0 ;0,1=39,2=0.000000
L 3.53333346 -1.28125128 3.52773287 -1.28500049 0 P 0 ;0,1=39,2=0.000000
L 3.52773287 -1.28500049 3.52400039 -1.29375089 0 P 0 ;0,1=39,2=0.000000
L 3.52400039 -1.29375089 3.52213238 -1.30125157 0 P 0 ;0,1=39,2=0.000000
L 3.52213238 -1.30125157 3.52213238 -1.30875 0 P 0 ;0,1=39,2=0.000000
L 3.52213238 -1.30875 3.52400039 -1.31625069 0 P 0 ;0,1=39,2=0.000000
L 3.52400039 -1.31625069 3.52866604 -1.32375138 0 P 0 ;0,1=39,2=0.000000
L 3.52866604 -1.32375138 3.53426654 -1.3287503 0 P 0 ;0,1=39,2=0.000000
L 3.53426654 -1.3287503 3.5408002 -1.33 0 P 0 ;0,1=39,2=0.000000
L 3.5408002 -1.33 3.54733386 -1.32750059 0 P 0 ;0,1=39,2=0.000000
L 3.54733386 -1.32750059 3.55386752 -1.32000217 0 P 0 ;0,1=39,2=0.000000
L 3.59993346 -1.33 3.59993346 -1.28000157 0 P 0 ;0,1=39,2=0.000000
L 3.59993346 -1.28999941 3.60459921 -1.28500049 0 P 0 ;0,1=39,2=0.000000
L 3.60459921 -1.28500049 3.60926654 -1.28125128 0 P 0 ;0,1=39,2=0.000000
L 3.60926654 -1.28125128 3.6158002 -1.28000157 0 P 0 ;0,1=39,2=0.000000
L 3.6158002 -1.28000157 3.62046585 -1.28125128 0 P 0 ;0,1=39,2=0.000000
L 3.62046585 -1.28125128 3.62606644 -1.28500049 0 P 0 ;0,1=39,2=0.000000
L 3.68799911 -1.33249941 3.68613287 -1.3312497 0 P 0 ;0,1=39,2=0.000000
L 3.68613287 -1.3312497 3.68613287 -1.3287503 0 P 0 ;0,1=39,2=0.000000
L 3.68613287 -1.3287503 3.68799911 -1.32750059 0 P 0 ;0,1=39,2=0.000000
L 3.68799911 -1.32750059 3.68986703 -1.3287503 0 P 0 ;0,1=39,2=0.000000
L 3.68986703 -1.3287503 3.68986703 -1.3312497 0 P 0 ;0,1=39,2=0.000000
L 3.68986703 -1.3312497 3.68799911 -1.33249941 0 P 0 ;0,1=39,2=0.000000
L 3.68799911 -1.29875217 3.68613287 -1.2975001 0 P 0 ;0,1=39,2=0.000000
L 3.68613287 -1.2975001 3.68613287 -1.29500069 0 P 0 ;0,1=39,2=0.000000
L 3.68613287 -1.29500069 3.68799911 -1.29375089 0 P 0 ;0,1=39,2=0.000000
L 3.68799911 -1.29375089 3.68986703 -1.29500069 0 P 0 ;0,1=39,2=0.000000
L 3.68986703 -1.29500069 3.68986703 -1.2975001 0 P 0 ;0,1=39,2=0.000000
L 3.68986703 -1.2975001 3.68799911 -1.29875217 0 P 0 ;0,1=39,2=0.000000
L 3.36933297 -1.08 3.36933297 -1.005 0 P 0 ;0,1=40,2=0.000000
L 3.36933297 -1.005 3.39266644 -1.005 0 P 0 ;0,1=40,2=0.000000
L 3.39266644 -1.005 3.40013327 -1.00875157 0 P 0 ;0,1=40,2=0.000000
L 3.40013327 -1.00875157 3.40480059 -1.01375049 0 P 0 ;0,1=40,2=0.000000
L 3.40480059 -1.01375049 3.40666693 -1.02375059 0 P 0 ;0,1=40,2=0.000000
L 3.40666693 -1.02375059 3.40480059 -1.03375079 0 P 0 ;0,1=40,2=0.000000
L 3.40480059 -1.03375079 3.3992001 -1.03999941 0 P 0 ;0,1=40,2=0.000000
L 3.3992001 -1.03999941 3.39266644 -1.04375089 0 P 0 ;0,1=40,2=0.000000
L 3.39266644 -1.04375089 3.36933297 -1.04375089 0 P 0 ;0,1=40,2=0.000000
L 3.39266644 -1.04375089 3.40666693 -1.08 0 P 0 ;0,1=40,2=0.000000
L 3.44900039 -1.04625039 3.47886752 -1.04625039 0 P 0 ;0,1=40,2=0.000000
L 3.47886752 -1.04625039 3.47606644 -1.0375 0 P 0 ;0,1=40,2=0.000000
L 3.47606644 -1.0375 3.47140069 -1.03250108 0 P 0 ;0,1=40,2=0.000000
L 3.47140069 -1.03250108 3.46486703 -1.03000157 0 P 0 ;0,1=40,2=0.000000
L 3.46486703 -1.03000157 3.45833346 -1.03125128 0 P 0 ;0,1=40,2=0.000000
L 3.45833346 -1.03125128 3.45273287 -1.03500049 0 P 0 ;0,1=40,2=0.000000
L 3.45273287 -1.03500049 3.44900039 -1.04375089 0 P 0 ;0,1=40,2=0.000000
L 3.44900039 -1.04375089 3.44713238 -1.05125157 0 P 0 ;0,1=40,2=0.000000
L 3.44713238 -1.05125157 3.44713238 -1.05875 0 P 0 ;0,1=40,2=0.000000
L 3.44713238 -1.05875 3.44900039 -1.06625069 0 P 0 ;0,1=40,2=0.000000
L 3.44900039 -1.06625069 3.45366604 -1.07375138 0 P 0 ;0,1=40,2=0.000000
L 3.45366604 -1.07375138 3.45926654 -1.0787503 0 P 0 ;0,1=40,2=0.000000
L 3.45926654 -1.0787503 3.4658002 -1.08 0 P 0 ;0,1=40,2=0.000000
L 3.4658002 -1.08 3.47233386 -1.07750059 0 P 0 ;0,1=40,2=0.000000
L 3.47233386 -1.07750059 3.47886752 -1.07000217 0 P 0 ;0,1=40,2=0.000000
L 3.52119931 -1.03000157 3.53799911 -1.08 0 P 0 ;0,1=40,2=0.000000
L 3.53799911 -1.08 3.55480059 -1.03000157 0 P 0 ;0,1=40,2=0.000000
L 3.68799911 -1.08249941 3.68613287 -1.0812497 0 P 0 ;0,1=40,2=0.000000
L 3.68613287 -1.0812497 3.68613287 -1.0787503 0 P 0 ;0,1=40,2=0.000000
L 3.68613287 -1.0787503 3.68799911 -1.07750059 0 P 0 ;0,1=40,2=0.000000
L 3.68799911 -1.07750059 3.68986703 -1.0787503 0 P 0 ;0,1=40,2=0.000000
L 3.68986703 -1.0787503 3.68986703 -1.0812497 0 P 0 ;0,1=40,2=0.000000
L 3.68986703 -1.0812497 3.68799911 -1.08249941 0 P 0 ;0,1=40,2=0.000000
L 3.68799911 -1.04875217 3.68613287 -1.0475001 0 P 0 ;0,1=40,2=0.000000
L 3.68613287 -1.0475001 3.68613287 -1.04500069 0 P 0 ;0,1=40,2=0.000000
L 3.68613287 -1.04500069 3.68799911 -1.04375089 0 P 0 ;0,1=40,2=0.000000
L 3.68799911 -1.04375089 3.68986703 -1.04500069 0 P 0 ;0,1=40,2=0.000000
L 3.68986703 -1.04500069 3.68986703 -1.0475001 0 P 0 ;0,1=40,2=0.000000
L 3.68986703 -1.0475001 3.68799911 -1.04875217 0 P 0 ;0,1=40,2=0.000000
L 3.83799911 -1.005 3.83053228 -1.00749951 0 P 0 ;0,1=40,2=0.000000
L 3.83053228 -1.00749951 3.82493346 -1.01375049 0 P 0 ;0,1=40,2=0.000000
L 3.82493346 -1.01375049 3.82119931 -1.02124882 0 P 0 ;0,1=40,2=0.000000
L 3.82119931 -1.02124882 3.8183999 -1.03125128 0 P 0 ;0,1=40,2=0.000000
L 3.8183999 -1.03125128 3.81746673 -1.04250118 0 P 0 ;0,1=40,2=0.000000
L 3.81746673 -1.04250118 3.8183999 -1.05375108 0 P 0 ;0,1=40,2=0.000000
L 3.8183999 -1.05375108 3.82119931 -1.06375128 0 P 0 ;0,1=40,2=0.000000
L 3.82119931 -1.06375128 3.82493346 -1.07125187 0 P 0 ;0,1=40,2=0.000000
L 3.82493346 -1.07125187 3.83053228 -1.07750059 0 P 0 ;0,1=40,2=0.000000
L 3.83053228 -1.07750059 3.83799911 -1.08 0 P 0 ;0,1=40,2=0.000000
L 3.83799911 -1.08 3.84546585 -1.07750059 0 P 0 ;0,1=40,2=0.000000
L 3.84546585 -1.07750059 3.85106644 -1.07125187 0 P 0 ;0,1=40,2=0.000000
L 3.85106644 -1.07125187 3.85480059 -1.06375128 0 P 0 ;0,1=40,2=0.000000
L 3.85480059 -1.06375128 3.8576 -1.05375108 0 P 0 ;0,1=40,2=0.000000
L 3.8576 -1.05375108 3.85853317 -1.04250118 0 P 0 ;0,1=40,2=0.000000
L 3.85853317 -1.04250118 3.8576 -1.03125128 0 P 0 ;0,1=40,2=0.000000
L 3.8576 -1.03125128 3.85480059 -1.02124882 0 P 0 ;0,1=40,2=0.000000
L 3.85480059 -1.02124882 3.85106644 -1.01375049 0 P 0 ;0,1=40,2=0.000000
L 3.85106644 -1.01375049 3.84546585 -1.00749951 0 P 0 ;0,1=40,2=0.000000
L 3.84546585 -1.00749951 3.83799911 -1.005 0 P 0 ;0,1=40,2=0.000000
L 3.91299911 -1.08 3.91299911 -1.005 0 P 0 ;0,1=40,2=0.000000
L 3.91299911 -1.005 3.9017998 -1.01999911 0 P 0 ;0,1=40,2=0.000000
L 3.9017998 -1.08 3.92419843 -1.08 0 P 0 ;0,1=40,2=0.000000
L 3.62349961 0.8005 3.62349961 0.7695 1 P 0 ;0,1=41,2=0.000000
L 3.61468337 0.8005 3.63231654 0.8005 1 P 0 ;0,1=41,2=0.000000
L 3.64683317 0.7695 3.64683317 0.8005 1 P 0 ;0,1=41,2=0.000000
L 3.64683317 0.8005 3.65603327 0.8005 1 P 0 ;0,1=41,2=0.000000
L 3.65603327 0.8005 3.6591 0.79894931 1 P 0 ;0,1=41,2=0.000000
L 3.6591 0.79894931 3.6614002 0.79533346 1 P 0 ;0,1=41,2=0.000000
L 3.6614002 0.79533346 3.66216673 0.7912 1 P 0 ;0,1=41,2=0.000000
L 3.66216673 0.7912 3.6614002 0.78706663 1 P 0 ;0,1=41,2=0.000000
L 3.6614002 0.78706663 3.65948327 0.78396634 1 P 0 ;0,1=41,2=0.000000
L 3.65948327 0.78396634 3.65603327 0.78241575 1 P 0 ;0,1=41,2=0.000000
L 3.65603327 0.78241575 3.64683317 0.78241575 1 P 0 ;0,1=41,2=0.000000
L 3.67706663 0.77414892 3.67936614 0.77156614 1 P 0 ;0,1=41,2=0.000000
L 3.67936614 0.77156614 3.68204961 0.77001654 1 P 0 ;0,1=41,2=0.000000
L 3.68204961 0.77001654 3.68549961 0.7695 1 P 0 ;0,1=41,2=0.000000
L 3.68549961 0.7695 3.6889503 0.77053307 1 P 0 ;0,1=41,2=0.000000
L 3.6889503 0.77053307 3.69163307 0.77259931 1 P 0 ;0,1=41,2=0.000000
L 3.69163307 0.77259931 3.69355 0.77621614 1 P 0 ;0,1=41,2=0.000000
L 3.69355 0.77621614 3.69393327 0.78034951 1 P 0 ;0,1=41,2=0.000000
L 3.69393327 0.78034951 3.69316673 0.78448287 1 P 0 ;0,1=41,2=0.000000
L 3.69316673 0.78448287 3.6912498 0.78706663 1 P 0 ;0,1=41,2=0.000000
L 3.6912498 0.78706663 3.68856634 0.78913287 1 P 0 ;0,1=41,2=0.000000
L 3.68856634 0.78913287 3.68588356 0.78964941 1 P 0 ;0,1=41,2=0.000000
L 3.68588356 0.78964941 3.6832001 0.78913287 1 P 0 ;0,1=41,2=0.000000
L 3.6832001 0.78913287 3.6797501 0.78706663 1 P 0 ;0,1=41,2=0.000000
L 3.6797501 0.78706663 3.6808999 0.8005 1 P 0 ;0,1=41,2=0.000000
L 3.6808999 0.8005 3.6912498 0.8005 1 P 0 ;0,1=41,2=0.000000
L 3.71649961 0.8005 3.71343287 0.79946683 1 P 0 ;0,1=41,2=0.000000
L 3.71343287 0.79946683 3.71113337 0.79688307 1 P 0 ;0,1=41,2=0.000000
L 3.71113337 0.79688307 3.7095997 0.79378376 1 P 0 ;0,1=41,2=0.000000
L 3.7095997 0.79378376 3.7084499 0.78964941 1 P 0 ;0,1=41,2=0.000000
L 3.7084499 0.78964941 3.70806663 0.78499951 1 P 0 ;0,1=41,2=0.000000
L 3.70806663 0.78499951 3.7084499 0.78034951 1 P 0 ;0,1=41,2=0.000000
L 3.7084499 0.78034951 3.7095997 0.77621614 1 P 0 ;0,1=41,2=0.000000
L 3.7095997 0.77621614 3.71113337 0.77311585 1 P 0 ;0,1=41,2=0.000000
L 3.71113337 0.77311585 3.71343287 0.77053307 1 P 0 ;0,1=41,2=0.000000
L 3.71343287 0.77053307 3.71649961 0.7695 1 P 0 ;0,1=41,2=0.000000
L 3.71649961 0.7695 3.71956634 0.77053307 1 P 0 ;0,1=41,2=0.000000
L 3.71956634 0.77053307 3.72186654 0.77311585 1 P 0 ;0,1=41,2=0.000000
L 3.72186654 0.77311585 3.7234002 0.77621614 1 P 0 ;0,1=41,2=0.000000
L 3.7234002 0.77621614 3.72455 0.78034951 1 P 0 ;0,1=41,2=0.000000
L 3.72455 0.78034951 3.72493327 0.78499951 1 P 0 ;0,1=41,2=0.000000
L 3.72493327 0.78499951 3.72455 0.78964941 1 P 0 ;0,1=41,2=0.000000
L 3.72455 0.78964941 3.7234002 0.79378376 1 P 0 ;0,1=41,2=0.000000
L 3.7234002 0.79378376 3.72186654 0.79688307 1 P 0 ;0,1=41,2=0.000000
L 3.72186654 0.79688307 3.71956634 0.79946683 1 P 0 ;0,1=41,2=0.000000
L 3.71956634 0.79946683 3.71649961 0.8005 1 P 0 ;0,1=41,2=0.000000
L 2.9895 1.59349961 3.0205 1.59349961 1 P 0 ;0,1=42,2=270.000000
L 2.9895 1.58468337 2.9895 1.60231654 1 P 0 ;0,1=42,2=270.000000
L 3.0205 1.61683317 2.9895 1.61683317 1 P 0 ;0,1=42,2=270.000000
L 2.9895 1.61683317 2.9895 1.62603327 1 P 0 ;0,1=42,2=270.000000
L 2.9895 1.62603327 2.99105069 1.6291 1 P 0 ;0,1=42,2=270.000000
L 2.99105069 1.6291 2.99466654 1.6314002 1 P 0 ;0,1=42,2=270.000000
L 2.99466654 1.6314002 2.9988 1.63216673 1 P 0 ;0,1=42,2=270.000000
L 2.9988 1.63216673 3.00293337 1.6314002 1 P 0 ;0,1=42,2=270.000000
L 3.00293337 1.6314002 3.00603366 1.62948327 1 P 0 ;0,1=42,2=270.000000
L 3.00603366 1.62948327 3.00758425 1.62603327 1 P 0 ;0,1=42,2=270.000000
L 3.00758425 1.62603327 3.00758425 1.61683317 1 P 0 ;0,1=42,2=270.000000
L 3.01585108 1.64706663 3.01843386 1.64936614 1 P 0 ;0,1=42,2=270.000000
L 3.01843386 1.64936614 3.01998346 1.65204961 1 P 0 ;0,1=42,2=270.000000
L 3.01998346 1.65204961 3.0205 1.65549961 1 P 0 ;0,1=42,2=270.000000
L 3.0205 1.65549961 3.01946693 1.6589503 1 P 0 ;0,1=42,2=270.000000
L 3.01946693 1.6589503 3.01740069 1.66163307 1 P 0 ;0,1=42,2=270.000000
L 3.01740069 1.66163307 3.01378386 1.66355 1 P 0 ;0,1=42,2=270.000000
L 3.01378386 1.66355 3.00965049 1.66393327 1 P 0 ;0,1=42,2=270.000000
L 3.00965049 1.66393327 3.00551713 1.66316673 1 P 0 ;0,1=42,2=270.000000
L 3.00551713 1.66316673 3.00293337 1.6612498 1 P 0 ;0,1=42,2=270.000000
L 3.00293337 1.6612498 3.00086713 1.65856634 1 P 0 ;0,1=42,2=270.000000
L 3.00086713 1.65856634 3.00035059 1.65588356 1 P 0 ;0,1=42,2=270.000000
L 3.00035059 1.65588356 3.00086713 1.6532001 1 P 0 ;0,1=42,2=270.000000
L 3.00086713 1.6532001 3.00293337 1.6497501 1 P 0 ;0,1=42,2=270.000000
L 3.00293337 1.6497501 2.9895 1.6508999 1 P 0 ;0,1=42,2=270.000000
L 2.9895 1.6508999 2.9895 1.6612498 1 P 0 ;0,1=42,2=270.000000
L 3.0205 1.68649961 2.9895 1.68649961 1 P 0 ;0,1=42,2=270.000000
L 2.9895 1.68649961 2.9956997 1.6818999 1 P 0 ;0,1=42,2=270.000000
L 3.0205 1.6818999 3.0205 1.69109931 1 P 0 ;0,1=42,2=270.000000
L 2.26849961 0.5655 2.26849961 0.5345 1 P 0 ;0,1=43,2=0.000000
L 2.25968337 0.5655 2.27731654 0.5655 1 P 0 ;0,1=43,2=0.000000
L 2.29183317 0.5345 2.29183317 0.5655 1 P 0 ;0,1=43,2=0.000000
L 2.29183317 0.5655 2.30103327 0.5655 1 P 0 ;0,1=43,2=0.000000
L 2.30103327 0.5655 2.3041 0.56394931 1 P 0 ;0,1=43,2=0.000000
L 2.3041 0.56394931 2.3064002 0.56033346 1 P 0 ;0,1=43,2=0.000000
L 2.3064002 0.56033346 2.30716673 0.5562 1 P 0 ;0,1=43,2=0.000000
L 2.30716673 0.5562 2.3064002 0.55206663 1 P 0 ;0,1=43,2=0.000000
L 2.3064002 0.55206663 2.30448327 0.54896634 1 P 0 ;0,1=43,2=0.000000
L 2.30448327 0.54896634 2.30103327 0.54741575 1 P 0 ;0,1=43,2=0.000000
L 2.30103327 0.54741575 2.29183317 0.54741575 1 P 0 ;0,1=43,2=0.000000
L 2.3351 0.5345 2.3351 0.5655 1 P 0 ;0,1=43,2=0.000000
L 2.3351 0.5655 2.32091624 0.54328327 1 P 0 ;0,1=43,2=0.000000
L 2.32091624 0.54328327 2.34008366 0.54328327 1 P 0 ;0,1=43,2=0.000000
L 2.36149961 0.5345 2.36418307 0.53501654 1 P 0 ;0,1=43,2=0.000000
L 2.36418307 0.53501654 2.3672498 0.53656614 1 P 0 ;0,1=43,2=0.000000
L 2.3672498 0.53656614 2.36916673 0.53914892 1 P 0 ;0,1=43,2=0.000000
L 2.36916673 0.53914892 2.36993327 0.54276673 1 P 0 ;0,1=43,2=0.000000
L 2.36993327 0.54276673 2.36916673 0.54638268 1 P 0 ;0,1=43,2=0.000000
L 2.36916673 0.54638268 2.36686654 0.54948287 1 P 0 ;0,1=43,2=0.000000
L 2.36686654 0.54948287 2.36341654 0.55103356 1 P 0 ;0,1=43,2=0.000000
L 2.36341654 0.55103356 2.35958337 0.55103356 1 P 0 ;0,1=43,2=0.000000
L 2.35958337 0.55103356 2.35728317 0.55206663 1 P 0 ;0,1=43,2=0.000000
L 2.35728317 0.55206663 2.35536614 0.55464941 1 P 0 ;0,1=43,2=0.000000
L 2.35536614 0.55464941 2.3545997 0.55826624 1 P 0 ;0,1=43,2=0.000000
L 2.3545997 0.55826624 2.3557501 0.56188307 1 P 0 ;0,1=43,2=0.000000
L 2.3557501 0.56188307 2.35843287 0.56446683 1 P 0 ;0,1=43,2=0.000000
L 2.35843287 0.56446683 2.36149961 0.5655 1 P 0 ;0,1=43,2=0.000000
L 2.36149961 0.5655 2.36456634 0.56446683 1 P 0 ;0,1=43,2=0.000000
L 2.36456634 0.56446683 2.3672498 0.56188307 1 P 0 ;0,1=43,2=0.000000
L 2.3672498 0.56188307 2.3684002 0.55826624 1 P 0 ;0,1=43,2=0.000000
L 2.3684002 0.55826624 2.36763307 0.55464941 1 P 0 ;0,1=43,2=0.000000
L 2.36763307 0.55464941 2.36571673 0.55206663 1 P 0 ;0,1=43,2=0.000000
L 2.36571673 0.55206663 2.36341654 0.55103356 1 P 0 ;0,1=43,2=0.000000
L 2.36341654 0.55103356 2.35958337 0.55103356 1 P 0 ;0,1=43,2=0.000000
L 2.35958337 0.55103356 2.35613337 0.54948287 1 P 0 ;0,1=43,2=0.000000
L 2.35613337 0.54948287 2.35383317 0.54638268 1 P 0 ;0,1=43,2=0.000000
L 2.35383317 0.54638268 2.35306663 0.54276673 1 P 0 ;0,1=43,2=0.000000
L 2.35306663 0.54276673 2.35383317 0.53914892 1 P 0 ;0,1=43,2=0.000000
L 2.35383317 0.53914892 2.3557501 0.53656614 1 P 0 ;0,1=43,2=0.000000
L 2.3557501 0.53656614 2.35881683 0.53501654 1 P 0 ;0,1=43,2=0.000000
L 2.35881683 0.53501654 2.36149961 0.5345 1 P 0 ;0,1=43,2=0.000000
L 3.7005 1.7399997 3.7255 1.7399997 1 P 0 ;0,1=44,2=270.000000
L 3.7005 1.73386673 3.7005 1.74613317 1 P 0 ;0,1=44,2=270.000000
L 3.7255 1.75666654 3.7005 1.75666654 1 P 0 ;0,1=44,2=270.000000
L 3.7005 1.75666654 3.7005 1.76306663 1 P 0 ;0,1=44,2=270.000000
L 3.7005 1.76306663 3.70175059 1.7652 1 P 0 ;0,1=44,2=270.000000
L 3.70175059 1.7652 3.70466663 1.7668001 1 P 0 ;0,1=44,2=270.000000
L 3.70466663 1.7668001 3.708 1.76733337 1 P 0 ;0,1=44,2=270.000000
L 3.708 1.76733337 3.71133337 1.7668001 1 P 0 ;0,1=44,2=270.000000
L 3.71133337 1.7668001 3.71383356 1.76546663 1 P 0 ;0,1=44,2=270.000000
L 3.71383356 1.76546663 3.71508406 1.76306663 1 P 0 ;0,1=44,2=270.000000
L 3.71508406 1.76306663 3.71508406 1.75666654 1 P 0 ;0,1=44,2=270.000000
L 3.7255 1.7872 3.7005 1.7872 1 P 0 ;0,1=44,2=270.000000
L 3.7005 1.7872 3.71841673 1.77733297 1 P 0 ;0,1=44,2=270.000000
L 3.71841673 1.77733297 3.71841673 1.79066693 1 P 0 ;0,1=44,2=270.000000
L 3.7255 1.80546654 3.72008376 1.8059997 1 P 0 ;0,1=44,2=270.000000
L 3.72008376 1.8059997 3.71550069 1.8068 1 P 0 ;0,1=44,2=270.000000
L 3.71550069 1.8068 3.71133337 1.80786644 1 P 0 ;0,1=44,2=270.000000
L 3.71133337 1.80786644 3.7067502 1.8092 1 P 0 ;0,1=44,2=270.000000
L 3.7067502 1.8092 3.7005 1.81133337 1 P 0 ;0,1=44,2=270.000000
L 3.7005 1.81133337 3.7005 1.80066654 1 P 0 ;0,1=44,2=270.000000
L 4.9325 1.5269997 4.9575 1.5269997 1 P 0 ;0,1=45,2=270.000000
L 4.9325 1.52086673 4.9325 1.53313317 1 P 0 ;0,1=45,2=270.000000
L 4.9575 1.54366654 4.9325 1.54366654 1 P 0 ;0,1=45,2=270.000000
L 4.9325 1.54366654 4.9325 1.55006663 1 P 0 ;0,1=45,2=270.000000
L 4.9325 1.55006663 4.93375059 1.5522 1 P 0 ;0,1=45,2=270.000000
L 4.93375059 1.5522 4.93666663 1.5538001 1 P 0 ;0,1=45,2=270.000000
L 4.93666663 1.5538001 4.94 1.55433337 1 P 0 ;0,1=45,2=270.000000
L 4.94 1.55433337 4.94333337 1.5538001 1 P 0 ;0,1=45,2=270.000000
L 4.94333337 1.5538001 4.94583356 1.55246663 1 P 0 ;0,1=45,2=270.000000
L 4.94583356 1.55246663 4.94708406 1.55006663 1 P 0 ;0,1=45,2=270.000000
L 4.94708406 1.55006663 4.94708406 1.54366654 1 P 0 ;0,1=45,2=270.000000
L 4.94708406 1.56593317 4.94416654 1.5677999 1 P 0 ;0,1=45,2=270.000000
L 4.94416654 1.5677999 4.9425002 1.5694 1 P 0 ;0,1=45,2=270.000000
L 4.9425002 1.5694 4.94166703 1.57153337 1 P 0 ;0,1=45,2=270.000000
L 4.94166703 1.57153337 4.9425002 1.5734002 1 P 0 ;0,1=45,2=270.000000
L 4.9425002 1.5734002 4.94416654 1.57473327 1 P 0 ;0,1=45,2=270.000000
L 4.94416654 1.57473327 4.94666673 1.5758001 1 P 0 ;0,1=45,2=270.000000
L 4.94666673 1.5758001 4.94958356 1.57606673 1 P 0 ;0,1=45,2=270.000000
L 4.94958356 1.57606673 4.95208376 1.5758001 1 P 0 ;0,1=45,2=270.000000
L 4.95208376 1.5758001 4.95458396 1.57473327 1 P 0 ;0,1=45,2=270.000000
L 4.95458396 1.57473327 4.95666693 1.57313307 1 P 0 ;0,1=45,2=270.000000
L 4.95666693 1.57313307 4.9575 1.57126683 1 P 0 ;0,1=45,2=270.000000
L 4.9575 1.57126683 4.95666693 1.56913346 1 P 0 ;0,1=45,2=270.000000
L 4.95666693 1.56913346 4.95416742 1.56726663 1 P 0 ;0,1=45,2=270.000000
L 4.95416742 1.56726663 4.95041673 1.5661998 1 P 0 ;0,1=45,2=270.000000
L 4.95041673 1.5661998 4.9462502 1.56593317 1 P 0 ;0,1=45,2=270.000000
L 4.9462502 1.56593317 4.94083386 1.56646634 1 P 0 ;0,1=45,2=270.000000
L 4.94083386 1.56646634 4.93791634 1.56726663 1 P 0 ;0,1=45,2=270.000000
L 4.93791634 1.56726663 4.9350003 1.5685997 1 P 0 ;0,1=45,2=270.000000
L 4.9350003 1.5685997 4.93291663 1.57046654 1 P 0 ;0,1=45,2=270.000000
L 4.93291663 1.57046654 4.9325 1.57233327 1 P 0 ;0,1=45,2=270.000000
L 4.9325 1.57233327 4.93333317 1.5742 1 P 0 ;0,1=45,2=270.000000
L 4.93333317 1.5742 4.93541683 1.57553356 1 P 0 ;0,1=45,2=270.000000
L 4.93666663 1.58793317 4.93416713 1.58953327 1 P 0 ;0,1=45,2=270.000000
L 4.93416713 1.58953327 4.93291663 1.5914 1 P 0 ;0,1=45,2=270.000000
L 4.93291663 1.5914 4.9325 1.59353337 1 P 0 ;0,1=45,2=270.000000
L 4.9325 1.59353337 4.93333317 1.5962 1 P 0 ;0,1=45,2=270.000000
L 4.93333317 1.5962 4.93541683 1.59806673 1 P 0 ;0,1=45,2=270.000000
L 4.93541683 1.59806673 4.93791634 1.5986 1 P 0 ;0,1=45,2=270.000000
L 4.93791634 1.5986 4.94041732 1.59833337 1 P 0 ;0,1=45,2=270.000000
L 4.94041732 1.59833337 4.9425002 1.59726644 1 P 0 ;0,1=45,2=270.000000
L 4.9425002 1.59726644 4.94666673 1.59193327 1 P 0 ;0,1=45,2=270.000000
L 4.94666673 1.59193327 4.94958356 1.58953327 1 P 0 ;0,1=45,2=270.000000
L 4.94958356 1.58953327 4.95375089 1.58793317 1 P 0 ;0,1=45,2=270.000000
L 4.95375089 1.58793317 4.9575 1.5873999 1 P 0 ;0,1=45,2=270.000000
L 4.9575 1.5873999 4.9575 1.5986 1 P 0 ;0,1=45,2=270.000000
L 4.1895 0.65349961 4.2205 0.65349961 1 P 0 ;0,1=46,2=270.000000
L 4.1895 0.64468337 4.1895 0.66231654 1 P 0 ;0,1=46,2=270.000000
L 4.2205 0.67683317 4.1895 0.67683317 1 P 0 ;0,1=46,2=270.000000
L 4.1895 0.67683317 4.1895 0.68603327 1 P 0 ;0,1=46,2=270.000000
L 4.1895 0.68603327 4.19105069 0.6891 1 P 0 ;0,1=46,2=270.000000
L 4.19105069 0.6891 4.19466654 0.6914002 1 P 0 ;0,1=46,2=270.000000
L 4.19466654 0.6914002 4.1988 0.69216673 1 P 0 ;0,1=46,2=270.000000
L 4.1988 0.69216673 4.20293337 0.6914002 1 P 0 ;0,1=46,2=270.000000
L 4.20293337 0.6914002 4.20603366 0.68948327 1 P 0 ;0,1=46,2=270.000000
L 4.20603366 0.68948327 4.20758425 0.68603327 1 P 0 ;0,1=46,2=270.000000
L 4.20758425 0.68603327 4.20758425 0.67683317 1 P 0 ;0,1=46,2=270.000000
L 4.2205 0.7201 4.1895 0.7201 1 P 0 ;0,1=46,2=270.000000
L 4.1895 0.7201 4.21171673 0.70591624 1 P 0 ;0,1=46,2=270.000000
L 4.21171673 0.70591624 4.21171673 0.72508366 1 P 0 ;0,1=46,2=270.000000
L 4.21688415 0.73998287 4.21946693 0.74266634 1 P 0 ;0,1=46,2=270.000000
L 4.21946693 0.74266634 4.2205 0.74573307 1 P 0 ;0,1=46,2=270.000000
L 4.2205 0.74573307 4.21946693 0.7487998 1 P 0 ;0,1=46,2=270.000000
L 4.21946693 0.7487998 4.21636762 0.75148327 1 P 0 ;0,1=46,2=270.000000
L 4.21636762 0.75148327 4.21171673 0.7534002 1 P 0 ;0,1=46,2=270.000000
L 4.21171673 0.7534002 4.20706673 0.75416673 1 P 0 ;0,1=46,2=270.000000
L 4.20706673 0.75416673 4.20138366 0.75416673 1 P 0 ;0,1=46,2=270.000000
L 4.20138366 0.75416673 4.19673376 0.7534002 1 P 0 ;0,1=46,2=270.000000
L 4.19673376 0.7534002 4.1926003 0.75148327 1 P 0 ;0,1=46,2=270.000000
L 4.1926003 0.75148327 4.19053317 0.74918307 1 P 0 ;0,1=46,2=270.000000
L 4.19053317 0.74918307 4.1895 0.74649961 1 P 0 ;0,1=46,2=270.000000
L 4.1895 0.74649961 4.19053317 0.74343287 1 P 0 ;0,1=46,2=270.000000
L 4.19053317 0.74343287 4.1926003 0.74113337 1 P 0 ;0,1=46,2=270.000000
L 4.1926003 0.74113337 4.1956997 0.7395997 1 P 0 ;0,1=46,2=270.000000
L 4.1956997 0.7395997 4.19983406 0.73883317 1 P 0 ;0,1=46,2=270.000000
L 4.19983406 0.73883317 4.2034499 0.7395997 1 P 0 ;0,1=46,2=270.000000
L 4.2034499 0.7395997 4.20706673 0.74151663 1 P 0 ;0,1=46,2=270.000000
L 4.20706673 0.74151663 4.20913396 0.74381683 1 P 0 ;0,1=46,2=270.000000
L 4.20913396 0.74381683 4.20965049 0.74649961 1 P 0 ;0,1=46,2=270.000000
L 4.20965049 0.74649961 4.20861732 0.74956634 1 P 0 ;0,1=46,2=270.000000
L 4.20861732 0.74956634 4.20603366 0.75186654 1 P 0 ;0,1=46,2=270.000000
L 4.20603366 0.75186654 4.20138366 0.75416673 1 P 0 ;0,1=46,2=270.000000
L 5.37849961 1.0405 5.37849961 1.0095 1 P 0 ;0,1=47,2=0.000000
L 5.36968337 1.0405 5.38731654 1.0405 1 P 0 ;0,1=47,2=0.000000
L 5.40183317 1.0095 5.40183317 1.0405 1 P 0 ;0,1=47,2=0.000000
L 5.40183317 1.0405 5.41103327 1.0405 1 P 0 ;0,1=47,2=0.000000
L 5.41103327 1.0405 5.4141 1.03894931 1 P 0 ;0,1=47,2=0.000000
L 5.4141 1.03894931 5.4164002 1.03533346 1 P 0 ;0,1=47,2=0.000000
L 5.4164002 1.03533346 5.41716673 1.0312 1 P 0 ;0,1=47,2=0.000000
L 5.41716673 1.0312 5.4164002 1.02706663 1 P 0 ;0,1=47,2=0.000000
L 5.4164002 1.02706663 5.41448327 1.02396634 1 P 0 ;0,1=47,2=0.000000
L 5.41448327 1.02396634 5.41103327 1.02241575 1 P 0 ;0,1=47,2=0.000000
L 5.41103327 1.02241575 5.40183317 1.02241575 1 P 0 ;0,1=47,2=0.000000
L 5.4451 1.0095 5.4451 1.0405 1 P 0 ;0,1=47,2=0.000000
L 5.4451 1.0405 5.43091624 1.01828327 1 P 0 ;0,1=47,2=0.000000
L 5.43091624 1.01828327 5.45008366 1.01828327 1 P 0 ;0,1=47,2=0.000000
L 5.46421644 1.02241575 5.4668999 1.02603356 1 P 0 ;0,1=47,2=0.000000
L 5.4668999 1.02603356 5.4692001 1.0280998 1 P 0 ;0,1=47,2=0.000000
L 5.4692001 1.0280998 5.47226683 1.02913287 1 P 0 ;0,1=47,2=0.000000
L 5.47226683 1.02913287 5.4749503 1.0280998 1 P 0 ;0,1=47,2=0.000000
L 5.4749503 1.0280998 5.47686654 1.02603356 1 P 0 ;0,1=47,2=0.000000
L 5.47686654 1.02603356 5.4784002 1.02293327 1 P 0 ;0,1=47,2=0.000000
L 5.4784002 1.02293327 5.47878346 1.01931644 1 P 0 ;0,1=47,2=0.000000
L 5.47878346 1.01931644 5.4784002 1.01621614 1 P 0 ;0,1=47,2=0.000000
L 5.4784002 1.01621614 5.47686654 1.01311585 1 P 0 ;0,1=47,2=0.000000
L 5.47686654 1.01311585 5.47456634 1.01053307 1 P 0 ;0,1=47,2=0.000000
L 5.47456634 1.01053307 5.47188356 1.0095 1 P 0 ;0,1=47,2=0.000000
L 5.47188356 1.0095 5.46881683 1.01053307 1 P 0 ;0,1=47,2=0.000000
L 5.46881683 1.01053307 5.46613337 1.01363238 1 P 0 ;0,1=47,2=0.000000
L 5.46613337 1.01363238 5.4645997 1.01828327 1 P 0 ;0,1=47,2=0.000000
L 5.4645997 1.01828327 5.46421644 1.0234498 1 P 0 ;0,1=47,2=0.000000
L 5.46421644 1.0234498 5.46498287 1.03016594 1 P 0 ;0,1=47,2=0.000000
L 5.46498287 1.03016594 5.46613337 1.03378376 1 P 0 ;0,1=47,2=0.000000
L 5.46613337 1.03378376 5.46804961 1.0373997 1 P 0 ;0,1=47,2=0.000000
L 5.46804961 1.0373997 5.47073307 1.03998337 1 P 0 ;0,1=47,2=0.000000
L 5.47073307 1.03998337 5.47341654 1.0405 1 P 0 ;0,1=47,2=0.000000
L 5.47341654 1.0405 5.4761 1.03946683 1 P 0 ;0,1=47,2=0.000000
L 5.4761 1.03946683 5.47801703 1.03688307 1 P 0 ;0,1=47,2=0.000000
L 4.7995 2.16849961 4.8305 2.16849961 1 P 0 ;0,1=48,2=270.000000
L 4.7995 2.15968337 4.7995 2.17731654 1 P 0 ;0,1=48,2=270.000000
L 4.8305 2.19183317 4.7995 2.19183317 1 P 0 ;0,1=48,2=270.000000
L 4.7995 2.19183317 4.7995 2.20103327 1 P 0 ;0,1=48,2=270.000000
L 4.7995 2.20103327 4.80105069 2.2041 1 P 0 ;0,1=48,2=270.000000
L 4.80105069 2.2041 4.80466654 2.2064002 1 P 0 ;0,1=48,2=270.000000
L 4.80466654 2.2064002 4.8088 2.20716673 1 P 0 ;0,1=48,2=270.000000
L 4.8088 2.20716673 4.81293337 2.2064002 1 P 0 ;0,1=48,2=270.000000
L 4.81293337 2.2064002 4.81603366 2.20448327 1 P 0 ;0,1=48,2=270.000000
L 4.81603366 2.20448327 4.81758425 2.20103327 1 P 0 ;0,1=48,2=270.000000
L 4.81758425 2.20103327 4.81758425 2.19183317 1 P 0 ;0,1=48,2=270.000000
L 4.8305 2.2351 4.7995 2.2351 1 P 0 ;0,1=48,2=270.000000
L 4.7995 2.2351 4.82171673 2.22091624 1 P 0 ;0,1=48,2=270.000000
L 4.82171673 2.22091624 4.82171673 2.24008366 1 P 0 ;0,1=48,2=270.000000
L 4.82585108 2.25306663 4.82843386 2.25536614 1 P 0 ;0,1=48,2=270.000000
L 4.82843386 2.25536614 4.82998346 2.25804961 1 P 0 ;0,1=48,2=270.000000
L 4.82998346 2.25804961 4.8305 2.26149961 1 P 0 ;0,1=48,2=270.000000
L 4.8305 2.26149961 4.82946693 2.2649503 1 P 0 ;0,1=48,2=270.000000
L 4.82946693 2.2649503 4.82740069 2.26763307 1 P 0 ;0,1=48,2=270.000000
L 4.82740069 2.26763307 4.82378386 2.26955 1 P 0 ;0,1=48,2=270.000000
L 4.82378386 2.26955 4.81965049 2.26993327 1 P 0 ;0,1=48,2=270.000000
L 4.81965049 2.26993327 4.81551713 2.26916673 1 P 0 ;0,1=48,2=270.000000
L 4.81551713 2.26916673 4.81293337 2.2672498 1 P 0 ;0,1=48,2=270.000000
L 4.81293337 2.2672498 4.81086713 2.26456634 1 P 0 ;0,1=48,2=270.000000
L 4.81086713 2.26456634 4.81035059 2.26188356 1 P 0 ;0,1=48,2=270.000000
L 4.81035059 2.26188356 4.81086713 2.2592001 1 P 0 ;0,1=48,2=270.000000
L 4.81086713 2.2592001 4.81293337 2.2557501 1 P 0 ;0,1=48,2=270.000000
L 4.81293337 2.2557501 4.7995 2.2568999 1 P 0 ;0,1=48,2=270.000000
L 4.7995 2.2568999 4.7995 2.2672498 1 P 0 ;0,1=48,2=270.000000
L 5.15849961 4.0705 5.15849961 4.0395 1 P 0 ;0,1=49,2=0.000000
L 5.14968337 4.0705 5.16731654 4.0705 1 P 0 ;0,1=49,2=0.000000
L 5.18183317 4.0395 5.18183317 4.0705 1 P 0 ;0,1=49,2=0.000000
L 5.18183317 4.0705 5.19103327 4.0705 1 P 0 ;0,1=49,2=0.000000
L 5.19103327 4.0705 5.1941 4.06894931 1 P 0 ;0,1=49,2=0.000000
L 5.1941 4.06894931 5.1964002 4.06533346 1 P 0 ;0,1=49,2=0.000000
L 5.1964002 4.06533346 5.19716673 4.0612 1 P 0 ;0,1=49,2=0.000000
L 5.19716673 4.0612 5.1964002 4.05706663 1 P 0 ;0,1=49,2=0.000000
L 5.1964002 4.05706663 5.19448327 4.05396634 1 P 0 ;0,1=49,2=0.000000
L 5.19448327 4.05396634 5.19103327 4.05241575 1 P 0 ;0,1=49,2=0.000000
L 5.19103327 4.05241575 5.18183317 4.05241575 1 P 0 ;0,1=49,2=0.000000
L 5.2251 4.0395 5.2251 4.0705 1 P 0 ;0,1=49,2=0.000000
L 5.2251 4.0705 5.21091624 4.04828327 1 P 0 ;0,1=49,2=0.000000
L 5.21091624 4.04828327 5.23008366 4.04828327 1 P 0 ;0,1=49,2=0.000000
L 5.2561 4.0395 5.2561 4.0705 1 P 0 ;0,1=49,2=0.000000
L 5.2561 4.0705 5.24191624 4.04828327 1 P 0 ;0,1=49,2=0.000000
L 5.24191624 4.04828327 5.26108366 4.04828327 1 P 0 ;0,1=49,2=0.000000
L 5.51849961 3.4905 5.51849961 3.4595 1 P 0 ;0,1=50,2=0.000000
L 5.50968337 3.4905 5.52731654 3.4905 1 P 0 ;0,1=50,2=0.000000
L 5.54183317 3.4595 5.54183317 3.4905 1 P 0 ;0,1=50,2=0.000000
L 5.54183317 3.4905 5.55103327 3.4905 1 P 0 ;0,1=50,2=0.000000
L 5.55103327 3.4905 5.5541 3.48894931 1 P 0 ;0,1=50,2=0.000000
L 5.5541 3.48894931 5.5564002 3.48533346 1 P 0 ;0,1=50,2=0.000000
L 5.5564002 3.48533346 5.55716673 3.4812 1 P 0 ;0,1=50,2=0.000000
L 5.55716673 3.4812 5.5564002 3.47706663 1 P 0 ;0,1=50,2=0.000000
L 5.5564002 3.47706663 5.55448327 3.47396634 1 P 0 ;0,1=50,2=0.000000
L 5.55448327 3.47396634 5.55103327 3.47241575 1 P 0 ;0,1=50,2=0.000000
L 5.55103327 3.47241575 5.54183317 3.47241575 1 P 0 ;0,1=50,2=0.000000
L 5.5851 3.4595 5.5851 3.4905 1 P 0 ;0,1=50,2=0.000000
L 5.5851 3.4905 5.57091624 3.46828327 1 P 0 ;0,1=50,2=0.000000
L 5.57091624 3.46828327 5.59008366 3.46828327 1 P 0 ;0,1=50,2=0.000000
L 5.60306663 3.46569961 5.60536614 3.46208278 1 P 0 ;0,1=50,2=0.000000
L 5.60536614 3.46208278 5.60843287 3.46001654 1 P 0 ;0,1=50,2=0.000000
L 5.60843287 3.46001654 5.61188356 3.4595 1 P 0 ;0,1=50,2=0.000000
L 5.61188356 3.4595 5.6149503 3.46001654 1 P 0 ;0,1=50,2=0.000000
L 5.6149503 3.46001654 5.61801703 3.46259931 1 P 0 ;0,1=50,2=0.000000
L 5.61801703 3.46259931 5.61993327 3.46569961 1 P 0 ;0,1=50,2=0.000000
L 5.61993327 3.46569961 5.62031654 3.4687999 1 P 0 ;0,1=50,2=0.000000
L 5.62031654 3.4687999 5.61955 3.47241575 1 P 0 ;0,1=50,2=0.000000
L 5.61955 3.47241575 5.61686654 3.47499951 1 P 0 ;0,1=50,2=0.000000
L 5.61686654 3.47499951 5.61418307 3.47603356 1 P 0 ;0,1=50,2=0.000000
L 5.61418307 3.47603356 5.61073307 3.47603356 1 P 0 ;0,1=50,2=0.000000
L 5.61418307 3.47603356 5.61648327 3.47758317 1 P 0 ;0,1=50,2=0.000000
L 5.61648327 3.47758317 5.6184002 3.48016594 1 P 0 ;0,1=50,2=0.000000
L 5.6184002 3.48016594 5.61916673 3.48326624 1 P 0 ;0,1=50,2=0.000000
L 5.61916673 3.48326624 5.6184002 3.48636654 1 P 0 ;0,1=50,2=0.000000
L 5.6184002 3.48636654 5.61648327 3.48894931 1 P 0 ;0,1=50,2=0.000000
L 5.61648327 3.48894931 5.61303327 3.4905 1 P 0 ;0,1=50,2=0.000000
L 5.61303327 3.4905 5.60958337 3.48998337 1 P 0 ;0,1=50,2=0.000000
L 5.60958337 3.48998337 5.60613337 3.48791624 1 P 0 ;0,1=50,2=0.000000
L 0.9895 3.97849961 1.0205 3.97849961 1 P 0 ;0,1=51,2=270.000000
L 0.9895 3.96968337 0.9895 3.98731654 1 P 0 ;0,1=51,2=270.000000
L 1.0205 4.00183317 0.9895 4.00183317 1 P 0 ;0,1=51,2=270.000000
L 0.9895 4.00183317 0.9895 4.01103327 1 P 0 ;0,1=51,2=270.000000
L 0.9895 4.01103327 0.99105069 4.0141 1 P 0 ;0,1=51,2=270.000000
L 0.99105069 4.0141 0.99466654 4.0164002 1 P 0 ;0,1=51,2=270.000000
L 0.99466654 4.0164002 0.9988 4.01716673 1 P 0 ;0,1=51,2=270.000000
L 0.9988 4.01716673 1.00293337 4.0164002 1 P 0 ;0,1=51,2=270.000000
L 1.00293337 4.0164002 1.00603366 4.01448327 1 P 0 ;0,1=51,2=270.000000
L 1.00603366 4.01448327 1.00758425 4.01103327 1 P 0 ;0,1=51,2=270.000000
L 1.00758425 4.01103327 1.00758425 4.00183317 1 P 0 ;0,1=51,2=270.000000
L 1.0205 4.0451 0.9895 4.0451 1 P 0 ;0,1=51,2=270.000000
L 0.9895 4.0451 1.01171673 4.03091624 1 P 0 ;0,1=51,2=270.000000
L 1.01171673 4.03091624 1.01171673 4.05008366 1 P 0 ;0,1=51,2=270.000000
L 0.99466654 4.06421644 0.99156722 4.06651663 1 P 0 ;0,1=51,2=270.000000
L 0.99156722 4.06651663 0.99001663 4.0692001 1 P 0 ;0,1=51,2=270.000000
L 0.99001663 4.0692001 0.9895 4.07226683 1 P 0 ;0,1=51,2=270.000000
L 0.9895 4.07226683 0.99053317 4.0761 1 P 0 ;0,1=51,2=270.000000
L 0.99053317 4.0761 0.99311693 4.07878346 1 P 0 ;0,1=51,2=270.000000
L 0.99311693 4.07878346 0.99621624 4.07955 1 P 0 ;0,1=51,2=270.000000
L 0.99621624 4.07955 0.99931742 4.07916673 1 P 0 ;0,1=51,2=270.000000
L 0.99931742 4.07916673 1.0019002 4.07763307 1 P 0 ;0,1=51,2=270.000000
L 1.0019002 4.07763307 1.00706673 4.06996663 1 P 0 ;0,1=51,2=270.000000
L 1.00706673 4.06996663 1.01068356 4.06651663 1 P 0 ;0,1=51,2=270.000000
L 1.01068356 4.06651663 1.01585108 4.06421644 1 P 0 ;0,1=51,2=270.000000
L 1.01585108 4.06421644 1.0205 4.0634499 1 P 0 ;0,1=51,2=270.000000
L 1.0205 4.0634499 1.0205 4.07955 1 P 0 ;0,1=51,2=270.000000
L 5.74849961 0.9605 5.74849961 0.9295 1 P 0 ;0,1=52,2=0.000000
L 5.73968337 0.9605 5.75731654 0.9605 1 P 0 ;0,1=52,2=0.000000
L 5.77183317 0.9295 5.77183317 0.9605 1 P 0 ;0,1=52,2=0.000000
L 5.77183317 0.9605 5.78103327 0.9605 1 P 0 ;0,1=52,2=0.000000
L 5.78103327 0.9605 5.7841 0.95894931 1 P 0 ;0,1=52,2=0.000000
L 5.7841 0.95894931 5.7864002 0.95533346 1 P 0 ;0,1=52,2=0.000000
L 5.7864002 0.95533346 5.78716673 0.9512 1 P 0 ;0,1=52,2=0.000000
L 5.78716673 0.9512 5.7864002 0.94706663 1 P 0 ;0,1=52,2=0.000000
L 5.7864002 0.94706663 5.78448327 0.94396634 1 P 0 ;0,1=52,2=0.000000
L 5.78448327 0.94396634 5.78103327 0.94241575 1 P 0 ;0,1=52,2=0.000000
L 5.78103327 0.94241575 5.77183317 0.94241575 1 P 0 ;0,1=52,2=0.000000
L 5.8151 0.9295 5.8151 0.9605 1 P 0 ;0,1=52,2=0.000000
L 5.8151 0.9605 5.80091624 0.93828327 1 P 0 ;0,1=52,2=0.000000
L 5.80091624 0.93828327 5.82008366 0.93828327 1 P 0 ;0,1=52,2=0.000000
L 5.84149961 0.9295 5.84149961 0.9605 1 P 0 ;0,1=52,2=0.000000
L 5.84149961 0.9605 5.8368999 0.9543003 1 P 0 ;0,1=52,2=0.000000
L 5.8368999 0.9295 5.84609931 0.9295 1 P 0 ;0,1=52,2=0.000000
L 4.76349961 2.8055 4.76349961 2.7745 1 P 0 ;0,1=53,2=0.000000
L 4.75468337 2.8055 4.77231654 2.8055 1 P 0 ;0,1=53,2=0.000000
L 4.78683317 2.7745 4.78683317 2.8055 1 P 0 ;0,1=53,2=0.000000
L 4.78683317 2.8055 4.79603327 2.8055 1 P 0 ;0,1=53,2=0.000000
L 4.79603327 2.8055 4.7991 2.80394931 1 P 0 ;0,1=53,2=0.000000
L 4.7991 2.80394931 4.8014002 2.80033346 1 P 0 ;0,1=53,2=0.000000
L 4.8014002 2.80033346 4.80216673 2.7962 1 P 0 ;0,1=53,2=0.000000
L 4.80216673 2.7962 4.8014002 2.79206663 1 P 0 ;0,1=53,2=0.000000
L 4.8014002 2.79206663 4.79948327 2.78896634 1 P 0 ;0,1=53,2=0.000000
L 4.79948327 2.78896634 4.79603327 2.78741575 1 P 0 ;0,1=53,2=0.000000
L 4.79603327 2.78741575 4.78683317 2.78741575 1 P 0 ;0,1=53,2=0.000000
L 4.8301 2.7745 4.8301 2.8055 1 P 0 ;0,1=53,2=0.000000
L 4.8301 2.8055 4.81591624 2.78328327 1 P 0 ;0,1=53,2=0.000000
L 4.81591624 2.78328327 4.83508366 2.78328327 1 P 0 ;0,1=53,2=0.000000
L 4.85649961 2.8055 4.85343287 2.80446683 1 P 0 ;0,1=53,2=0.000000
L 4.85343287 2.80446683 4.85113337 2.80188307 1 P 0 ;0,1=53,2=0.000000
L 4.85113337 2.80188307 4.8495997 2.79878376 1 P 0 ;0,1=53,2=0.000000
L 4.8495997 2.79878376 4.8484499 2.79464941 1 P 0 ;0,1=53,2=0.000000
L 4.8484499 2.79464941 4.84806663 2.78999951 1 P 0 ;0,1=53,2=0.000000
L 4.84806663 2.78999951 4.8484499 2.78534951 1 P 0 ;0,1=53,2=0.000000
L 4.8484499 2.78534951 4.8495997 2.78121614 1 P 0 ;0,1=53,2=0.000000
L 4.8495997 2.78121614 4.85113337 2.77811585 1 P 0 ;0,1=53,2=0.000000
L 4.85113337 2.77811585 4.85343287 2.77553307 1 P 0 ;0,1=53,2=0.000000
L 4.85343287 2.77553307 4.85649961 2.7745 1 P 0 ;0,1=53,2=0.000000
L 4.85649961 2.7745 4.85956634 2.77553307 1 P 0 ;0,1=53,2=0.000000
L 4.85956634 2.77553307 4.86186654 2.77811585 1 P 0 ;0,1=53,2=0.000000
L 4.86186654 2.77811585 4.8634002 2.78121614 1 P 0 ;0,1=53,2=0.000000
L 4.8634002 2.78121614 4.86455 2.78534951 1 P 0 ;0,1=53,2=0.000000
L 4.86455 2.78534951 4.86493327 2.78999951 1 P 0 ;0,1=53,2=0.000000
L 4.86493327 2.78999951 4.86455 2.79464941 1 P 0 ;0,1=53,2=0.000000
L 4.86455 2.79464941 4.8634002 2.79878376 1 P 0 ;0,1=53,2=0.000000
L 4.8634002 2.79878376 4.86186654 2.80188307 1 P 0 ;0,1=53,2=0.000000
L 4.86186654 2.80188307 4.85956634 2.80446683 1 P 0 ;0,1=53,2=0.000000
L 4.85956634 2.80446683 4.85649961 2.8055 1 P 0 ;0,1=53,2=0.000000
L 5.70349961 2.5355 5.70349961 2.5045 1 P 0 ;0,1=54,2=0.000000
L 5.69468337 2.5355 5.71231654 2.5355 1 P 0 ;0,1=54,2=0.000000
L 5.72683317 2.5045 5.72683317 2.5355 1 P 0 ;0,1=54,2=0.000000
L 5.72683317 2.5355 5.73603327 2.5355 1 P 0 ;0,1=54,2=0.000000
L 5.73603327 2.5355 5.7391 2.53394931 1 P 0 ;0,1=54,2=0.000000
L 5.7391 2.53394931 5.7414002 2.53033346 1 P 0 ;0,1=54,2=0.000000
L 5.7414002 2.53033346 5.74216673 2.5262 1 P 0 ;0,1=54,2=0.000000
L 5.74216673 2.5262 5.7414002 2.52206663 1 P 0 ;0,1=54,2=0.000000
L 5.7414002 2.52206663 5.73948327 2.51896634 1 P 0 ;0,1=54,2=0.000000
L 5.73948327 2.51896634 5.73603327 2.51741575 1 P 0 ;0,1=54,2=0.000000
L 5.73603327 2.51741575 5.72683317 2.51741575 1 P 0 ;0,1=54,2=0.000000
L 5.75706663 2.51069961 5.75936614 2.50708278 1 P 0 ;0,1=54,2=0.000000
L 5.75936614 2.50708278 5.76243287 2.50501654 1 P 0 ;0,1=54,2=0.000000
L 5.76243287 2.50501654 5.76588356 2.5045 1 P 0 ;0,1=54,2=0.000000
L 5.76588356 2.5045 5.7689503 2.50501654 1 P 0 ;0,1=54,2=0.000000
L 5.7689503 2.50501654 5.77201703 2.50759931 1 P 0 ;0,1=54,2=0.000000
L 5.77201703 2.50759931 5.77393327 2.51069961 1 P 0 ;0,1=54,2=0.000000
L 5.77393327 2.51069961 5.77431654 2.5137999 1 P 0 ;0,1=54,2=0.000000
L 5.77431654 2.5137999 5.77355 2.51741575 1 P 0 ;0,1=54,2=0.000000
L 5.77355 2.51741575 5.77086654 2.51999951 1 P 0 ;0,1=54,2=0.000000
L 5.77086654 2.51999951 5.76818307 2.52103356 1 P 0 ;0,1=54,2=0.000000
L 5.76818307 2.52103356 5.76473307 2.52103356 1 P 0 ;0,1=54,2=0.000000
L 5.76818307 2.52103356 5.77048327 2.52258317 1 P 0 ;0,1=54,2=0.000000
L 5.77048327 2.52258317 5.7724002 2.52516594 1 P 0 ;0,1=54,2=0.000000
L 5.7724002 2.52516594 5.77316673 2.52826624 1 P 0 ;0,1=54,2=0.000000
L 5.77316673 2.52826624 5.7724002 2.53136654 1 P 0 ;0,1=54,2=0.000000
L 5.7724002 2.53136654 5.77048327 2.53394931 1 P 0 ;0,1=54,2=0.000000
L 5.77048327 2.53394931 5.76703327 2.5355 1 P 0 ;0,1=54,2=0.000000
L 5.76703327 2.5355 5.76358337 2.53498337 1 P 0 ;0,1=54,2=0.000000
L 5.76358337 2.53498337 5.76013337 2.53291624 1 P 0 ;0,1=54,2=0.000000
L 5.78998287 2.50811585 5.79266634 2.50553307 1 P 0 ;0,1=54,2=0.000000
L 5.79266634 2.50553307 5.79573307 2.5045 1 P 0 ;0,1=54,2=0.000000
L 5.79573307 2.5045 5.7987998 2.50553307 1 P 0 ;0,1=54,2=0.000000
L 5.7987998 2.50553307 5.80148327 2.50863238 1 P 0 ;0,1=54,2=0.000000
L 5.80148327 2.50863238 5.8034002 2.51328327 1 P 0 ;0,1=54,2=0.000000
L 5.8034002 2.51328327 5.80416673 2.51793327 1 P 0 ;0,1=54,2=0.000000
L 5.80416673 2.51793327 5.80416673 2.52361634 1 P 0 ;0,1=54,2=0.000000
L 5.80416673 2.52361634 5.8034002 2.52826624 1 P 0 ;0,1=54,2=0.000000
L 5.8034002 2.52826624 5.80148327 2.5323997 1 P 0 ;0,1=54,2=0.000000
L 5.80148327 2.5323997 5.79918307 2.53446683 1 P 0 ;0,1=54,2=0.000000
L 5.79918307 2.53446683 5.79649961 2.5355 1 P 0 ;0,1=54,2=0.000000
L 5.79649961 2.5355 5.79343287 2.53446683 1 P 0 ;0,1=54,2=0.000000
L 5.79343287 2.53446683 5.79113337 2.5323997 1 P 0 ;0,1=54,2=0.000000
L 5.79113337 2.5323997 5.7895997 2.5293003 1 P 0 ;0,1=54,2=0.000000
L 5.7895997 2.5293003 5.78883317 2.52516594 1 P 0 ;0,1=54,2=0.000000
L 5.78883317 2.52516594 5.7895997 2.5215501 1 P 0 ;0,1=54,2=0.000000
L 5.7895997 2.5215501 5.79151663 2.51793327 1 P 0 ;0,1=54,2=0.000000
L 5.79151663 2.51793327 5.79381683 2.51586604 1 P 0 ;0,1=54,2=0.000000
L 5.79381683 2.51586604 5.79649961 2.51534951 1 P 0 ;0,1=54,2=0.000000
L 5.79649961 2.51534951 5.79956634 2.51638268 1 P 0 ;0,1=54,2=0.000000
L 5.79956634 2.51638268 5.80186654 2.51896634 1 P 0 ;0,1=54,2=0.000000
L 5.80186654 2.51896634 5.80416673 2.52361634 1 P 0 ;0,1=54,2=0.000000
L 3.78949961 4.2055 3.78949961 4.1745 1 P 0 ;0,1=55,2=0.000000
L 3.78068337 4.2055 3.79831654 4.2055 1 P 0 ;0,1=55,2=0.000000
L 3.81283317 4.1745 3.81283317 4.2055 1 P 0 ;0,1=55,2=0.000000
L 3.81283317 4.2055 3.82203327 4.2055 1 P 0 ;0,1=55,2=0.000000
L 3.82203327 4.2055 3.8251 4.20394931 1 P 0 ;0,1=55,2=0.000000
L 3.8251 4.20394931 3.8274002 4.20033346 1 P 0 ;0,1=55,2=0.000000
L 3.8274002 4.20033346 3.82816673 4.1962 1 P 0 ;0,1=55,2=0.000000
L 3.82816673 4.1962 3.8274002 4.19206663 1 P 0 ;0,1=55,2=0.000000
L 3.8274002 4.19206663 3.82548327 4.18896634 1 P 0 ;0,1=55,2=0.000000
L 3.82548327 4.18896634 3.82203327 4.18741575 1 P 0 ;0,1=55,2=0.000000
L 3.82203327 4.18741575 3.81283317 4.18741575 1 P 0 ;0,1=55,2=0.000000
L 3.84306663 4.18069961 3.84536614 4.17708278 1 P 0 ;0,1=55,2=0.000000
L 3.84536614 4.17708278 3.84843287 4.17501654 1 P 0 ;0,1=55,2=0.000000
L 3.84843287 4.17501654 3.85188356 4.1745 1 P 0 ;0,1=55,2=0.000000
L 3.85188356 4.1745 3.8549503 4.17501654 1 P 0 ;0,1=55,2=0.000000
L 3.8549503 4.17501654 3.85801703 4.17759931 1 P 0 ;0,1=55,2=0.000000
L 3.85801703 4.17759931 3.85993327 4.18069961 1 P 0 ;0,1=55,2=0.000000
L 3.85993327 4.18069961 3.86031654 4.1837999 1 P 0 ;0,1=55,2=0.000000
L 3.86031654 4.1837999 3.85955 4.18741575 1 P 0 ;0,1=55,2=0.000000
L 3.85955 4.18741575 3.85686654 4.18999951 1 P 0 ;0,1=55,2=0.000000
L 3.85686654 4.18999951 3.85418307 4.19103356 1 P 0 ;0,1=55,2=0.000000
L 3.85418307 4.19103356 3.85073307 4.19103356 1 P 0 ;0,1=55,2=0.000000
L 3.85418307 4.19103356 3.85648327 4.19258317 1 P 0 ;0,1=55,2=0.000000
L 3.85648327 4.19258317 3.8584002 4.19516594 1 P 0 ;0,1=55,2=0.000000
L 3.8584002 4.19516594 3.85916673 4.19826624 1 P 0 ;0,1=55,2=0.000000
L 3.85916673 4.19826624 3.8584002 4.20136654 1 P 0 ;0,1=55,2=0.000000
L 3.8584002 4.20136654 3.85648327 4.20394931 1 P 0 ;0,1=55,2=0.000000
L 3.85648327 4.20394931 3.85303327 4.2055 1 P 0 ;0,1=55,2=0.000000
L 3.85303327 4.2055 3.84958337 4.20498337 1 P 0 ;0,1=55,2=0.000000
L 3.84958337 4.20498337 3.84613337 4.20291624 1 P 0 ;0,1=55,2=0.000000
L 3.88249961 4.1745 3.88518307 4.17501654 1 P 0 ;0,1=55,2=0.000000
L 3.88518307 4.17501654 3.8882498 4.17656614 1 P 0 ;0,1=55,2=0.000000
L 3.8882498 4.17656614 3.89016673 4.17914892 1 P 0 ;0,1=55,2=0.000000
L 3.89016673 4.17914892 3.89093327 4.18276673 1 P 0 ;0,1=55,2=0.000000
L 3.89093327 4.18276673 3.89016673 4.18638268 1 P 0 ;0,1=55,2=0.000000
L 3.89016673 4.18638268 3.88786654 4.18948287 1 P 0 ;0,1=55,2=0.000000
L 3.88786654 4.18948287 3.88441654 4.19103356 1 P 0 ;0,1=55,2=0.000000
L 3.88441654 4.19103356 3.88058337 4.19103356 1 P 0 ;0,1=55,2=0.000000
L 3.88058337 4.19103356 3.87828317 4.19206663 1 P 0 ;0,1=55,2=0.000000
L 3.87828317 4.19206663 3.87636614 4.19464941 1 P 0 ;0,1=55,2=0.000000
L 3.87636614 4.19464941 3.8755997 4.19826624 1 P 0 ;0,1=55,2=0.000000
L 3.8755997 4.19826624 3.8767501 4.20188307 1 P 0 ;0,1=55,2=0.000000
L 3.8767501 4.20188307 3.87943287 4.20446683 1 P 0 ;0,1=55,2=0.000000
L 3.87943287 4.20446683 3.88249961 4.2055 1 P 0 ;0,1=55,2=0.000000
L 3.88249961 4.2055 3.88556634 4.20446683 1 P 0 ;0,1=55,2=0.000000
L 3.88556634 4.20446683 3.8882498 4.20188307 1 P 0 ;0,1=55,2=0.000000
L 3.8882498 4.20188307 3.8894002 4.19826624 1 P 0 ;0,1=55,2=0.000000
L 3.8894002 4.19826624 3.88863307 4.19464941 1 P 0 ;0,1=55,2=0.000000
L 3.88863307 4.19464941 3.88671673 4.19206663 1 P 0 ;0,1=55,2=0.000000
L 3.88671673 4.19206663 3.88441654 4.19103356 1 P 0 ;0,1=55,2=0.000000
L 3.88441654 4.19103356 3.88058337 4.19103356 1 P 0 ;0,1=55,2=0.000000
L 3.88058337 4.19103356 3.87713337 4.18948287 1 P 0 ;0,1=55,2=0.000000
L 3.87713337 4.18948287 3.87483317 4.18638268 1 P 0 ;0,1=55,2=0.000000
L 3.87483317 4.18638268 3.87406663 4.18276673 1 P 0 ;0,1=55,2=0.000000
L 3.87406663 4.18276673 3.87483317 4.17914892 1 P 0 ;0,1=55,2=0.000000
L 3.87483317 4.17914892 3.8767501 4.17656614 1 P 0 ;0,1=55,2=0.000000
L 3.8767501 4.17656614 3.87981683 4.17501654 1 P 0 ;0,1=55,2=0.000000
L 3.87981683 4.17501654 3.88249961 4.1745 1 P 0 ;0,1=55,2=0.000000
L 5.7819997 3.9725 5.7819997 3.9475 1 P 0 ;0,1=56,2=0.000000
L 5.77586673 3.9725 5.78813317 3.9725 1 P 0 ;0,1=56,2=0.000000
L 5.79866654 3.9475 5.79866654 3.9725 1 P 0 ;0,1=56,2=0.000000
L 5.79866654 3.9725 5.80506663 3.9725 1 P 0 ;0,1=56,2=0.000000
L 5.80506663 3.9725 5.8072 3.97124941 1 P 0 ;0,1=56,2=0.000000
L 5.8072 3.97124941 5.8088001 3.96833337 1 P 0 ;0,1=56,2=0.000000
L 5.8088001 3.96833337 5.80933337 3.965 1 P 0 ;0,1=56,2=0.000000
L 5.80933337 3.965 5.8088001 3.96166663 1 P 0 ;0,1=56,2=0.000000
L 5.8088001 3.96166663 5.80746663 3.95916644 1 P 0 ;0,1=56,2=0.000000
L 5.80746663 3.95916644 5.80506663 3.95791594 1 P 0 ;0,1=56,2=0.000000
L 5.80506663 3.95791594 5.79866654 3.95791594 1 P 0 ;0,1=56,2=0.000000
L 5.82013327 3.95249961 5.82173297 3.94958287 1 P 0 ;0,1=56,2=0.000000
L 5.82173297 3.94958287 5.82386634 3.94791654 1 P 0 ;0,1=56,2=0.000000
L 5.82386634 3.94791654 5.82626683 3.9475 1 P 0 ;0,1=56,2=0.000000
L 5.82626683 3.9475 5.8284002 3.94791654 1 P 0 ;0,1=56,2=0.000000
L 5.8284002 3.94791654 5.83053356 3.94999941 1 P 0 ;0,1=56,2=0.000000
L 5.83053356 3.94999941 5.83186663 3.95249961 1 P 0 ;0,1=56,2=0.000000
L 5.83186663 3.95249961 5.83213317 3.9549999 1 P 0 ;0,1=56,2=0.000000
L 5.83213317 3.9549999 5.8316 3.95791594 1 P 0 ;0,1=56,2=0.000000
L 5.8316 3.95791594 5.82973327 3.95999961 1 P 0 ;0,1=56,2=0.000000
L 5.82973327 3.95999961 5.82786644 3.96083346 1 P 0 ;0,1=56,2=0.000000
L 5.82786644 3.96083346 5.82546654 3.96083346 1 P 0 ;0,1=56,2=0.000000
L 5.82786644 3.96083346 5.82946663 3.96208327 1 P 0 ;0,1=56,2=0.000000
L 5.82946663 3.96208327 5.8308001 3.96416614 1 P 0 ;0,1=56,2=0.000000
L 5.8308001 3.96416614 5.83133337 3.96666634 1 P 0 ;0,1=56,2=0.000000
L 5.83133337 3.96666634 5.8308001 3.96916654 1 P 0 ;0,1=56,2=0.000000
L 5.8308001 3.96916654 5.82946663 3.97124941 1 P 0 ;0,1=56,2=0.000000
L 5.82946663 3.97124941 5.82706663 3.9725 1 P 0 ;0,1=56,2=0.000000
L 5.82706663 3.9725 5.82466663 3.97208337 1 P 0 ;0,1=56,2=0.000000
L 5.82466663 3.97208337 5.82226663 3.97041634 1 P 0 ;0,1=56,2=0.000000
L 5.84746654 3.9475 5.8479997 3.95291624 1 P 0 ;0,1=56,2=0.000000
L 5.8479997 3.95291624 5.8488 3.95749931 1 P 0 ;0,1=56,2=0.000000
L 5.8488 3.95749931 5.84986644 3.96166663 1 P 0 ;0,1=56,2=0.000000
L 5.84986644 3.96166663 5.8512 3.9662498 1 P 0 ;0,1=56,2=0.000000
L 5.8512 3.9662498 5.85333337 3.9725 1 P 0 ;0,1=56,2=0.000000
L 5.85333337 3.9725 5.84266654 3.9725 1 P 0 ;0,1=56,2=0.000000
L 5.6269997 4.0175 5.6269997 3.9925 1 P 0 ;0,1=57,2=0.000000
L 5.62086673 4.0175 5.63313317 4.0175 1 P 0 ;0,1=57,2=0.000000
L 5.64366654 3.9925 5.64366654 4.0175 1 P 0 ;0,1=57,2=0.000000
L 5.64366654 4.0175 5.65006663 4.0175 1 P 0 ;0,1=57,2=0.000000
L 5.65006663 4.0175 5.6522 4.01624941 1 P 0 ;0,1=57,2=0.000000
L 5.6522 4.01624941 5.6538001 4.01333337 1 P 0 ;0,1=57,2=0.000000
L 5.6538001 4.01333337 5.65433337 4.01 1 P 0 ;0,1=57,2=0.000000
L 5.65433337 4.01 5.6538001 4.00666663 1 P 0 ;0,1=57,2=0.000000
L 5.6538001 4.00666663 5.65246663 4.00416644 1 P 0 ;0,1=57,2=0.000000
L 5.65246663 4.00416644 5.65006663 4.00291594 1 P 0 ;0,1=57,2=0.000000
L 5.65006663 4.00291594 5.64366654 4.00291594 1 P 0 ;0,1=57,2=0.000000
L 5.66513327 3.99749961 5.66673297 3.99458287 1 P 0 ;0,1=57,2=0.000000
L 5.66673297 3.99458287 5.66886634 3.99291654 1 P 0 ;0,1=57,2=0.000000
L 5.66886634 3.99291654 5.67126683 3.9925 1 P 0 ;0,1=57,2=0.000000
L 5.67126683 3.9925 5.6734002 3.99291654 1 P 0 ;0,1=57,2=0.000000
L 5.6734002 3.99291654 5.67553356 3.99499941 1 P 0 ;0,1=57,2=0.000000
L 5.67553356 3.99499941 5.67686663 3.99749961 1 P 0 ;0,1=57,2=0.000000
L 5.67686663 3.99749961 5.67713317 3.9999999 1 P 0 ;0,1=57,2=0.000000
L 5.67713317 3.9999999 5.6766 4.00291594 1 P 0 ;0,1=57,2=0.000000
L 5.6766 4.00291594 5.67473327 4.00499961 1 P 0 ;0,1=57,2=0.000000
L 5.67473327 4.00499961 5.67286644 4.00583346 1 P 0 ;0,1=57,2=0.000000
L 5.67286644 4.00583346 5.67046654 4.00583346 1 P 0 ;0,1=57,2=0.000000
L 5.67286644 4.00583346 5.67446663 4.00708327 1 P 0 ;0,1=57,2=0.000000
L 5.67446663 4.00708327 5.6758001 4.00916614 1 P 0 ;0,1=57,2=0.000000
L 5.6758001 4.00916614 5.67633337 4.01166634 1 P 0 ;0,1=57,2=0.000000
L 5.67633337 4.01166634 5.6758001 4.01416654 1 P 0 ;0,1=57,2=0.000000
L 5.6758001 4.01416654 5.67446663 4.01624941 1 P 0 ;0,1=57,2=0.000000
L 5.67446663 4.01624941 5.67206663 4.0175 1 P 0 ;0,1=57,2=0.000000
L 5.67206663 4.0175 5.66966663 4.01708337 1 P 0 ;0,1=57,2=0.000000
L 5.66966663 4.01708337 5.66726663 4.01541634 1 P 0 ;0,1=57,2=0.000000
L 5.68793317 4.00291594 5.6897999 4.00583346 1 P 0 ;0,1=57,2=0.000000
L 5.6897999 4.00583346 5.6914 4.0074998 1 P 0 ;0,1=57,2=0.000000
L 5.6914 4.0074998 5.69353337 4.00833297 1 P 0 ;0,1=57,2=0.000000
L 5.69353337 4.00833297 5.6954002 4.0074998 1 P 0 ;0,1=57,2=0.000000
L 5.6954002 4.0074998 5.69673327 4.00583346 1 P 0 ;0,1=57,2=0.000000
L 5.69673327 4.00583346 5.6978001 4.00333327 1 P 0 ;0,1=57,2=0.000000
L 5.6978001 4.00333327 5.69806673 4.00041644 1 P 0 ;0,1=57,2=0.000000
L 5.69806673 4.00041644 5.6978001 3.99791624 1 P 0 ;0,1=57,2=0.000000
L 5.6978001 3.99791624 5.69673327 3.99541604 1 P 0 ;0,1=57,2=0.000000
L 5.69673327 3.99541604 5.69513307 3.99333307 1 P 0 ;0,1=57,2=0.000000
L 5.69513307 3.99333307 5.69326683 3.9925 1 P 0 ;0,1=57,2=0.000000
L 5.69326683 3.9925 5.69113346 3.99333307 1 P 0 ;0,1=57,2=0.000000
L 5.69113346 3.99333307 5.68926663 3.99583258 1 P 0 ;0,1=57,2=0.000000
L 5.68926663 3.99583258 5.6881998 3.99958327 1 P 0 ;0,1=57,2=0.000000
L 5.6881998 3.99958327 5.68793317 4.0037498 1 P 0 ;0,1=57,2=0.000000
L 5.68793317 4.0037498 5.68846634 4.00916614 1 P 0 ;0,1=57,2=0.000000
L 5.68846634 4.00916614 5.68926663 4.01208366 1 P 0 ;0,1=57,2=0.000000
L 5.68926663 4.01208366 5.6905997 4.0149997 1 P 0 ;0,1=57,2=0.000000
L 5.6905997 4.0149997 5.69246654 4.01708337 1 P 0 ;0,1=57,2=0.000000
L 5.69246654 4.01708337 5.69433327 4.0175 1 P 0 ;0,1=57,2=0.000000
L 5.69433327 4.0175 5.6962 4.01666683 1 P 0 ;0,1=57,2=0.000000
L 5.6962 4.01666683 5.69753356 4.01458317 1 P 0 ;0,1=57,2=0.000000
L 0.6145 0.89349961 0.6455 0.89349961 1 P 0 ;0,1=58,2=270.000000
L 0.6145 0.88468337 0.6145 0.90231654 1 P 0 ;0,1=58,2=270.000000
L 0.6455 0.91683317 0.6145 0.91683317 1 P 0 ;0,1=58,2=270.000000
L 0.6145 0.91683317 0.6145 0.92603327 1 P 0 ;0,1=58,2=270.000000
L 0.6145 0.92603327 0.61605069 0.9291 1 P 0 ;0,1=58,2=270.000000
L 0.61605069 0.9291 0.61966654 0.9314002 1 P 0 ;0,1=58,2=270.000000
L 0.61966654 0.9314002 0.6238 0.93216673 1 P 0 ;0,1=58,2=270.000000
L 0.6238 0.93216673 0.62793337 0.9314002 1 P 0 ;0,1=58,2=270.000000
L 0.62793337 0.9314002 0.63103366 0.92948327 1 P 0 ;0,1=58,2=270.000000
L 0.63103366 0.92948327 0.63258425 0.92603327 1 P 0 ;0,1=58,2=270.000000
L 0.63258425 0.92603327 0.63258425 0.91683317 1 P 0 ;0,1=58,2=270.000000
L 0.63930039 0.94706663 0.64291722 0.94936614 1 P 0 ;0,1=58,2=270.000000
L 0.64291722 0.94936614 0.64498346 0.95243287 1 P 0 ;0,1=58,2=270.000000
L 0.64498346 0.95243287 0.6455 0.95588356 1 P 0 ;0,1=58,2=270.000000
L 0.6455 0.95588356 0.64498346 0.9589503 1 P 0 ;0,1=58,2=270.000000
L 0.64498346 0.9589503 0.64240069 0.96201703 1 P 0 ;0,1=58,2=270.000000
L 0.64240069 0.96201703 0.63930039 0.96393327 1 P 0 ;0,1=58,2=270.000000
L 0.63930039 0.96393327 0.6362001 0.96431654 1 P 0 ;0,1=58,2=270.000000
L 0.6362001 0.96431654 0.63258425 0.96355 1 P 0 ;0,1=58,2=270.000000
L 0.63258425 0.96355 0.63000049 0.96086654 1 P 0 ;0,1=58,2=270.000000
L 0.63000049 0.96086654 0.62896644 0.95818307 1 P 0 ;0,1=58,2=270.000000
L 0.62896644 0.95818307 0.62896644 0.95473307 1 P 0 ;0,1=58,2=270.000000
L 0.62896644 0.95818307 0.62741683 0.96048327 1 P 0 ;0,1=58,2=270.000000
L 0.62741683 0.96048327 0.62483406 0.9624002 1 P 0 ;0,1=58,2=270.000000
L 0.62483406 0.9624002 0.62173376 0.96316673 1 P 0 ;0,1=58,2=270.000000
L 0.62173376 0.96316673 0.61863346 0.9624002 1 P 0 ;0,1=58,2=270.000000
L 0.61863346 0.9624002 0.61605069 0.96048327 1 P 0 ;0,1=58,2=270.000000
L 0.61605069 0.96048327 0.6145 0.95703327 1 P 0 ;0,1=58,2=270.000000
L 0.6145 0.95703327 0.61501663 0.95358337 1 P 0 ;0,1=58,2=270.000000
L 0.61501663 0.95358337 0.61708376 0.95013337 1 P 0 ;0,1=58,2=270.000000
L 0.64085108 0.97806663 0.64343386 0.98036614 1 P 0 ;0,1=58,2=270.000000
L 0.64343386 0.98036614 0.64498346 0.98304961 1 P 0 ;0,1=58,2=270.000000
L 0.64498346 0.98304961 0.6455 0.98649961 1 P 0 ;0,1=58,2=270.000000
L 0.6455 0.98649961 0.64446693 0.9899503 1 P 0 ;0,1=58,2=270.000000
L 0.64446693 0.9899503 0.64240069 0.99263307 1 P 0 ;0,1=58,2=270.000000
L 0.64240069 0.99263307 0.63878386 0.99455 1 P 0 ;0,1=58,2=270.000000
L 0.63878386 0.99455 0.63465049 0.99493327 1 P 0 ;0,1=58,2=270.000000
L 0.63465049 0.99493327 0.63051713 0.99416673 1 P 0 ;0,1=58,2=270.000000
L 0.63051713 0.99416673 0.62793337 0.9922498 1 P 0 ;0,1=58,2=270.000000
L 0.62793337 0.9922498 0.62586713 0.98956634 1 P 0 ;0,1=58,2=270.000000
L 0.62586713 0.98956634 0.62535059 0.98688356 1 P 0 ;0,1=58,2=270.000000
L 0.62535059 0.98688356 0.62586713 0.9842001 1 P 0 ;0,1=58,2=270.000000
L 0.62586713 0.9842001 0.62793337 0.9807501 1 P 0 ;0,1=58,2=270.000000
L 0.62793337 0.9807501 0.6145 0.9818999 1 P 0 ;0,1=58,2=270.000000
L 0.6145 0.9818999 0.6145 0.9922498 1 P 0 ;0,1=58,2=270.000000
L 0.6945 1.18849961 0.7255 1.18849961 1 P 0 ;0,1=59,2=270.000000
L 0.6945 1.17968337 0.6945 1.19731654 1 P 0 ;0,1=59,2=270.000000
L 0.7255 1.21183317 0.6945 1.21183317 1 P 0 ;0,1=59,2=270.000000
L 0.6945 1.21183317 0.6945 1.22103327 1 P 0 ;0,1=59,2=270.000000
L 0.6945 1.22103327 0.69605069 1.2241 1 P 0 ;0,1=59,2=270.000000
L 0.69605069 1.2241 0.69966654 1.2264002 1 P 0 ;0,1=59,2=270.000000
L 0.69966654 1.2264002 0.7038 1.22716673 1 P 0 ;0,1=59,2=270.000000
L 0.7038 1.22716673 0.70793337 1.2264002 1 P 0 ;0,1=59,2=270.000000
L 0.70793337 1.2264002 0.71103366 1.22448327 1 P 0 ;0,1=59,2=270.000000
L 0.71103366 1.22448327 0.71258425 1.22103327 1 P 0 ;0,1=59,2=270.000000
L 0.71258425 1.22103327 0.71258425 1.21183317 1 P 0 ;0,1=59,2=270.000000
L 0.71930039 1.24206663 0.72291722 1.24436614 1 P 0 ;0,1=59,2=270.000000
L 0.72291722 1.24436614 0.72498346 1.24743287 1 P 0 ;0,1=59,2=270.000000
L 0.72498346 1.24743287 0.7255 1.25088356 1 P 0 ;0,1=59,2=270.000000
L 0.7255 1.25088356 0.72498346 1.2539503 1 P 0 ;0,1=59,2=270.000000
L 0.72498346 1.2539503 0.72240069 1.25701703 1 P 0 ;0,1=59,2=270.000000
L 0.72240069 1.25701703 0.71930039 1.25893327 1 P 0 ;0,1=59,2=270.000000
L 0.71930039 1.25893327 0.7162001 1.25931654 1 P 0 ;0,1=59,2=270.000000
L 0.7162001 1.25931654 0.71258425 1.25855 1 P 0 ;0,1=59,2=270.000000
L 0.71258425 1.25855 0.71000049 1.25586654 1 P 0 ;0,1=59,2=270.000000
L 0.71000049 1.25586654 0.70896644 1.25318307 1 P 0 ;0,1=59,2=270.000000
L 0.70896644 1.25318307 0.70896644 1.24973307 1 P 0 ;0,1=59,2=270.000000
L 0.70896644 1.25318307 0.70741683 1.25548327 1 P 0 ;0,1=59,2=270.000000
L 0.70741683 1.25548327 0.70483406 1.2574002 1 P 0 ;0,1=59,2=270.000000
L 0.70483406 1.2574002 0.70173376 1.25816673 1 P 0 ;0,1=59,2=270.000000
L 0.70173376 1.25816673 0.69863346 1.2574002 1 P 0 ;0,1=59,2=270.000000
L 0.69863346 1.2574002 0.69605069 1.25548327 1 P 0 ;0,1=59,2=270.000000
L 0.69605069 1.25548327 0.6945 1.25203327 1 P 0 ;0,1=59,2=270.000000
L 0.6945 1.25203327 0.69501663 1.24858337 1 P 0 ;0,1=59,2=270.000000
L 0.69501663 1.24858337 0.69708376 1.24513337 1 P 0 ;0,1=59,2=270.000000
L 0.7255 1.2861 0.6945 1.2861 1 P 0 ;0,1=59,2=270.000000
L 0.6945 1.2861 0.71671673 1.27191624 1 P 0 ;0,1=59,2=270.000000
L 0.71671673 1.27191624 0.71671673 1.29108366 1 P 0 ;0,1=59,2=270.000000
L 0.6495 1.87349961 0.6805 1.87349961 1 P 0 ;0,1=60,2=270.000000
L 0.6495 1.86468337 0.6495 1.88231654 1 P 0 ;0,1=60,2=270.000000
L 0.6805 1.89683317 0.6495 1.89683317 1 P 0 ;0,1=60,2=270.000000
L 0.6495 1.89683317 0.6495 1.90603327 1 P 0 ;0,1=60,2=270.000000
L 0.6495 1.90603327 0.65105069 1.9091 1 P 0 ;0,1=60,2=270.000000
L 0.65105069 1.9091 0.65466654 1.9114002 1 P 0 ;0,1=60,2=270.000000
L 0.65466654 1.9114002 0.6588 1.91216673 1 P 0 ;0,1=60,2=270.000000
L 0.6588 1.91216673 0.66293337 1.9114002 1 P 0 ;0,1=60,2=270.000000
L 0.66293337 1.9114002 0.66603366 1.90948327 1 P 0 ;0,1=60,2=270.000000
L 0.66603366 1.90948327 0.66758425 1.90603327 1 P 0 ;0,1=60,2=270.000000
L 0.66758425 1.90603327 0.66758425 1.89683317 1 P 0 ;0,1=60,2=270.000000
L 0.67430039 1.92706663 0.67791722 1.92936614 1 P 0 ;0,1=60,2=270.000000
L 0.67791722 1.92936614 0.67998346 1.93243287 1 P 0 ;0,1=60,2=270.000000
L 0.67998346 1.93243287 0.6805 1.93588356 1 P 0 ;0,1=60,2=270.000000
L 0.6805 1.93588356 0.67998346 1.9389503 1 P 0 ;0,1=60,2=270.000000
L 0.67998346 1.9389503 0.67740069 1.94201703 1 P 0 ;0,1=60,2=270.000000
L 0.67740069 1.94201703 0.67430039 1.94393327 1 P 0 ;0,1=60,2=270.000000
L 0.67430039 1.94393327 0.6712001 1.94431654 1 P 0 ;0,1=60,2=270.000000
L 0.6712001 1.94431654 0.66758425 1.94355 1 P 0 ;0,1=60,2=270.000000
L 0.66758425 1.94355 0.66500049 1.94086654 1 P 0 ;0,1=60,2=270.000000
L 0.66500049 1.94086654 0.66396644 1.93818307 1 P 0 ;0,1=60,2=270.000000
L 0.66396644 1.93818307 0.66396644 1.93473307 1 P 0 ;0,1=60,2=270.000000
L 0.66396644 1.93818307 0.66241683 1.94048327 1 P 0 ;0,1=60,2=270.000000
L 0.66241683 1.94048327 0.65983406 1.9424002 1 P 0 ;0,1=60,2=270.000000
L 0.65983406 1.9424002 0.65673376 1.94316673 1 P 0 ;0,1=60,2=270.000000
L 0.65673376 1.94316673 0.65363346 1.9424002 1 P 0 ;0,1=60,2=270.000000
L 0.65363346 1.9424002 0.65105069 1.94048327 1 P 0 ;0,1=60,2=270.000000
L 0.65105069 1.94048327 0.6495 1.93703327 1 P 0 ;0,1=60,2=270.000000
L 0.6495 1.93703327 0.65001663 1.93358337 1 P 0 ;0,1=60,2=270.000000
L 0.65001663 1.93358337 0.65208376 1.93013337 1 P 0 ;0,1=60,2=270.000000
L 0.67430039 1.95806663 0.67791722 1.96036614 1 P 0 ;0,1=60,2=270.000000
L 0.67791722 1.96036614 0.67998346 1.96343287 1 P 0 ;0,1=60,2=270.000000
L 0.67998346 1.96343287 0.6805 1.96688356 1 P 0 ;0,1=60,2=270.000000
L 0.6805 1.96688356 0.67998346 1.9699503 1 P 0 ;0,1=60,2=270.000000
L 0.67998346 1.9699503 0.67740069 1.97301703 1 P 0 ;0,1=60,2=270.000000
L 0.67740069 1.97301703 0.67430039 1.97493327 1 P 0 ;0,1=60,2=270.000000
L 0.67430039 1.97493327 0.6712001 1.97531654 1 P 0 ;0,1=60,2=270.000000
L 0.6712001 1.97531654 0.66758425 1.97455 1 P 0 ;0,1=60,2=270.000000
L 0.66758425 1.97455 0.66500049 1.97186654 1 P 0 ;0,1=60,2=270.000000
L 0.66500049 1.97186654 0.66396644 1.96918307 1 P 0 ;0,1=60,2=270.000000
L 0.66396644 1.96918307 0.66396644 1.96573307 1 P 0 ;0,1=60,2=270.000000
L 0.66396644 1.96918307 0.66241683 1.97148327 1 P 0 ;0,1=60,2=270.000000
L 0.66241683 1.97148327 0.65983406 1.9734002 1 P 0 ;0,1=60,2=270.000000
L 0.65983406 1.9734002 0.65673376 1.97416673 1 P 0 ;0,1=60,2=270.000000
L 0.65673376 1.97416673 0.65363346 1.9734002 1 P 0 ;0,1=60,2=270.000000
L 0.65363346 1.9734002 0.65105069 1.97148327 1 P 0 ;0,1=60,2=270.000000
L 0.65105069 1.97148327 0.6495 1.96803327 1 P 0 ;0,1=60,2=270.000000
L 0.6495 1.96803327 0.65001663 1.96458337 1 P 0 ;0,1=60,2=270.000000
L 0.65001663 1.96458337 0.65208376 1.96113337 1 P 0 ;0,1=60,2=270.000000
L 0.6125 2.4019997 0.6375 2.4019997 1 P 0 ;0,1=61,2=270.000000
L 0.6125 2.39586673 0.6125 2.40813317 1 P 0 ;0,1=61,2=270.000000
L 0.6375 2.41866654 0.6125 2.41866654 1 P 0 ;0,1=61,2=270.000000
L 0.6125 2.41866654 0.6125 2.42506663 1 P 0 ;0,1=61,2=270.000000
L 0.6125 2.42506663 0.61375059 2.4272 1 P 0 ;0,1=61,2=270.000000
L 0.61375059 2.4272 0.61666663 2.4288001 1 P 0 ;0,1=61,2=270.000000
L 0.61666663 2.4288001 0.62 2.42933337 1 P 0 ;0,1=61,2=270.000000
L 0.62 2.42933337 0.62333337 2.4288001 1 P 0 ;0,1=61,2=270.000000
L 0.62333337 2.4288001 0.62583356 2.42746663 1 P 0 ;0,1=61,2=270.000000
L 0.62583356 2.42746663 0.62708406 2.42506663 1 P 0 ;0,1=61,2=270.000000
L 0.62708406 2.42506663 0.62708406 2.41866654 1 P 0 ;0,1=61,2=270.000000
L 0.63250039 2.44013327 0.63541713 2.44173297 1 P 0 ;0,1=61,2=270.000000
L 0.63541713 2.44173297 0.63708346 2.44386634 1 P 0 ;0,1=61,2=270.000000
L 0.63708346 2.44386634 0.6375 2.44626683 1 P 0 ;0,1=61,2=270.000000
L 0.6375 2.44626683 0.63708346 2.4484002 1 P 0 ;0,1=61,2=270.000000
L 0.63708346 2.4484002 0.63500059 2.45053356 1 P 0 ;0,1=61,2=270.000000
L 0.63500059 2.45053356 0.63250039 2.45186663 1 P 0 ;0,1=61,2=270.000000
L 0.63250039 2.45186663 0.6300001 2.45213317 1 P 0 ;0,1=61,2=270.000000
L 0.6300001 2.45213317 0.62708406 2.4516 1 P 0 ;0,1=61,2=270.000000
L 0.62708406 2.4516 0.62500039 2.44973327 1 P 0 ;0,1=61,2=270.000000
L 0.62500039 2.44973327 0.62416654 2.44786644 1 P 0 ;0,1=61,2=270.000000
L 0.62416654 2.44786644 0.62416654 2.44546654 1 P 0 ;0,1=61,2=270.000000
L 0.62416654 2.44786644 0.62291673 2.44946663 1 P 0 ;0,1=61,2=270.000000
L 0.62291673 2.44946663 0.62083386 2.4508001 1 P 0 ;0,1=61,2=270.000000
L 0.62083386 2.4508001 0.61833366 2.45133337 1 P 0 ;0,1=61,2=270.000000
L 0.61833366 2.45133337 0.61583346 2.4508001 1 P 0 ;0,1=61,2=270.000000
L 0.61583346 2.4508001 0.61375059 2.44946663 1 P 0 ;0,1=61,2=270.000000
L 0.61375059 2.44946663 0.6125 2.44706663 1 P 0 ;0,1=61,2=270.000000
L 0.6125 2.44706663 0.61291663 2.44466663 1 P 0 ;0,1=61,2=270.000000
L 0.61291663 2.44466663 0.61458366 2.44226663 1 P 0 ;0,1=61,2=270.000000
L 0.61666663 2.46293317 0.61416713 2.46453327 1 P 0 ;0,1=61,2=270.000000
L 0.61416713 2.46453327 0.61291663 2.4664 1 P 0 ;0,1=61,2=270.000000
L 0.61291663 2.4664 0.6125 2.46853337 1 P 0 ;0,1=61,2=270.000000
L 0.6125 2.46853337 0.61333317 2.4712 1 P 0 ;0,1=61,2=270.000000
L 0.61333317 2.4712 0.61541683 2.47306673 1 P 0 ;0,1=61,2=270.000000
L 0.61541683 2.47306673 0.61791634 2.4736 1 P 0 ;0,1=61,2=270.000000
L 0.61791634 2.4736 0.62041732 2.47333337 1 P 0 ;0,1=61,2=270.000000
L 0.62041732 2.47333337 0.6225002 2.47226644 1 P 0 ;0,1=61,2=270.000000
L 0.6225002 2.47226644 0.62666673 2.46693327 1 P 0 ;0,1=61,2=270.000000
L 0.62666673 2.46693327 0.62958356 2.46453327 1 P 0 ;0,1=61,2=270.000000
L 0.62958356 2.46453327 0.63375089 2.46293317 1 P 0 ;0,1=61,2=270.000000
L 0.63375089 2.46293317 0.6375 2.4623999 1 P 0 ;0,1=61,2=270.000000
L 0.6375 2.4623999 0.6375 2.4736 1 P 0 ;0,1=61,2=270.000000
L 0.6455 0.5649997 0.6705 0.5649997 1 P 0 ;0,1=62,2=270.000000
L 0.6455 0.55886673 0.6455 0.57113317 1 P 0 ;0,1=62,2=270.000000
L 0.6705 0.58166654 0.6455 0.58166654 1 P 0 ;0,1=62,2=270.000000
L 0.6455 0.58166654 0.6455 0.58806663 1 P 0 ;0,1=62,2=270.000000
L 0.6455 0.58806663 0.64675059 0.5902 1 P 0 ;0,1=62,2=270.000000
L 0.64675059 0.5902 0.64966663 0.5918001 1 P 0 ;0,1=62,2=270.000000
L 0.64966663 0.5918001 0.653 0.59233337 1 P 0 ;0,1=62,2=270.000000
L 0.653 0.59233337 0.65633337 0.5918001 1 P 0 ;0,1=62,2=270.000000
L 0.65633337 0.5918001 0.65883356 0.59046663 1 P 0 ;0,1=62,2=270.000000
L 0.65883356 0.59046663 0.66008406 0.58806663 1 P 0 ;0,1=62,2=270.000000
L 0.66008406 0.58806663 0.66008406 0.58166654 1 P 0 ;0,1=62,2=270.000000
L 0.66550039 0.60313327 0.66841713 0.60473297 1 P 0 ;0,1=62,2=270.000000
L 0.66841713 0.60473297 0.67008346 0.60686634 1 P 0 ;0,1=62,2=270.000000
L 0.67008346 0.60686634 0.6705 0.60926683 1 P 0 ;0,1=62,2=270.000000
L 0.6705 0.60926683 0.67008346 0.6114002 1 P 0 ;0,1=62,2=270.000000
L 0.67008346 0.6114002 0.66800059 0.61353356 1 P 0 ;0,1=62,2=270.000000
L 0.66800059 0.61353356 0.66550039 0.61486663 1 P 0 ;0,1=62,2=270.000000
L 0.66550039 0.61486663 0.6630001 0.61513317 1 P 0 ;0,1=62,2=270.000000
L 0.6630001 0.61513317 0.66008406 0.6146 1 P 0 ;0,1=62,2=270.000000
L 0.66008406 0.6146 0.65800039 0.61273327 1 P 0 ;0,1=62,2=270.000000
L 0.65800039 0.61273327 0.65716654 0.61086644 1 P 0 ;0,1=62,2=270.000000
L 0.65716654 0.61086644 0.65716654 0.60846654 1 P 0 ;0,1=62,2=270.000000
L 0.65716654 0.61086644 0.65591673 0.61246663 1 P 0 ;0,1=62,2=270.000000
L 0.65591673 0.61246663 0.65383386 0.6138001 1 P 0 ;0,1=62,2=270.000000
L 0.65383386 0.6138001 0.65133366 0.61433337 1 P 0 ;0,1=62,2=270.000000
L 0.65133366 0.61433337 0.64883346 0.6138001 1 P 0 ;0,1=62,2=270.000000
L 0.64883346 0.6138001 0.64675059 0.61246663 1 P 0 ;0,1=62,2=270.000000
L 0.64675059 0.61246663 0.6455 0.61006663 1 P 0 ;0,1=62,2=270.000000
L 0.6455 0.61006663 0.64591663 0.60766663 1 P 0 ;0,1=62,2=270.000000
L 0.64591663 0.60766663 0.64758366 0.60526663 1 P 0 ;0,1=62,2=270.000000
L 0.6705 0.6309997 0.6455 0.6309997 1 P 0 ;0,1=62,2=270.000000
L 0.6455 0.6309997 0.6504997 0.6277999 1 P 0 ;0,1=62,2=270.000000
L 0.6705 0.6277999 0.6705 0.63419951 1 P 0 ;0,1=62,2=270.000000
L 0.5425 1.0369997 0.5675 1.0369997 1 P 0 ;0,1=63,2=270.000000
L 0.5425 1.03086673 0.5425 1.04313317 1 P 0 ;0,1=63,2=270.000000
L 0.5675 1.05366654 0.5425 1.05366654 1 P 0 ;0,1=63,2=270.000000
L 0.5425 1.05366654 0.5425 1.06006663 1 P 0 ;0,1=63,2=270.000000
L 0.5425 1.06006663 0.54375059 1.0622 1 P 0 ;0,1=63,2=270.000000
L 0.54375059 1.0622 0.54666663 1.0638001 1 P 0 ;0,1=63,2=270.000000
L 0.54666663 1.0638001 0.55 1.06433337 1 P 0 ;0,1=63,2=270.000000
L 0.55 1.06433337 0.55333337 1.0638001 1 P 0 ;0,1=63,2=270.000000
L 0.55333337 1.0638001 0.55583356 1.06246663 1 P 0 ;0,1=63,2=270.000000
L 0.55583356 1.06246663 0.55708406 1.06006663 1 P 0 ;0,1=63,2=270.000000
L 0.55708406 1.06006663 0.55708406 1.05366654 1 P 0 ;0,1=63,2=270.000000
L 0.56250039 1.07513327 0.56541713 1.07673297 1 P 0 ;0,1=63,2=270.000000
L 0.56541713 1.07673297 0.56708346 1.07886634 1 P 0 ;0,1=63,2=270.000000
L 0.56708346 1.07886634 0.5675 1.08126683 1 P 0 ;0,1=63,2=270.000000
L 0.5675 1.08126683 0.56708346 1.0834002 1 P 0 ;0,1=63,2=270.000000
L 0.56708346 1.0834002 0.56500059 1.08553356 1 P 0 ;0,1=63,2=270.000000
L 0.56500059 1.08553356 0.56250039 1.08686663 1 P 0 ;0,1=63,2=270.000000
L 0.56250039 1.08686663 0.5600001 1.08713317 1 P 0 ;0,1=63,2=270.000000
L 0.5600001 1.08713317 0.55708406 1.0866 1 P 0 ;0,1=63,2=270.000000
L 0.55708406 1.0866 0.55500039 1.08473327 1 P 0 ;0,1=63,2=270.000000
L 0.55500039 1.08473327 0.55416654 1.08286644 1 P 0 ;0,1=63,2=270.000000
L 0.55416654 1.08286644 0.55416654 1.08046654 1 P 0 ;0,1=63,2=270.000000
L 0.55416654 1.08286644 0.55291673 1.08446663 1 P 0 ;0,1=63,2=270.000000
L 0.55291673 1.08446663 0.55083386 1.0858001 1 P 0 ;0,1=63,2=270.000000
L 0.55083386 1.0858001 0.54833366 1.08633337 1 P 0 ;0,1=63,2=270.000000
L 0.54833366 1.08633337 0.54583346 1.0858001 1 P 0 ;0,1=63,2=270.000000
L 0.54583346 1.0858001 0.54375059 1.08446663 1 P 0 ;0,1=63,2=270.000000
L 0.54375059 1.08446663 0.5425 1.08206663 1 P 0 ;0,1=63,2=270.000000
L 0.5425 1.08206663 0.54291663 1.07966663 1 P 0 ;0,1=63,2=270.000000
L 0.54291663 1.07966663 0.54458366 1.07726663 1 P 0 ;0,1=63,2=270.000000
L 0.5425 1.1029997 0.54333317 1.10086634 1 P 0 ;0,1=63,2=270.000000
L 0.54333317 1.10086634 0.54541683 1.09926663 1 P 0 ;0,1=63,2=270.000000
L 0.54541683 1.09926663 0.54791634 1.0981998 1 P 0 ;0,1=63,2=270.000000
L 0.54791634 1.0981998 0.55125049 1.0973999 1 P 0 ;0,1=63,2=270.000000
L 0.55125049 1.0973999 0.55500039 1.09713327 1 P 0 ;0,1=63,2=270.000000
L 0.55500039 1.09713327 0.55875039 1.0973999 1 P 0 ;0,1=63,2=270.000000
L 0.55875039 1.0973999 0.56208376 1.0981998 1 P 0 ;0,1=63,2=270.000000
L 0.56208376 1.0981998 0.56458396 1.09926663 1 P 0 ;0,1=63,2=270.000000
L 0.56458396 1.09926663 0.56666693 1.10086634 1 P 0 ;0,1=63,2=270.000000
L 0.56666693 1.10086634 0.5675 1.1029997 1 P 0 ;0,1=63,2=270.000000
L 0.5675 1.1029997 0.56666693 1.10513307 1 P 0 ;0,1=63,2=270.000000
L 0.56666693 1.10513307 0.56458396 1.10673327 1 P 0 ;0,1=63,2=270.000000
L 0.56458396 1.10673327 0.56208376 1.1078001 1 P 0 ;0,1=63,2=270.000000
L 0.56208376 1.1078001 0.55875039 1.1086 1 P 0 ;0,1=63,2=270.000000
L 0.55875039 1.1086 0.55500039 1.10886663 1 P 0 ;0,1=63,2=270.000000
L 0.55500039 1.10886663 0.55125049 1.1086 1 P 0 ;0,1=63,2=270.000000
L 0.55125049 1.1086 0.54791634 1.1078001 1 P 0 ;0,1=63,2=270.000000
L 0.54791634 1.1078001 0.54541683 1.10673327 1 P 0 ;0,1=63,2=270.000000
L 0.54541683 1.10673327 0.54333317 1.10513307 1 P 0 ;0,1=63,2=270.000000
L 0.54333317 1.10513307 0.5425 1.1029997 1 P 0 ;0,1=63,2=270.000000
L 0.5819997 1.7475 0.5819997 1.7225 1 P 0 ;0,1=64,2=0.000000
L 0.57586673 1.7475 0.58813317 1.7475 1 P 0 ;0,1=64,2=0.000000
L 0.59866654 1.7225 0.59866654 1.7475 1 P 0 ;0,1=64,2=0.000000
L 0.59866654 1.7475 0.60506663 1.7475 1 P 0 ;0,1=64,2=0.000000
L 0.60506663 1.7475 0.6072 1.74624941 1 P 0 ;0,1=64,2=0.000000
L 0.6072 1.74624941 0.6088001 1.74333337 1 P 0 ;0,1=64,2=0.000000
L 0.6088001 1.74333337 0.60933337 1.74 1 P 0 ;0,1=64,2=0.000000
L 0.60933337 1.74 0.6088001 1.73666663 1 P 0 ;0,1=64,2=0.000000
L 0.6088001 1.73666663 0.60746663 1.73416644 1 P 0 ;0,1=64,2=0.000000
L 0.60746663 1.73416644 0.60506663 1.73291594 1 P 0 ;0,1=64,2=0.000000
L 0.60506663 1.73291594 0.59866654 1.73291594 1 P 0 ;0,1=64,2=0.000000
L 0.62093317 1.74333337 0.62253327 1.74583287 1 P 0 ;0,1=64,2=0.000000
L 0.62253327 1.74583287 0.6244 1.74708337 1 P 0 ;0,1=64,2=0.000000
L 0.6244 1.74708337 0.62653337 1.7475 1 P 0 ;0,1=64,2=0.000000
L 0.62653337 1.7475 0.6292 1.74666683 1 P 0 ;0,1=64,2=0.000000
L 0.6292 1.74666683 0.63106673 1.74458317 1 P 0 ;0,1=64,2=0.000000
L 0.63106673 1.74458317 0.6316 1.74208366 1 P 0 ;0,1=64,2=0.000000
L 0.6316 1.74208366 0.63133337 1.73958268 1 P 0 ;0,1=64,2=0.000000
L 0.63133337 1.73958268 0.63026644 1.7374998 1 P 0 ;0,1=64,2=0.000000
L 0.63026644 1.7374998 0.62493327 1.73333327 1 P 0 ;0,1=64,2=0.000000
L 0.62493327 1.73333327 0.62253327 1.73041644 1 P 0 ;0,1=64,2=0.000000
L 0.62253327 1.73041644 0.62093317 1.72624911 1 P 0 ;0,1=64,2=0.000000
L 0.62093317 1.72624911 0.6203999 1.7225 1 P 0 ;0,1=64,2=0.000000
L 0.6203999 1.7225 0.6316 1.7225 1 P 0 ;0,1=64,2=0.000000
L 0.64346634 1.72541604 0.64533317 1.72333307 1 P 0 ;0,1=64,2=0.000000
L 0.64533317 1.72333307 0.64746654 1.7225 1 P 0 ;0,1=64,2=0.000000
L 0.64746654 1.7225 0.6495999 1.72333307 1 P 0 ;0,1=64,2=0.000000
L 0.6495999 1.72333307 0.65146663 1.72583258 1 P 0 ;0,1=64,2=0.000000
L 0.65146663 1.72583258 0.6528001 1.72958327 1 P 0 ;0,1=64,2=0.000000
L 0.6528001 1.72958327 0.65333337 1.73333327 1 P 0 ;0,1=64,2=0.000000
L 0.65333337 1.73333327 0.65333337 1.73791634 1 P 0 ;0,1=64,2=0.000000
L 0.65333337 1.73791634 0.6528001 1.74166634 1 P 0 ;0,1=64,2=0.000000
L 0.6528001 1.74166634 0.65146663 1.7449997 1 P 0 ;0,1=64,2=0.000000
L 0.65146663 1.7449997 0.64986644 1.74666683 1 P 0 ;0,1=64,2=0.000000
L 0.64986644 1.74666683 0.6479997 1.7475 1 P 0 ;0,1=64,2=0.000000
L 0.6479997 1.7475 0.64586634 1.74666683 1 P 0 ;0,1=64,2=0.000000
L 0.64586634 1.74666683 0.64426663 1.7449997 1 P 0 ;0,1=64,2=0.000000
L 0.64426663 1.7449997 0.6431998 1.7425003 1 P 0 ;0,1=64,2=0.000000
L 0.6431998 1.7425003 0.64266654 1.73916614 1 P 0 ;0,1=64,2=0.000000
L 0.64266654 1.73916614 0.6431998 1.7362501 1 P 0 ;0,1=64,2=0.000000
L 0.6431998 1.7362501 0.64453327 1.73333327 1 P 0 ;0,1=64,2=0.000000
L 0.64453327 1.73333327 0.64613346 1.73166614 1 P 0 ;0,1=64,2=0.000000
L 0.64613346 1.73166614 0.6479997 1.73124961 1 P 0 ;0,1=64,2=0.000000
L 0.6479997 1.73124961 0.65013307 1.73208278 1 P 0 ;0,1=64,2=0.000000
L 0.65013307 1.73208278 0.65173327 1.73416644 1 P 0 ;0,1=64,2=0.000000
L 0.65173327 1.73416644 0.65333337 1.73791634 1 P 0 ;0,1=64,2=0.000000
L 0.5875 2.1619997 0.6125 2.1619997 1 P 0 ;0,1=65,2=270.000000
L 0.5875 2.15586673 0.5875 2.16813317 1 P 0 ;0,1=65,2=270.000000
L 0.6125 2.17866654 0.5875 2.17866654 1 P 0 ;0,1=65,2=270.000000
L 0.5875 2.17866654 0.5875 2.18506663 1 P 0 ;0,1=65,2=270.000000
L 0.5875 2.18506663 0.58875059 2.1872 1 P 0 ;0,1=65,2=270.000000
L 0.58875059 2.1872 0.59166663 2.1888001 1 P 0 ;0,1=65,2=270.000000
L 0.59166663 2.1888001 0.595 2.18933337 1 P 0 ;0,1=65,2=270.000000
L 0.595 2.18933337 0.59833337 2.1888001 1 P 0 ;0,1=65,2=270.000000
L 0.59833337 2.1888001 0.60083356 2.18746663 1 P 0 ;0,1=65,2=270.000000
L 0.60083356 2.18746663 0.60208406 2.18506663 1 P 0 ;0,1=65,2=270.000000
L 0.60208406 2.18506663 0.60208406 2.17866654 1 P 0 ;0,1=65,2=270.000000
L 0.59166663 2.20093317 0.58916713 2.20253327 1 P 0 ;0,1=65,2=270.000000
L 0.58916713 2.20253327 0.58791663 2.2044 1 P 0 ;0,1=65,2=270.000000
L 0.58791663 2.2044 0.5875 2.20653337 1 P 0 ;0,1=65,2=270.000000
L 0.5875 2.20653337 0.58833317 2.2092 1 P 0 ;0,1=65,2=270.000000
L 0.58833317 2.2092 0.59041683 2.21106673 1 P 0 ;0,1=65,2=270.000000
L 0.59041683 2.21106673 0.59291634 2.2116 1 P 0 ;0,1=65,2=270.000000
L 0.59291634 2.2116 0.59541732 2.21133337 1 P 0 ;0,1=65,2=270.000000
L 0.59541732 2.21133337 0.5975002 2.21026644 1 P 0 ;0,1=65,2=270.000000
L 0.5975002 2.21026644 0.60166673 2.20493327 1 P 0 ;0,1=65,2=270.000000
L 0.60166673 2.20493327 0.60458356 2.20253327 1 P 0 ;0,1=65,2=270.000000
L 0.60458356 2.20253327 0.60875089 2.20093317 1 P 0 ;0,1=65,2=270.000000
L 0.60875089 2.20093317 0.6125 2.2003999 1 P 0 ;0,1=65,2=270.000000
L 0.6125 2.2003999 0.6125 2.2116 1 P 0 ;0,1=65,2=270.000000
L 0.6125 2.2279997 0.61208346 2.22986644 1 P 0 ;0,1=65,2=270.000000
L 0.61208346 2.22986644 0.61083376 2.2319998 1 P 0 ;0,1=65,2=270.000000
L 0.61083376 2.2319998 0.60875089 2.23333337 1 P 0 ;0,1=65,2=270.000000
L 0.60875089 2.23333337 0.60583327 2.23386663 1 P 0 ;0,1=65,2=270.000000
L 0.60583327 2.23386663 0.60291722 2.23333337 1 P 0 ;0,1=65,2=270.000000
L 0.60291722 2.23333337 0.60041703 2.23173327 1 P 0 ;0,1=65,2=270.000000
L 0.60041703 2.23173327 0.59916654 2.22933327 1 P 0 ;0,1=65,2=270.000000
L 0.59916654 2.22933327 0.59916654 2.22666663 1 P 0 ;0,1=65,2=270.000000
L 0.59916654 2.22666663 0.59833337 2.22506654 1 P 0 ;0,1=65,2=270.000000
L 0.59833337 2.22506654 0.59625049 2.22373297 1 P 0 ;0,1=65,2=270.000000
L 0.59625049 2.22373297 0.59333366 2.2231998 1 P 0 ;0,1=65,2=270.000000
L 0.59333366 2.2231998 0.59041683 2.2240001 1 P 0 ;0,1=65,2=270.000000
L 0.59041683 2.2240001 0.58833317 2.22586634 1 P 0 ;0,1=65,2=270.000000
L 0.58833317 2.22586634 0.5875 2.2279997 1 P 0 ;0,1=65,2=270.000000
L 0.5875 2.2279997 0.58833317 2.23013307 1 P 0 ;0,1=65,2=270.000000
L 0.58833317 2.23013307 0.59041683 2.2319998 1 P 0 ;0,1=65,2=270.000000
L 0.59041683 2.2319998 0.59333366 2.2328001 1 P 0 ;0,1=65,2=270.000000
L 0.59333366 2.2328001 0.59625049 2.23226644 1 P 0 ;0,1=65,2=270.000000
L 0.59625049 2.23226644 0.59833337 2.23093337 1 P 0 ;0,1=65,2=270.000000
L 0.59833337 2.23093337 0.59916654 2.22933327 1 P 0 ;0,1=65,2=270.000000
L 0.59916654 2.22933327 0.59916654 2.22666663 1 P 0 ;0,1=65,2=270.000000
L 0.59916654 2.22666663 0.60041703 2.22426663 1 P 0 ;0,1=65,2=270.000000
L 0.60041703 2.22426663 0.60291722 2.22266654 1 P 0 ;0,1=65,2=270.000000
L 0.60291722 2.22266654 0.60583327 2.22213327 1 P 0 ;0,1=65,2=270.000000
L 0.60583327 2.22213327 0.60875089 2.22266654 1 P 0 ;0,1=65,2=270.000000
L 0.60875089 2.22266654 0.61083376 2.2240001 1 P 0 ;0,1=65,2=270.000000
L 0.61083376 2.2240001 0.61208346 2.22613346 1 P 0 ;0,1=65,2=270.000000
L 0.61208346 2.22613346 0.6125 2.2279997 1 P 0 ;0,1=65,2=270.000000
L 5.78349961 1.8005 5.78349961 1.7695 1 P 0 ;0,1=66,2=0.000000
L 5.77468337 1.8005 5.79231654 1.8005 1 P 0 ;0,1=66,2=0.000000
L 5.80683317 1.7695 5.80683317 1.8005 1 P 0 ;0,1=66,2=0.000000
L 5.80683317 1.8005 5.81603327 1.8005 1 P 0 ;0,1=66,2=0.000000
L 5.81603327 1.8005 5.8191 1.79894931 1 P 0 ;0,1=66,2=0.000000
L 5.8191 1.79894931 5.8214002 1.79533346 1 P 0 ;0,1=66,2=0.000000
L 5.8214002 1.79533346 5.82216673 1.7912 1 P 0 ;0,1=66,2=0.000000
L 5.82216673 1.7912 5.8214002 1.78706663 1 P 0 ;0,1=66,2=0.000000
L 5.8214002 1.78706663 5.81948327 1.78396634 1 P 0 ;0,1=66,2=0.000000
L 5.81948327 1.78396634 5.81603327 1.78241575 1 P 0 ;0,1=66,2=0.000000
L 5.81603327 1.78241575 5.80683317 1.78241575 1 P 0 ;0,1=66,2=0.000000
L 5.83821644 1.79533346 5.84051663 1.79843278 1 P 0 ;0,1=66,2=0.000000
L 5.84051663 1.79843278 5.8432001 1.79998337 1 P 0 ;0,1=66,2=0.000000
L 5.8432001 1.79998337 5.84626683 1.8005 1 P 0 ;0,1=66,2=0.000000
L 5.84626683 1.8005 5.8501 1.79946683 1 P 0 ;0,1=66,2=0.000000
L 5.8501 1.79946683 5.85278346 1.79688307 1 P 0 ;0,1=66,2=0.000000
L 5.85278346 1.79688307 5.85355 1.79378376 1 P 0 ;0,1=66,2=0.000000
L 5.85355 1.79378376 5.85316673 1.79068258 1 P 0 ;0,1=66,2=0.000000
L 5.85316673 1.79068258 5.85163307 1.7880998 1 P 0 ;0,1=66,2=0.000000
L 5.85163307 1.7880998 5.84396663 1.78293327 1 P 0 ;0,1=66,2=0.000000
L 5.84396663 1.78293327 5.84051663 1.77931644 1 P 0 ;0,1=66,2=0.000000
L 5.84051663 1.77931644 5.83821644 1.77414892 1 P 0 ;0,1=66,2=0.000000
L 5.83821644 1.77414892 5.8374499 1.7695 1 P 0 ;0,1=66,2=0.000000
L 5.8374499 1.7695 5.85355 1.7695 1 P 0 ;0,1=66,2=0.000000
L 5.87573307 1.7695 5.87649961 1.77621614 1 P 0 ;0,1=66,2=0.000000
L 5.87649961 1.77621614 5.8776501 1.78189921 1 P 0 ;0,1=66,2=0.000000
L 5.8776501 1.78189921 5.87918307 1.78706663 1 P 0 ;0,1=66,2=0.000000
L 5.87918307 1.78706663 5.8811 1.7927497 1 P 0 ;0,1=66,2=0.000000
L 5.8811 1.7927497 5.88416673 1.8005 1 P 0 ;0,1=66,2=0.000000
L 5.88416673 1.8005 5.86883317 1.8005 1 P 0 ;0,1=66,2=0.000000
L 5.93849961 2.4655 5.93849961 2.4345 1 P 0 ;0,1=67,2=0.000000
L 5.92968337 2.4655 5.94731654 2.4655 1 P 0 ;0,1=67,2=0.000000
L 5.96183317 2.4345 5.96183317 2.4655 1 P 0 ;0,1=67,2=0.000000
L 5.96183317 2.4655 5.97103327 2.4655 1 P 0 ;0,1=67,2=0.000000
L 5.97103327 2.4655 5.9741 2.46394931 1 P 0 ;0,1=67,2=0.000000
L 5.9741 2.46394931 5.9764002 2.46033346 1 P 0 ;0,1=67,2=0.000000
L 5.9764002 2.46033346 5.97716673 2.4562 1 P 0 ;0,1=67,2=0.000000
L 5.97716673 2.4562 5.9764002 2.45206663 1 P 0 ;0,1=67,2=0.000000
L 5.9764002 2.45206663 5.97448327 2.44896634 1 P 0 ;0,1=67,2=0.000000
L 5.97448327 2.44896634 5.97103327 2.44741575 1 P 0 ;0,1=67,2=0.000000
L 5.97103327 2.44741575 5.96183317 2.44741575 1 P 0 ;0,1=67,2=0.000000
L 5.99321644 2.46033346 5.99551663 2.46343278 1 P 0 ;0,1=67,2=0.000000
L 5.99551663 2.46343278 5.9982001 2.46498337 1 P 0 ;0,1=67,2=0.000000
L 5.9982001 2.46498337 6.00126683 2.4655 1 P 0 ;0,1=67,2=0.000000
L 6.00126683 2.4655 6.0051 2.46446683 1 P 0 ;0,1=67,2=0.000000
L 6.0051 2.46446683 6.00778346 2.46188307 1 P 0 ;0,1=67,2=0.000000
L 6.00778346 2.46188307 6.00855 2.45878376 1 P 0 ;0,1=67,2=0.000000
L 6.00855 2.45878376 6.00816673 2.45568258 1 P 0 ;0,1=67,2=0.000000
L 6.00816673 2.45568258 6.00663307 2.4530998 1 P 0 ;0,1=67,2=0.000000
L 6.00663307 2.4530998 5.99896663 2.44793327 1 P 0 ;0,1=67,2=0.000000
L 5.99896663 2.44793327 5.99551663 2.44431644 1 P 0 ;0,1=67,2=0.000000
L 5.99551663 2.44431644 5.99321644 2.43914892 1 P 0 ;0,1=67,2=0.000000
L 5.99321644 2.43914892 5.9924499 2.4345 1 P 0 ;0,1=67,2=0.000000
L 5.9924499 2.4345 6.00855 2.4345 1 P 0 ;0,1=67,2=0.000000
L 6.02421644 2.44741575 6.0268999 2.45103356 1 P 0 ;0,1=67,2=0.000000
L 6.0268999 2.45103356 6.0292001 2.4530998 1 P 0 ;0,1=67,2=0.000000
L 6.0292001 2.4530998 6.03226683 2.45413287 1 P 0 ;0,1=67,2=0.000000
L 6.03226683 2.45413287 6.0349503 2.4530998 1 P 0 ;0,1=67,2=0.000000
L 6.0349503 2.4530998 6.03686654 2.45103356 1 P 0 ;0,1=67,2=0.000000
L 6.03686654 2.45103356 6.0384002 2.44793327 1 P 0 ;0,1=67,2=0.000000
L 6.0384002 2.44793327 6.03878346 2.44431644 1 P 0 ;0,1=67,2=0.000000
L 6.03878346 2.44431644 6.0384002 2.44121614 1 P 0 ;0,1=67,2=0.000000
L 6.0384002 2.44121614 6.03686654 2.43811585 1 P 0 ;0,1=67,2=0.000000
L 6.03686654 2.43811585 6.03456634 2.43553307 1 P 0 ;0,1=67,2=0.000000
L 6.03456634 2.43553307 6.03188356 2.4345 1 P 0 ;0,1=67,2=0.000000
L 6.03188356 2.4345 6.02881683 2.43553307 1 P 0 ;0,1=67,2=0.000000
L 6.02881683 2.43553307 6.02613337 2.43863238 1 P 0 ;0,1=67,2=0.000000
L 6.02613337 2.43863238 6.0245997 2.44328327 1 P 0 ;0,1=67,2=0.000000
L 6.0245997 2.44328327 6.02421644 2.4484498 1 P 0 ;0,1=67,2=0.000000
L 6.02421644 2.4484498 6.02498287 2.45516594 1 P 0 ;0,1=67,2=0.000000
L 6.02498287 2.45516594 6.02613337 2.45878376 1 P 0 ;0,1=67,2=0.000000
L 6.02613337 2.45878376 6.02804961 2.4623997 1 P 0 ;0,1=67,2=0.000000
L 6.02804961 2.4623997 6.03073307 2.46498337 1 P 0 ;0,1=67,2=0.000000
L 6.03073307 2.46498337 6.03341654 2.4655 1 P 0 ;0,1=67,2=0.000000
L 6.03341654 2.4655 6.0361 2.46446683 1 P 0 ;0,1=67,2=0.000000
L 6.0361 2.46446683 6.03801703 2.46188307 1 P 0 ;0,1=67,2=0.000000
L 4.2719997 3.8375 4.2719997 3.8125 1 P 0 ;0,1=68,2=0.000000
L 4.26586673 3.8375 4.27813317 3.8375 1 P 0 ;0,1=68,2=0.000000
L 4.28866654 3.8125 4.28866654 3.8375 1 P 0 ;0,1=68,2=0.000000
L 4.28866654 3.8375 4.29506663 3.8375 1 P 0 ;0,1=68,2=0.000000
L 4.29506663 3.8375 4.2972 3.83624941 1 P 0 ;0,1=68,2=0.000000
L 4.2972 3.83624941 4.2988001 3.83333337 1 P 0 ;0,1=68,2=0.000000
L 4.2988001 3.83333337 4.29933337 3.83 1 P 0 ;0,1=68,2=0.000000
L 4.29933337 3.83 4.2988001 3.82666663 1 P 0 ;0,1=68,2=0.000000
L 4.2988001 3.82666663 4.29746663 3.82416644 1 P 0 ;0,1=68,2=0.000000
L 4.29746663 3.82416644 4.29506663 3.82291594 1 P 0 ;0,1=68,2=0.000000
L 4.29506663 3.82291594 4.28866654 3.82291594 1 P 0 ;0,1=68,2=0.000000
L 4.31093317 3.83333337 4.31253327 3.83583287 1 P 0 ;0,1=68,2=0.000000
L 4.31253327 3.83583287 4.3144 3.83708337 1 P 0 ;0,1=68,2=0.000000
L 4.3144 3.83708337 4.31653337 3.8375 1 P 0 ;0,1=68,2=0.000000
L 4.31653337 3.8375 4.3192 3.83666683 1 P 0 ;0,1=68,2=0.000000
L 4.3192 3.83666683 4.32106673 3.83458317 1 P 0 ;0,1=68,2=0.000000
L 4.32106673 3.83458317 4.3216 3.83208366 1 P 0 ;0,1=68,2=0.000000
L 4.3216 3.83208366 4.32133337 3.82958268 1 P 0 ;0,1=68,2=0.000000
L 4.32133337 3.82958268 4.32026644 3.8274998 1 P 0 ;0,1=68,2=0.000000
L 4.32026644 3.8274998 4.31493327 3.82333327 1 P 0 ;0,1=68,2=0.000000
L 4.31493327 3.82333327 4.31253327 3.82041644 1 P 0 ;0,1=68,2=0.000000
L 4.31253327 3.82041644 4.31093317 3.81624911 1 P 0 ;0,1=68,2=0.000000
L 4.31093317 3.81624911 4.3103999 3.8125 1 P 0 ;0,1=68,2=0.000000
L 4.3103999 3.8125 4.3216 3.8125 1 P 0 ;0,1=68,2=0.000000
L 4.33213327 3.81624911 4.33373297 3.81416624 1 P 0 ;0,1=68,2=0.000000
L 4.33373297 3.81416624 4.3355997 3.81291654 1 P 0 ;0,1=68,2=0.000000
L 4.3355997 3.81291654 4.3379997 3.8125 1 P 0 ;0,1=68,2=0.000000
L 4.3379997 3.8125 4.3404002 3.81333307 1 P 0 ;0,1=68,2=0.000000
L 4.3404002 3.81333307 4.34226644 3.81499941 1 P 0 ;0,1=68,2=0.000000
L 4.34226644 3.81499941 4.3436 3.81791624 1 P 0 ;0,1=68,2=0.000000
L 4.3436 3.81791624 4.34386663 3.82124961 1 P 0 ;0,1=68,2=0.000000
L 4.34386663 3.82124961 4.34333337 3.82458297 1 P 0 ;0,1=68,2=0.000000
L 4.34333337 3.82458297 4.3419998 3.82666663 1 P 0 ;0,1=68,2=0.000000
L 4.3419998 3.82666663 4.34013307 3.82833297 1 P 0 ;0,1=68,2=0.000000
L 4.34013307 3.82833297 4.33826683 3.82874951 1 P 0 ;0,1=68,2=0.000000
L 4.33826683 3.82874951 4.3364 3.82833297 1 P 0 ;0,1=68,2=0.000000
L 4.3364 3.82833297 4.3340001 3.82666663 1 P 0 ;0,1=68,2=0.000000
L 4.3340001 3.82666663 4.3347999 3.8375 1 P 0 ;0,1=68,2=0.000000
L 4.3347999 3.8375 4.3419998 3.8375 1 P 0 ;0,1=68,2=0.000000
L 0.55349961 3.0255 0.55349961 2.9945 1 P 0 ;0,1=69,2=0.000000
L 0.54468337 3.0255 0.56231654 3.0255 1 P 0 ;0,1=69,2=0.000000
L 0.57683317 2.9945 0.57683317 3.0255 1 P 0 ;0,1=69,2=0.000000
L 0.57683317 3.0255 0.58603327 3.0255 1 P 0 ;0,1=69,2=0.000000
L 0.58603327 3.0255 0.5891 3.02394931 1 P 0 ;0,1=69,2=0.000000
L 0.5891 3.02394931 0.5914002 3.02033346 1 P 0 ;0,1=69,2=0.000000
L 0.5914002 3.02033346 0.59216673 3.0162 1 P 0 ;0,1=69,2=0.000000
L 0.59216673 3.0162 0.5914002 3.01206663 1 P 0 ;0,1=69,2=0.000000
L 0.5914002 3.01206663 0.58948327 3.00896634 1 P 0 ;0,1=69,2=0.000000
L 0.58948327 3.00896634 0.58603327 3.00741575 1 P 0 ;0,1=69,2=0.000000
L 0.58603327 3.00741575 0.57683317 3.00741575 1 P 0 ;0,1=69,2=0.000000
L 0.60821644 3.02033346 0.61051663 3.02343278 1 P 0 ;0,1=69,2=0.000000
L 0.61051663 3.02343278 0.6132001 3.02498337 1 P 0 ;0,1=69,2=0.000000
L 0.6132001 3.02498337 0.61626683 3.0255 1 P 0 ;0,1=69,2=0.000000
L 0.61626683 3.0255 0.6201 3.02446683 1 P 0 ;0,1=69,2=0.000000
L 0.6201 3.02446683 0.62278346 3.02188307 1 P 0 ;0,1=69,2=0.000000
L 0.62278346 3.02188307 0.62355 3.01878376 1 P 0 ;0,1=69,2=0.000000
L 0.62355 3.01878376 0.62316673 3.01568258 1 P 0 ;0,1=69,2=0.000000
L 0.62316673 3.01568258 0.62163307 3.0130998 1 P 0 ;0,1=69,2=0.000000
L 0.62163307 3.0130998 0.61396663 3.00793327 1 P 0 ;0,1=69,2=0.000000
L 0.61396663 3.00793327 0.61051663 3.00431644 1 P 0 ;0,1=69,2=0.000000
L 0.61051663 3.00431644 0.60821644 2.99914892 1 P 0 ;0,1=69,2=0.000000
L 0.60821644 2.99914892 0.6074499 2.9945 1 P 0 ;0,1=69,2=0.000000
L 0.6074499 2.9945 0.62355 2.9945 1 P 0 ;0,1=69,2=0.000000
L 0.6511 2.9945 0.6511 3.0255 1 P 0 ;0,1=69,2=0.000000
L 0.6511 3.0255 0.63691624 3.00328327 1 P 0 ;0,1=69,2=0.000000
L 0.63691624 3.00328327 0.65608366 3.00328327 1 P 0 ;0,1=69,2=0.000000
L 1.9995 3.32349961 2.0305 3.32349961 1 P 0 ;0,1=70,2=270.000000
L 1.9995 3.31468337 1.9995 3.33231654 1 P 0 ;0,1=70,2=270.000000
L 2.0305 3.34683317 1.9995 3.34683317 1 P 0 ;0,1=70,2=270.000000
L 1.9995 3.34683317 1.9995 3.35603327 1 P 0 ;0,1=70,2=270.000000
L 1.9995 3.35603327 2.00105069 3.3591 1 P 0 ;0,1=70,2=270.000000
L 2.00105069 3.3591 2.00466654 3.3614002 1 P 0 ;0,1=70,2=270.000000
L 2.00466654 3.3614002 2.0088 3.36216673 1 P 0 ;0,1=70,2=270.000000
L 2.0088 3.36216673 2.01293337 3.3614002 1 P 0 ;0,1=70,2=270.000000
L 2.01293337 3.3614002 2.01603366 3.35948327 1 P 0 ;0,1=70,2=270.000000
L 2.01603366 3.35948327 2.01758425 3.35603327 1 P 0 ;0,1=70,2=270.000000
L 2.01758425 3.35603327 2.01758425 3.34683317 1 P 0 ;0,1=70,2=270.000000
L 2.00466654 3.37821644 2.00156722 3.38051663 1 P 0 ;0,1=70,2=270.000000
L 2.00156722 3.38051663 2.00001663 3.3832001 1 P 0 ;0,1=70,2=270.000000
L 2.00001663 3.3832001 1.9995 3.38626683 1 P 0 ;0,1=70,2=270.000000
L 1.9995 3.38626683 2.00053317 3.3901 1 P 0 ;0,1=70,2=270.000000
L 2.00053317 3.3901 2.00311693 3.39278346 1 P 0 ;0,1=70,2=270.000000
L 2.00311693 3.39278346 2.00621624 3.39355 1 P 0 ;0,1=70,2=270.000000
L 2.00621624 3.39355 2.00931742 3.39316673 1 P 0 ;0,1=70,2=270.000000
L 2.00931742 3.39316673 2.0119002 3.39163307 1 P 0 ;0,1=70,2=270.000000
L 2.0119002 3.39163307 2.01706673 3.38396663 1 P 0 ;0,1=70,2=270.000000
L 2.01706673 3.38396663 2.02068356 3.38051663 1 P 0 ;0,1=70,2=270.000000
L 2.02068356 3.38051663 2.02585108 3.37821644 1 P 0 ;0,1=70,2=270.000000
L 2.02585108 3.37821644 2.0305 3.3774499 1 P 0 ;0,1=70,2=270.000000
L 2.0305 3.3774499 2.0305 3.39355 1 P 0 ;0,1=70,2=270.000000
L 2.02430039 3.40806663 2.02791722 3.41036614 1 P 0 ;0,1=70,2=270.000000
L 2.02791722 3.41036614 2.02998346 3.41343287 1 P 0 ;0,1=70,2=270.000000
L 2.02998346 3.41343287 2.0305 3.41688356 1 P 0 ;0,1=70,2=270.000000
L 2.0305 3.41688356 2.02998346 3.4199503 1 P 0 ;0,1=70,2=270.000000
L 2.02998346 3.4199503 2.02740069 3.42301703 1 P 0 ;0,1=70,2=270.000000
L 2.02740069 3.42301703 2.02430039 3.42493327 1 P 0 ;0,1=70,2=270.000000
L 2.02430039 3.42493327 2.0212001 3.42531654 1 P 0 ;0,1=70,2=270.000000
L 2.0212001 3.42531654 2.01758425 3.42455 1 P 0 ;0,1=70,2=270.000000
L 2.01758425 3.42455 2.01500049 3.42186654 1 P 0 ;0,1=70,2=270.000000
L 2.01500049 3.42186654 2.01396644 3.41918307 1 P 0 ;0,1=70,2=270.000000
L 2.01396644 3.41918307 2.01396644 3.41573307 1 P 0 ;0,1=70,2=270.000000
L 2.01396644 3.41918307 2.01241683 3.42148327 1 P 0 ;0,1=70,2=270.000000
L 2.01241683 3.42148327 2.00983406 3.4234002 1 P 0 ;0,1=70,2=270.000000
L 2.00983406 3.4234002 2.00673376 3.42416673 1 P 0 ;0,1=70,2=270.000000
L 2.00673376 3.42416673 2.00363346 3.4234002 1 P 0 ;0,1=70,2=270.000000
L 2.00363346 3.4234002 2.00105069 3.42148327 1 P 0 ;0,1=70,2=270.000000
L 2.00105069 3.42148327 1.9995 3.41803327 1 P 0 ;0,1=70,2=270.000000
L 1.9995 3.41803327 2.00001663 3.41458337 1 P 0 ;0,1=70,2=270.000000
L 2.00001663 3.41458337 2.00208376 3.41113337 1 P 0 ;0,1=70,2=270.000000
L 5.74349961 1.0955 5.74349961 1.0645 1 P 0 ;0,1=71,2=0.000000
L 5.73468337 1.0955 5.75231654 1.0955 1 P 0 ;0,1=71,2=0.000000
L 5.76683317 1.0645 5.76683317 1.0955 1 P 0 ;0,1=71,2=0.000000
L 5.76683317 1.0955 5.77603327 1.0955 1 P 0 ;0,1=71,2=0.000000
L 5.77603327 1.0955 5.7791 1.09394931 1 P 0 ;0,1=71,2=0.000000
L 5.7791 1.09394931 5.7814002 1.09033346 1 P 0 ;0,1=71,2=0.000000
L 5.7814002 1.09033346 5.78216673 1.0862 1 P 0 ;0,1=71,2=0.000000
L 5.78216673 1.0862 5.7814002 1.08206663 1 P 0 ;0,1=71,2=0.000000
L 5.7814002 1.08206663 5.77948327 1.07896634 1 P 0 ;0,1=71,2=0.000000
L 5.77948327 1.07896634 5.77603327 1.07741575 1 P 0 ;0,1=71,2=0.000000
L 5.77603327 1.07741575 5.76683317 1.07741575 1 P 0 ;0,1=71,2=0.000000
L 5.79821644 1.09033346 5.80051663 1.09343278 1 P 0 ;0,1=71,2=0.000000
L 5.80051663 1.09343278 5.8032001 1.09498337 1 P 0 ;0,1=71,2=0.000000
L 5.8032001 1.09498337 5.80626683 1.0955 1 P 0 ;0,1=71,2=0.000000
L 5.80626683 1.0955 5.8101 1.09446683 1 P 0 ;0,1=71,2=0.000000
L 5.8101 1.09446683 5.81278346 1.09188307 1 P 0 ;0,1=71,2=0.000000
L 5.81278346 1.09188307 5.81355 1.08878376 1 P 0 ;0,1=71,2=0.000000
L 5.81355 1.08878376 5.81316673 1.08568258 1 P 0 ;0,1=71,2=0.000000
L 5.81316673 1.08568258 5.81163307 1.0830998 1 P 0 ;0,1=71,2=0.000000
L 5.81163307 1.0830998 5.80396663 1.07793327 1 P 0 ;0,1=71,2=0.000000
L 5.80396663 1.07793327 5.80051663 1.07431644 1 P 0 ;0,1=71,2=0.000000
L 5.80051663 1.07431644 5.79821644 1.06914892 1 P 0 ;0,1=71,2=0.000000
L 5.79821644 1.06914892 5.7974499 1.0645 1 P 0 ;0,1=71,2=0.000000
L 5.7974499 1.0645 5.81355 1.0645 1 P 0 ;0,1=71,2=0.000000
L 5.82921644 1.09033346 5.83151663 1.09343278 1 P 0 ;0,1=71,2=0.000000
L 5.83151663 1.09343278 5.8342001 1.09498337 1 P 0 ;0,1=71,2=0.000000
L 5.8342001 1.09498337 5.83726683 1.0955 1 P 0 ;0,1=71,2=0.000000
L 5.83726683 1.0955 5.8411 1.09446683 1 P 0 ;0,1=71,2=0.000000
L 5.8411 1.09446683 5.84378346 1.09188307 1 P 0 ;0,1=71,2=0.000000
L 5.84378346 1.09188307 5.84455 1.08878376 1 P 0 ;0,1=71,2=0.000000
L 5.84455 1.08878376 5.84416673 1.08568258 1 P 0 ;0,1=71,2=0.000000
L 5.84416673 1.08568258 5.84263307 1.0830998 1 P 0 ;0,1=71,2=0.000000
L 5.84263307 1.0830998 5.83496663 1.07793327 1 P 0 ;0,1=71,2=0.000000
L 5.83496663 1.07793327 5.83151663 1.07431644 1 P 0 ;0,1=71,2=0.000000
L 5.83151663 1.07431644 5.82921644 1.06914892 1 P 0 ;0,1=71,2=0.000000
L 5.82921644 1.06914892 5.8284499 1.0645 1 P 0 ;0,1=71,2=0.000000
L 5.8284499 1.0645 5.84455 1.0645 1 P 0 ;0,1=71,2=0.000000
L 3.33349961 3.5205 3.33349961 3.4895 1 P 0 ;0,1=72,2=0.000000
L 3.32468337 3.5205 3.34231654 3.5205 1 P 0 ;0,1=72,2=0.000000
L 3.35683317 3.4895 3.35683317 3.5205 1 P 0 ;0,1=72,2=0.000000
L 3.35683317 3.5205 3.36603327 3.5205 1 P 0 ;0,1=72,2=0.000000
L 3.36603327 3.5205 3.3691 3.51894931 1 P 0 ;0,1=72,2=0.000000
L 3.3691 3.51894931 3.3714002 3.51533346 1 P 0 ;0,1=72,2=0.000000
L 3.3714002 3.51533346 3.37216673 3.5112 1 P 0 ;0,1=72,2=0.000000
L 3.37216673 3.5112 3.3714002 3.50706663 1 P 0 ;0,1=72,2=0.000000
L 3.3714002 3.50706663 3.36948327 3.50396634 1 P 0 ;0,1=72,2=0.000000
L 3.36948327 3.50396634 3.36603327 3.50241575 1 P 0 ;0,1=72,2=0.000000
L 3.36603327 3.50241575 3.35683317 3.50241575 1 P 0 ;0,1=72,2=0.000000
L 3.38821644 3.51533346 3.39051663 3.51843278 1 P 0 ;0,1=72,2=0.000000
L 3.39051663 3.51843278 3.3932001 3.51998337 1 P 0 ;0,1=72,2=0.000000
L 3.3932001 3.51998337 3.39626683 3.5205 1 P 0 ;0,1=72,2=0.000000
L 3.39626683 3.5205 3.4001 3.51946683 1 P 0 ;0,1=72,2=0.000000
L 3.4001 3.51946683 3.40278346 3.51688307 1 P 0 ;0,1=72,2=0.000000
L 3.40278346 3.51688307 3.40355 3.51378376 1 P 0 ;0,1=72,2=0.000000
L 3.40355 3.51378376 3.40316673 3.51068258 1 P 0 ;0,1=72,2=0.000000
L 3.40316673 3.51068258 3.40163307 3.5080998 1 P 0 ;0,1=72,2=0.000000
L 3.40163307 3.5080998 3.39396663 3.50293327 1 P 0 ;0,1=72,2=0.000000
L 3.39396663 3.50293327 3.39051663 3.49931644 1 P 0 ;0,1=72,2=0.000000
L 3.39051663 3.49931644 3.38821644 3.49414892 1 P 0 ;0,1=72,2=0.000000
L 3.38821644 3.49414892 3.3874499 3.4895 1 P 0 ;0,1=72,2=0.000000
L 3.3874499 3.4895 3.40355 3.4895 1 P 0 ;0,1=72,2=0.000000
L 3.42649961 3.4895 3.42649961 3.5205 1 P 0 ;0,1=72,2=0.000000
L 3.42649961 3.5205 3.4218999 3.5143003 1 P 0 ;0,1=72,2=0.000000
L 3.4218999 3.4895 3.43109931 3.4895 1 P 0 ;0,1=72,2=0.000000
L 0.7999997 0.5995 0.7999997 0.5745 1 P 0 ;0,1=73,2=0.000000
L 0.79386673 0.5995 0.80613317 0.5995 1 P 0 ;0,1=73,2=0.000000
L 0.81666654 0.5745 0.81666654 0.5995 1 P 0 ;0,1=73,2=0.000000
L 0.81666654 0.5995 0.82306663 0.5995 1 P 0 ;0,1=73,2=0.000000
L 0.82306663 0.5995 0.8252 0.59824941 1 P 0 ;0,1=73,2=0.000000
L 0.8252 0.59824941 0.8268001 0.59533337 1 P 0 ;0,1=73,2=0.000000
L 0.8268001 0.59533337 0.82733337 0.592 1 P 0 ;0,1=73,2=0.000000
L 0.82733337 0.592 0.8268001 0.58866663 1 P 0 ;0,1=73,2=0.000000
L 0.8268001 0.58866663 0.82546663 0.58616644 1 P 0 ;0,1=73,2=0.000000
L 0.82546663 0.58616644 0.82306663 0.58491594 1 P 0 ;0,1=73,2=0.000000
L 0.82306663 0.58491594 0.81666654 0.58491594 1 P 0 ;0,1=73,2=0.000000
L 0.83893317 0.59533337 0.84053327 0.59783287 1 P 0 ;0,1=73,2=0.000000
L 0.84053327 0.59783287 0.8424 0.59908337 1 P 0 ;0,1=73,2=0.000000
L 0.8424 0.59908337 0.84453337 0.5995 1 P 0 ;0,1=73,2=0.000000
L 0.84453337 0.5995 0.8472 0.59866683 1 P 0 ;0,1=73,2=0.000000
L 0.8472 0.59866683 0.84906673 0.59658317 1 P 0 ;0,1=73,2=0.000000
L 0.84906673 0.59658317 0.8496 0.59408366 1 P 0 ;0,1=73,2=0.000000
L 0.8496 0.59408366 0.84933337 0.59158268 1 P 0 ;0,1=73,2=0.000000
L 0.84933337 0.59158268 0.84826644 0.5894998 1 P 0 ;0,1=73,2=0.000000
L 0.84826644 0.5894998 0.84293327 0.58533327 1 P 0 ;0,1=73,2=0.000000
L 0.84293327 0.58533327 0.84053327 0.58241644 1 P 0 ;0,1=73,2=0.000000
L 0.84053327 0.58241644 0.83893317 0.57824911 1 P 0 ;0,1=73,2=0.000000
L 0.83893317 0.57824911 0.8383999 0.5745 1 P 0 ;0,1=73,2=0.000000
L 0.8383999 0.5745 0.8496 0.5745 1 P 0 ;0,1=73,2=0.000000
L 0.8659997 0.5995 0.86386634 0.59866683 1 P 0 ;0,1=73,2=0.000000
L 0.86386634 0.59866683 0.86226663 0.59658317 1 P 0 ;0,1=73,2=0.000000
L 0.86226663 0.59658317 0.8611998 0.59408366 1 P 0 ;0,1=73,2=0.000000
L 0.8611998 0.59408366 0.8603999 0.59074951 1 P 0 ;0,1=73,2=0.000000
L 0.8603999 0.59074951 0.86013327 0.58699961 1 P 0 ;0,1=73,2=0.000000
L 0.86013327 0.58699961 0.8603999 0.58324961 1 P 0 ;0,1=73,2=0.000000
L 0.8603999 0.58324961 0.8611998 0.57991624 1 P 0 ;0,1=73,2=0.000000
L 0.8611998 0.57991624 0.86226663 0.57741604 1 P 0 ;0,1=73,2=0.000000
L 0.86226663 0.57741604 0.86386634 0.57533307 1 P 0 ;0,1=73,2=0.000000
L 0.86386634 0.57533307 0.8659997 0.5745 1 P 0 ;0,1=73,2=0.000000
L 0.8659997 0.5745 0.86813307 0.57533307 1 P 0 ;0,1=73,2=0.000000
L 0.86813307 0.57533307 0.86973327 0.57741604 1 P 0 ;0,1=73,2=0.000000
L 0.86973327 0.57741604 0.8708001 0.57991624 1 P 0 ;0,1=73,2=0.000000
L 0.8708001 0.57991624 0.8716 0.58324961 1 P 0 ;0,1=73,2=0.000000
L 0.8716 0.58324961 0.87186663 0.58699961 1 P 0 ;0,1=73,2=0.000000
L 0.87186663 0.58699961 0.8716 0.59074951 1 P 0 ;0,1=73,2=0.000000
L 0.8716 0.59074951 0.8708001 0.59408366 1 P 0 ;0,1=73,2=0.000000
L 0.8708001 0.59408366 0.86973327 0.59658317 1 P 0 ;0,1=73,2=0.000000
L 0.86973327 0.59658317 0.86813307 0.59866683 1 P 0 ;0,1=73,2=0.000000
L 0.86813307 0.59866683 0.8659997 0.5995 1 P 0 ;0,1=73,2=0.000000
L 3.4219997 2.6975 3.4219997 2.6725 1 P 0 ;0,1=74,2=0.000000
L 3.41586673 2.6975 3.42813317 2.6975 1 P 0 ;0,1=74,2=0.000000
L 3.43866654 2.6725 3.43866654 2.6975 1 P 0 ;0,1=74,2=0.000000
L 3.43866654 2.6975 3.44506663 2.6975 1 P 0 ;0,1=74,2=0.000000
L 3.44506663 2.6975 3.4472 2.69624941 1 P 0 ;0,1=74,2=0.000000
L 3.4472 2.69624941 3.4488001 2.69333337 1 P 0 ;0,1=74,2=0.000000
L 3.4488001 2.69333337 3.44933337 2.69 1 P 0 ;0,1=74,2=0.000000
L 3.44933337 2.69 3.4488001 2.68666663 1 P 0 ;0,1=74,2=0.000000
L 3.4488001 2.68666663 3.44746663 2.68416644 1 P 0 ;0,1=74,2=0.000000
L 3.44746663 2.68416644 3.44506663 2.68291594 1 P 0 ;0,1=74,2=0.000000
L 3.44506663 2.68291594 3.43866654 2.68291594 1 P 0 ;0,1=74,2=0.000000
L 3.4659997 2.6725 3.4659997 2.6975 1 P 0 ;0,1=74,2=0.000000
L 3.4659997 2.6975 3.4627999 2.6925003 1 P 0 ;0,1=74,2=0.000000
L 3.4627999 2.6725 3.46919951 2.6725 1 P 0 ;0,1=74,2=0.000000
L 3.48346634 2.67541604 3.48533317 2.67333307 1 P 0 ;0,1=74,2=0.000000
L 3.48533317 2.67333307 3.48746654 2.6725 1 P 0 ;0,1=74,2=0.000000
L 3.48746654 2.6725 3.4895999 2.67333307 1 P 0 ;0,1=74,2=0.000000
L 3.4895999 2.67333307 3.49146663 2.67583258 1 P 0 ;0,1=74,2=0.000000
L 3.49146663 2.67583258 3.4928001 2.67958327 1 P 0 ;0,1=74,2=0.000000
L 3.4928001 2.67958327 3.49333337 2.68333327 1 P 0 ;0,1=74,2=0.000000
L 3.49333337 2.68333327 3.49333337 2.68791634 1 P 0 ;0,1=74,2=0.000000
L 3.49333337 2.68791634 3.4928001 2.69166634 1 P 0 ;0,1=74,2=0.000000
L 3.4928001 2.69166634 3.49146663 2.6949997 1 P 0 ;0,1=74,2=0.000000
L 3.49146663 2.6949997 3.48986644 2.69666683 1 P 0 ;0,1=74,2=0.000000
L 3.48986644 2.69666683 3.4879997 2.6975 1 P 0 ;0,1=74,2=0.000000
L 3.4879997 2.6975 3.48586634 2.69666683 1 P 0 ;0,1=74,2=0.000000
L 3.48586634 2.69666683 3.48426663 2.6949997 1 P 0 ;0,1=74,2=0.000000
L 3.48426663 2.6949997 3.4831998 2.6925003 1 P 0 ;0,1=74,2=0.000000
L 3.4831998 2.6925003 3.48266654 2.68916614 1 P 0 ;0,1=74,2=0.000000
L 3.48266654 2.68916614 3.4831998 2.6862501 1 P 0 ;0,1=74,2=0.000000
L 3.4831998 2.6862501 3.48453327 2.68333327 1 P 0 ;0,1=74,2=0.000000
L 3.48453327 2.68333327 3.48613346 2.68166614 1 P 0 ;0,1=74,2=0.000000
L 3.48613346 2.68166614 3.4879997 2.68124961 1 P 0 ;0,1=74,2=0.000000
L 3.4879997 2.68124961 3.49013307 2.68208278 1 P 0 ;0,1=74,2=0.000000
L 3.49013307 2.68208278 3.49173327 2.68416644 1 P 0 ;0,1=74,2=0.000000
L 3.49173327 2.68416644 3.49333337 2.68791634 1 P 0 ;0,1=74,2=0.000000
L 3.3319997 2.6975 3.3319997 2.6725 1 P 0 ;0,1=75,2=0.000000
L 3.32586673 2.6975 3.33813317 2.6975 1 P 0 ;0,1=75,2=0.000000
L 3.34866654 2.6725 3.34866654 2.6975 1 P 0 ;0,1=75,2=0.000000
L 3.34866654 2.6975 3.35506663 2.6975 1 P 0 ;0,1=75,2=0.000000
L 3.35506663 2.6975 3.3572 2.69624941 1 P 0 ;0,1=75,2=0.000000
L 3.3572 2.69624941 3.3588001 2.69333337 1 P 0 ;0,1=75,2=0.000000
L 3.3588001 2.69333337 3.35933337 2.69 1 P 0 ;0,1=75,2=0.000000
L 3.35933337 2.69 3.3588001 2.68666663 1 P 0 ;0,1=75,2=0.000000
L 3.3588001 2.68666663 3.35746663 2.68416644 1 P 0 ;0,1=75,2=0.000000
L 3.35746663 2.68416644 3.35506663 2.68291594 1 P 0 ;0,1=75,2=0.000000
L 3.35506663 2.68291594 3.34866654 2.68291594 1 P 0 ;0,1=75,2=0.000000
L 3.3759997 2.6725 3.3759997 2.6975 1 P 0 ;0,1=75,2=0.000000
L 3.3759997 2.6975 3.3727999 2.6925003 1 P 0 ;0,1=75,2=0.000000
L 3.3727999 2.6725 3.37919951 2.6725 1 P 0 ;0,1=75,2=0.000000
L 3.3979997 2.6725 3.39986644 2.67291654 1 P 0 ;0,1=75,2=0.000000
L 3.39986644 2.67291654 3.4019998 2.67416624 1 P 0 ;0,1=75,2=0.000000
L 3.4019998 2.67416624 3.40333337 2.67624911 1 P 0 ;0,1=75,2=0.000000
L 3.40333337 2.67624911 3.40386663 2.67916673 1 P 0 ;0,1=75,2=0.000000
L 3.40386663 2.67916673 3.40333337 2.68208278 1 P 0 ;0,1=75,2=0.000000
L 3.40333337 2.68208278 3.40173327 2.68458297 1 P 0 ;0,1=75,2=0.000000
L 3.40173327 2.68458297 3.39933327 2.68583346 1 P 0 ;0,1=75,2=0.000000
L 3.39933327 2.68583346 3.39666663 2.68583346 1 P 0 ;0,1=75,2=0.000000
L 3.39666663 2.68583346 3.39506654 2.68666663 1 P 0 ;0,1=75,2=0.000000
L 3.39506654 2.68666663 3.39373297 2.68874951 1 P 0 ;0,1=75,2=0.000000
L 3.39373297 2.68874951 3.3931998 2.69166634 1 P 0 ;0,1=75,2=0.000000
L 3.3931998 2.69166634 3.3940001 2.69458317 1 P 0 ;0,1=75,2=0.000000
L 3.3940001 2.69458317 3.39586634 2.69666683 1 P 0 ;0,1=75,2=0.000000
L 3.39586634 2.69666683 3.3979997 2.6975 1 P 0 ;0,1=75,2=0.000000
L 3.3979997 2.6975 3.40013307 2.69666683 1 P 0 ;0,1=75,2=0.000000
L 3.40013307 2.69666683 3.4019998 2.69458317 1 P 0 ;0,1=75,2=0.000000
L 3.4019998 2.69458317 3.4028001 2.69166634 1 P 0 ;0,1=75,2=0.000000
L 3.4028001 2.69166634 3.40226644 2.68874951 1 P 0 ;0,1=75,2=0.000000
L 3.40226644 2.68874951 3.40093337 2.68666663 1 P 0 ;0,1=75,2=0.000000
L 3.40093337 2.68666663 3.39933327 2.68583346 1 P 0 ;0,1=75,2=0.000000
L 3.39933327 2.68583346 3.39666663 2.68583346 1 P 0 ;0,1=75,2=0.000000
L 3.39666663 2.68583346 3.39426663 2.68458297 1 P 0 ;0,1=75,2=0.000000
L 3.39426663 2.68458297 3.39266654 2.68208278 1 P 0 ;0,1=75,2=0.000000
L 3.39266654 2.68208278 3.39213327 2.67916673 1 P 0 ;0,1=75,2=0.000000
L 3.39213327 2.67916673 3.39266654 2.67624911 1 P 0 ;0,1=75,2=0.000000
L 3.39266654 2.67624911 3.3940001 2.67416624 1 P 0 ;0,1=75,2=0.000000
L 3.3940001 2.67416624 3.39613346 2.67291654 1 P 0 ;0,1=75,2=0.000000
L 3.39613346 2.67291654 3.3979997 2.6725 1 P 0 ;0,1=75,2=0.000000
L 3.2419997 2.6975 3.2419997 2.6725 1 P 0 ;0,1=76,2=0.000000
L 3.23586673 2.6975 3.24813317 2.6975 1 P 0 ;0,1=76,2=0.000000
L 3.25866654 2.6725 3.25866654 2.6975 1 P 0 ;0,1=76,2=0.000000
L 3.25866654 2.6975 3.26506663 2.6975 1 P 0 ;0,1=76,2=0.000000
L 3.26506663 2.6975 3.2672 2.69624941 1 P 0 ;0,1=76,2=0.000000
L 3.2672 2.69624941 3.2688001 2.69333337 1 P 0 ;0,1=76,2=0.000000
L 3.2688001 2.69333337 3.26933337 2.69 1 P 0 ;0,1=76,2=0.000000
L 3.26933337 2.69 3.2688001 2.68666663 1 P 0 ;0,1=76,2=0.000000
L 3.2688001 2.68666663 3.26746663 2.68416644 1 P 0 ;0,1=76,2=0.000000
L 3.26746663 2.68416644 3.26506663 2.68291594 1 P 0 ;0,1=76,2=0.000000
L 3.26506663 2.68291594 3.25866654 2.68291594 1 P 0 ;0,1=76,2=0.000000
L 3.2859997 2.6725 3.2859997 2.6975 1 P 0 ;0,1=76,2=0.000000
L 3.2859997 2.6975 3.2827999 2.6925003 1 P 0 ;0,1=76,2=0.000000
L 3.2827999 2.6725 3.28919951 2.6725 1 P 0 ;0,1=76,2=0.000000
L 3.30746654 2.6725 3.3079997 2.67791624 1 P 0 ;0,1=76,2=0.000000
L 3.3079997 2.67791624 3.3088 2.68249931 1 P 0 ;0,1=76,2=0.000000
L 3.3088 2.68249931 3.30986644 2.68666663 1 P 0 ;0,1=76,2=0.000000
L 3.30986644 2.68666663 3.3112 2.6912498 1 P 0 ;0,1=76,2=0.000000
L 3.3112 2.6912498 3.31333337 2.6975 1 P 0 ;0,1=76,2=0.000000
L 3.31333337 2.6975 3.30266654 2.6975 1 P 0 ;0,1=76,2=0.000000
L 3.1519997 2.6725 3.1519997 2.6475 1 P 0 ;0,1=77,2=0.000000
L 3.14586673 2.6725 3.15813317 2.6725 1 P 0 ;0,1=77,2=0.000000
L 3.16866654 2.6475 3.16866654 2.6725 1 P 0 ;0,1=77,2=0.000000
L 3.16866654 2.6725 3.17506663 2.6725 1 P 0 ;0,1=77,2=0.000000
L 3.17506663 2.6725 3.1772 2.67124941 1 P 0 ;0,1=77,2=0.000000
L 3.1772 2.67124941 3.1788001 2.66833337 1 P 0 ;0,1=77,2=0.000000
L 3.1788001 2.66833337 3.17933337 2.665 1 P 0 ;0,1=77,2=0.000000
L 3.17933337 2.665 3.1788001 2.66166663 1 P 0 ;0,1=77,2=0.000000
L 3.1788001 2.66166663 3.17746663 2.65916644 1 P 0 ;0,1=77,2=0.000000
L 3.17746663 2.65916644 3.17506663 2.65791594 1 P 0 ;0,1=77,2=0.000000
L 3.17506663 2.65791594 3.16866654 2.65791594 1 P 0 ;0,1=77,2=0.000000
L 3.1959997 2.6475 3.1959997 2.6725 1 P 0 ;0,1=77,2=0.000000
L 3.1959997 2.6725 3.1927999 2.6675003 1 P 0 ;0,1=77,2=0.000000
L 3.1927999 2.6475 3.19919951 2.6475 1 P 0 ;0,1=77,2=0.000000
L 3.21293317 2.65791594 3.2147999 2.66083346 1 P 0 ;0,1=77,2=0.000000
L 3.2147999 2.66083346 3.2164 2.6624998 1 P 0 ;0,1=77,2=0.000000
L 3.2164 2.6624998 3.21853337 2.66333297 1 P 0 ;0,1=77,2=0.000000
L 3.21853337 2.66333297 3.2204002 2.6624998 1 P 0 ;0,1=77,2=0.000000
L 3.2204002 2.6624998 3.22173327 2.66083346 1 P 0 ;0,1=77,2=0.000000
L 3.22173327 2.66083346 3.2228001 2.65833327 1 P 0 ;0,1=77,2=0.000000
L 3.2228001 2.65833327 3.22306673 2.65541644 1 P 0 ;0,1=77,2=0.000000
L 3.22306673 2.65541644 3.2228001 2.65291624 1 P 0 ;0,1=77,2=0.000000
L 3.2228001 2.65291624 3.22173327 2.65041604 1 P 0 ;0,1=77,2=0.000000
L 3.22173327 2.65041604 3.22013307 2.64833307 1 P 0 ;0,1=77,2=0.000000
L 3.22013307 2.64833307 3.21826683 2.6475 1 P 0 ;0,1=77,2=0.000000
L 3.21826683 2.6475 3.21613346 2.64833307 1 P 0 ;0,1=77,2=0.000000
L 3.21613346 2.64833307 3.21426663 2.65083258 1 P 0 ;0,1=77,2=0.000000
L 3.21426663 2.65083258 3.2131998 2.65458327 1 P 0 ;0,1=77,2=0.000000
L 3.2131998 2.65458327 3.21293317 2.6587498 1 P 0 ;0,1=77,2=0.000000
L 3.21293317 2.6587498 3.21346634 2.66416614 1 P 0 ;0,1=77,2=0.000000
L 3.21346634 2.66416614 3.21426663 2.66708366 1 P 0 ;0,1=77,2=0.000000
L 3.21426663 2.66708366 3.2155997 2.6699997 1 P 0 ;0,1=77,2=0.000000
L 3.2155997 2.6699997 3.21746654 2.67208337 1 P 0 ;0,1=77,2=0.000000
L 3.21746654 2.67208337 3.21933327 2.6725 1 P 0 ;0,1=77,2=0.000000
L 3.21933327 2.6725 3.2212 2.67166683 1 P 0 ;0,1=77,2=0.000000
L 3.2212 2.67166683 3.22253356 2.66958317 1 P 0 ;0,1=77,2=0.000000
L 4.60349961 3.5205 4.60349961 3.4895 1 P 0 ;0,1=78,2=0.000000
L 4.59468337 3.5205 4.61231654 3.5205 1 P 0 ;0,1=78,2=0.000000
L 4.62683317 3.4895 4.62683317 3.5205 1 P 0 ;0,1=78,2=0.000000
L 4.62683317 3.5205 4.63603327 3.5205 1 P 0 ;0,1=78,2=0.000000
L 4.63603327 3.5205 4.6391 3.51894931 1 P 0 ;0,1=78,2=0.000000
L 4.6391 3.51894931 4.6414002 3.51533346 1 P 0 ;0,1=78,2=0.000000
L 4.6414002 3.51533346 4.64216673 3.5112 1 P 0 ;0,1=78,2=0.000000
L 4.64216673 3.5112 4.6414002 3.50706663 1 P 0 ;0,1=78,2=0.000000
L 4.6414002 3.50706663 4.63948327 3.50396634 1 P 0 ;0,1=78,2=0.000000
L 4.63948327 3.50396634 4.63603327 3.50241575 1 P 0 ;0,1=78,2=0.000000
L 4.63603327 3.50241575 4.62683317 3.50241575 1 P 0 ;0,1=78,2=0.000000
L 4.66549961 3.4895 4.66549961 3.5205 1 P 0 ;0,1=78,2=0.000000
L 4.66549961 3.5205 4.6608999 3.5143003 1 P 0 ;0,1=78,2=0.000000
L 4.6608999 3.4895 4.67009931 3.4895 1 P 0 ;0,1=78,2=0.000000
L 4.68806663 3.49414892 4.69036614 3.49156614 1 P 0 ;0,1=78,2=0.000000
L 4.69036614 3.49156614 4.69304961 3.49001654 1 P 0 ;0,1=78,2=0.000000
L 4.69304961 3.49001654 4.69649961 3.4895 1 P 0 ;0,1=78,2=0.000000
L 4.69649961 3.4895 4.6999503 3.49053307 1 P 0 ;0,1=78,2=0.000000
L 4.6999503 3.49053307 4.70263307 3.49259931 1 P 0 ;0,1=78,2=0.000000
L 4.70263307 3.49259931 4.70455 3.49621614 1 P 0 ;0,1=78,2=0.000000
L 4.70455 3.49621614 4.70493327 3.50034951 1 P 0 ;0,1=78,2=0.000000
L 4.70493327 3.50034951 4.70416673 3.50448287 1 P 0 ;0,1=78,2=0.000000
L 4.70416673 3.50448287 4.7022498 3.50706663 1 P 0 ;0,1=78,2=0.000000
L 4.7022498 3.50706663 4.69956634 3.50913287 1 P 0 ;0,1=78,2=0.000000
L 4.69956634 3.50913287 4.69688356 3.50964941 1 P 0 ;0,1=78,2=0.000000
L 4.69688356 3.50964941 4.6942001 3.50913287 1 P 0 ;0,1=78,2=0.000000
L 4.6942001 3.50913287 4.6907501 3.50706663 1 P 0 ;0,1=78,2=0.000000
L 4.6907501 3.50706663 4.6918999 3.5205 1 P 0 ;0,1=78,2=0.000000
L 4.6918999 3.5205 4.7022498 3.5205 1 P 0 ;0,1=78,2=0.000000
L 3.9169997 3.8875 3.9169997 3.8625 1 P 0 ;0,1=79,2=0.000000
L 3.91086673 3.8875 3.92313317 3.8875 1 P 0 ;0,1=79,2=0.000000
L 3.93366654 3.8625 3.93366654 3.8875 1 P 0 ;0,1=79,2=0.000000
L 3.93366654 3.8875 3.94006663 3.8875 1 P 0 ;0,1=79,2=0.000000
L 3.94006663 3.8875 3.9422 3.88624941 1 P 0 ;0,1=79,2=0.000000
L 3.9422 3.88624941 3.9438001 3.88333337 1 P 0 ;0,1=79,2=0.000000
L 3.9438001 3.88333337 3.94433337 3.88 1 P 0 ;0,1=79,2=0.000000
L 3.94433337 3.88 3.9438001 3.87666663 1 P 0 ;0,1=79,2=0.000000
L 3.9438001 3.87666663 3.94246663 3.87416644 1 P 0 ;0,1=79,2=0.000000
L 3.94246663 3.87416644 3.94006663 3.87291594 1 P 0 ;0,1=79,2=0.000000
L 3.94006663 3.87291594 3.93366654 3.87291594 1 P 0 ;0,1=79,2=0.000000
L 3.9609997 3.8625 3.9609997 3.8875 1 P 0 ;0,1=79,2=0.000000
L 3.9609997 3.8875 3.9577999 3.8825003 1 P 0 ;0,1=79,2=0.000000
L 3.9577999 3.8625 3.96419951 3.8625 1 P 0 ;0,1=79,2=0.000000
L 3.9862 3.8625 3.9862 3.8875 1 P 0 ;0,1=79,2=0.000000
L 3.9862 3.8875 3.97633297 3.86958327 1 P 0 ;0,1=79,2=0.000000
L 3.97633297 3.86958327 3.98966693 3.86958327 1 P 0 ;0,1=79,2=0.000000
L 4.06349961 3.3405 4.06349961 3.3095 1 P 0 ;0,1=80,2=0.000000
L 4.05468337 3.3405 4.07231654 3.3405 1 P 0 ;0,1=80,2=0.000000
L 4.08683317 3.3095 4.08683317 3.3405 1 P 0 ;0,1=80,2=0.000000
L 4.08683317 3.3405 4.09603327 3.3405 1 P 0 ;0,1=80,2=0.000000
L 4.09603327 3.3405 4.0991 3.33894931 1 P 0 ;0,1=80,2=0.000000
L 4.0991 3.33894931 4.1014002 3.33533346 1 P 0 ;0,1=80,2=0.000000
L 4.1014002 3.33533346 4.10216673 3.3312 1 P 0 ;0,1=80,2=0.000000
L 4.10216673 3.3312 4.1014002 3.32706663 1 P 0 ;0,1=80,2=0.000000
L 4.1014002 3.32706663 4.09948327 3.32396634 1 P 0 ;0,1=80,2=0.000000
L 4.09948327 3.32396634 4.09603327 3.32241575 1 P 0 ;0,1=80,2=0.000000
L 4.09603327 3.32241575 4.08683317 3.32241575 1 P 0 ;0,1=80,2=0.000000
L 4.12549961 3.3095 4.12549961 3.3405 1 P 0 ;0,1=80,2=0.000000
L 4.12549961 3.3405 4.1208999 3.3343003 1 P 0 ;0,1=80,2=0.000000
L 4.1208999 3.3095 4.13009931 3.3095 1 P 0 ;0,1=80,2=0.000000
L 4.14806663 3.31569961 4.15036614 3.31208278 1 P 0 ;0,1=80,2=0.000000
L 4.15036614 3.31208278 4.15343287 3.31001654 1 P 0 ;0,1=80,2=0.000000
L 4.15343287 3.31001654 4.15688356 3.3095 1 P 0 ;0,1=80,2=0.000000
L 4.15688356 3.3095 4.1599503 3.31001654 1 P 0 ;0,1=80,2=0.000000
L 4.1599503 3.31001654 4.16301703 3.31259931 1 P 0 ;0,1=80,2=0.000000
L 4.16301703 3.31259931 4.16493327 3.31569961 1 P 0 ;0,1=80,2=0.000000
L 4.16493327 3.31569961 4.16531654 3.3187999 1 P 0 ;0,1=80,2=0.000000
L 4.16531654 3.3187999 4.16455 3.32241575 1 P 0 ;0,1=80,2=0.000000
L 4.16455 3.32241575 4.16186654 3.32499951 1 P 0 ;0,1=80,2=0.000000
L 4.16186654 3.32499951 4.15918307 3.32603356 1 P 0 ;0,1=80,2=0.000000
L 4.15918307 3.32603356 4.15573307 3.32603356 1 P 0 ;0,1=80,2=0.000000
L 4.15918307 3.32603356 4.16148327 3.32758317 1 P 0 ;0,1=80,2=0.000000
L 4.16148327 3.32758317 4.1634002 3.33016594 1 P 0 ;0,1=80,2=0.000000
L 4.1634002 3.33016594 4.16416673 3.33326624 1 P 0 ;0,1=80,2=0.000000
L 4.16416673 3.33326624 4.1634002 3.33636654 1 P 0 ;0,1=80,2=0.000000
L 4.1634002 3.33636654 4.16148327 3.33894931 1 P 0 ;0,1=80,2=0.000000
L 4.16148327 3.33894931 4.15803327 3.3405 1 P 0 ;0,1=80,2=0.000000
L 4.15803327 3.3405 4.15458337 3.33998337 1 P 0 ;0,1=80,2=0.000000
L 4.15458337 3.33998337 4.15113337 3.33791624 1 P 0 ;0,1=80,2=0.000000
L 4.7949997 1.0045 4.7949997 0.9795 1 P 0 ;0,1=81,2=0.000000
L 4.78886673 1.0045 4.80113317 1.0045 1 P 0 ;0,1=81,2=0.000000
L 4.81166654 0.9795 4.81166654 1.0045 1 P 0 ;0,1=81,2=0.000000
L 4.81166654 1.0045 4.81806663 1.0045 1 P 0 ;0,1=81,2=0.000000
L 4.81806663 1.0045 4.8202 1.00324941 1 P 0 ;0,1=81,2=0.000000
L 4.8202 1.00324941 4.8218001 1.00033337 1 P 0 ;0,1=81,2=0.000000
L 4.8218001 1.00033337 4.82233337 0.997 1 P 0 ;0,1=81,2=0.000000
L 4.82233337 0.997 4.8218001 0.99366663 1 P 0 ;0,1=81,2=0.000000
L 4.8218001 0.99366663 4.82046663 0.99116644 1 P 0 ;0,1=81,2=0.000000
L 4.82046663 0.99116644 4.81806663 0.98991594 1 P 0 ;0,1=81,2=0.000000
L 4.81806663 0.98991594 4.81166654 0.98991594 1 P 0 ;0,1=81,2=0.000000
L 4.8389997 0.9795 4.8389997 1.0045 1 P 0 ;0,1=81,2=0.000000
L 4.8389997 1.0045 4.8357999 0.9995003 1 P 0 ;0,1=81,2=0.000000
L 4.8357999 0.9795 4.84219951 0.9795 1 P 0 ;0,1=81,2=0.000000
L 4.85593317 1.00033337 4.85753327 1.00283287 1 P 0 ;0,1=81,2=0.000000
L 4.85753327 1.00283287 4.8594 1.00408337 1 P 0 ;0,1=81,2=0.000000
L 4.8594 1.00408337 4.86153337 1.0045 1 P 0 ;0,1=81,2=0.000000
L 4.86153337 1.0045 4.8642 1.00366683 1 P 0 ;0,1=81,2=0.000000
L 4.8642 1.00366683 4.86606673 1.00158317 1 P 0 ;0,1=81,2=0.000000
L 4.86606673 1.00158317 4.8666 0.99908366 1 P 0 ;0,1=81,2=0.000000
L 4.8666 0.99908366 4.86633337 0.99658268 1 P 0 ;0,1=81,2=0.000000
L 4.86633337 0.99658268 4.86526644 0.9944998 1 P 0 ;0,1=81,2=0.000000
L 4.86526644 0.9944998 4.85993327 0.99033327 1 P 0 ;0,1=81,2=0.000000
L 4.85993327 0.99033327 4.85753327 0.98741644 1 P 0 ;0,1=81,2=0.000000
L 4.85753327 0.98741644 4.85593317 0.98324911 1 P 0 ;0,1=81,2=0.000000
L 4.85593317 0.98324911 4.8553999 0.9795 1 P 0 ;0,1=81,2=0.000000
L 4.8553999 0.9795 4.8666 0.9795 1 P 0 ;0,1=81,2=0.000000
L 0.9745 3.74349961 1.0055 3.74349961 1 P 0 ;0,1=82,2=270.000000
L 0.9745 3.73468337 0.9745 3.75231654 1 P 0 ;0,1=82,2=270.000000
L 1.0055 3.76683317 0.9745 3.76683317 1 P 0 ;0,1=82,2=270.000000
L 0.9745 3.76683317 0.9745 3.77603327 1 P 0 ;0,1=82,2=270.000000
L 0.9745 3.77603327 0.97605069 3.7791 1 P 0 ;0,1=82,2=270.000000
L 0.97605069 3.7791 0.97966654 3.7814002 1 P 0 ;0,1=82,2=270.000000
L 0.97966654 3.7814002 0.9838 3.78216673 1 P 0 ;0,1=82,2=270.000000
L 0.9838 3.78216673 0.98793337 3.7814002 1 P 0 ;0,1=82,2=270.000000
L 0.98793337 3.7814002 0.99103366 3.77948327 1 P 0 ;0,1=82,2=270.000000
L 0.99103366 3.77948327 0.99258425 3.77603327 1 P 0 ;0,1=82,2=270.000000
L 0.99258425 3.77603327 0.99258425 3.76683317 1 P 0 ;0,1=82,2=270.000000
L 1.0055 3.80549961 0.9745 3.80549961 1 P 0 ;0,1=82,2=270.000000
L 0.9745 3.80549961 0.9806997 3.8008999 1 P 0 ;0,1=82,2=270.000000
L 1.0055 3.8008999 1.0055 3.81009931 1 P 0 ;0,1=82,2=270.000000
L 1.0055 3.83649961 0.9745 3.83649961 1 P 0 ;0,1=82,2=270.000000
L 0.9745 3.83649961 0.9806997 3.8318999 1 P 0 ;0,1=82,2=270.000000
L 1.0055 3.8318999 1.0055 3.84109931 1 P 0 ;0,1=82,2=270.000000
L 5.3825 2.5319997 5.4075 2.5319997 1 P 0 ;0,1=83,2=270.000000
L 5.3825 2.52586673 5.3825 2.53813317 1 P 0 ;0,1=83,2=270.000000
L 5.4075 2.54866654 5.3825 2.54866654 1 P 0 ;0,1=83,2=270.000000
L 5.3825 2.54866654 5.3825 2.55506663 1 P 0 ;0,1=83,2=270.000000
L 5.3825 2.55506663 5.38375059 2.5572 1 P 0 ;0,1=83,2=270.000000
L 5.38375059 2.5572 5.38666663 2.5588001 1 P 0 ;0,1=83,2=270.000000
L 5.38666663 2.5588001 5.39 2.55933337 1 P 0 ;0,1=83,2=270.000000
L 5.39 2.55933337 5.39333337 2.5588001 1 P 0 ;0,1=83,2=270.000000
L 5.39333337 2.5588001 5.39583356 2.55746663 1 P 0 ;0,1=83,2=270.000000
L 5.39583356 2.55746663 5.39708406 2.55506663 1 P 0 ;0,1=83,2=270.000000
L 5.39708406 2.55506663 5.39708406 2.54866654 1 P 0 ;0,1=83,2=270.000000
L 5.40375089 2.57013327 5.40583376 2.57173297 1 P 0 ;0,1=83,2=270.000000
L 5.40583376 2.57173297 5.40708346 2.5735997 1 P 0 ;0,1=83,2=270.000000
L 5.40708346 2.5735997 5.4075 2.5759997 1 P 0 ;0,1=83,2=270.000000
L 5.4075 2.5759997 5.40666693 2.5784002 1 P 0 ;0,1=83,2=270.000000
L 5.40666693 2.5784002 5.40500059 2.58026644 1 P 0 ;0,1=83,2=270.000000
L 5.40500059 2.58026644 5.40208376 2.5816 1 P 0 ;0,1=83,2=270.000000
L 5.40208376 2.5816 5.39875039 2.58186663 1 P 0 ;0,1=83,2=270.000000
L 5.39875039 2.58186663 5.39541703 2.58133337 1 P 0 ;0,1=83,2=270.000000
L 5.39541703 2.58133337 5.39333337 2.5799998 1 P 0 ;0,1=83,2=270.000000
L 5.39333337 2.5799998 5.39166703 2.57813307 1 P 0 ;0,1=83,2=270.000000
L 5.39166703 2.57813307 5.39125049 2.57626683 1 P 0 ;0,1=83,2=270.000000
L 5.39125049 2.57626683 5.39166703 2.5744 1 P 0 ;0,1=83,2=270.000000
L 5.39166703 2.5744 5.39333337 2.5720001 1 P 0 ;0,1=83,2=270.000000
L 5.39333337 2.5720001 5.3825 2.5727999 1 P 0 ;0,1=83,2=270.000000
L 5.3825 2.5727999 5.3825 2.5799998 1 P 0 ;0,1=83,2=270.000000
L 5.39708406 2.59293317 5.39416654 2.5947999 1 P 0 ;0,1=83,2=270.000000
L 5.39416654 2.5947999 5.3925002 2.5964 1 P 0 ;0,1=83,2=270.000000
L 5.3925002 2.5964 5.39166703 2.59853337 1 P 0 ;0,1=83,2=270.000000
L 5.39166703 2.59853337 5.3925002 2.6004002 1 P 0 ;0,1=83,2=270.000000
L 5.3925002 2.6004002 5.39416654 2.60173327 1 P 0 ;0,1=83,2=270.000000
L 5.39416654 2.60173327 5.39666673 2.6028001 1 P 0 ;0,1=83,2=270.000000
L 5.39666673 2.6028001 5.39958356 2.60306673 1 P 0 ;0,1=83,2=270.000000
L 5.39958356 2.60306673 5.40208376 2.6028001 1 P 0 ;0,1=83,2=270.000000
L 5.40208376 2.6028001 5.40458396 2.60173327 1 P 0 ;0,1=83,2=270.000000
L 5.40458396 2.60173327 5.40666693 2.60013307 1 P 0 ;0,1=83,2=270.000000
L 5.40666693 2.60013307 5.4075 2.59826683 1 P 0 ;0,1=83,2=270.000000
L 5.4075 2.59826683 5.40666693 2.59613346 1 P 0 ;0,1=83,2=270.000000
L 5.40666693 2.59613346 5.40416742 2.59426663 1 P 0 ;0,1=83,2=270.000000
L 5.40416742 2.59426663 5.40041673 2.5931998 1 P 0 ;0,1=83,2=270.000000
L 5.40041673 2.5931998 5.3962502 2.59293317 1 P 0 ;0,1=83,2=270.000000
L 5.3962502 2.59293317 5.39083386 2.59346634 1 P 0 ;0,1=83,2=270.000000
L 5.39083386 2.59346634 5.38791634 2.59426663 1 P 0 ;0,1=83,2=270.000000
L 5.38791634 2.59426663 5.3850003 2.5955997 1 P 0 ;0,1=83,2=270.000000
L 5.3850003 2.5955997 5.38291663 2.59746654 1 P 0 ;0,1=83,2=270.000000
L 5.38291663 2.59746654 5.3825 2.59933327 1 P 0 ;0,1=83,2=270.000000
L 5.3825 2.59933327 5.38333317 2.6012 1 P 0 ;0,1=83,2=270.000000
L 5.38333317 2.6012 5.38541683 2.60253356 1 P 0 ;0,1=83,2=270.000000
L 3.6275 2.8369997 3.6525 2.8369997 1 P 0 ;0,1=84,2=270.000000
L 3.6275 2.83086673 3.6275 2.84313317 1 P 0 ;0,1=84,2=270.000000
L 3.6525 2.85366654 3.6275 2.85366654 1 P 0 ;0,1=84,2=270.000000
L 3.6275 2.85366654 3.6275 2.86006663 1 P 0 ;0,1=84,2=270.000000
L 3.6275 2.86006663 3.62875059 2.8622 1 P 0 ;0,1=84,2=270.000000
L 3.62875059 2.8622 3.63166663 2.8638001 1 P 0 ;0,1=84,2=270.000000
L 3.63166663 2.8638001 3.635 2.86433337 1 P 0 ;0,1=84,2=270.000000
L 3.635 2.86433337 3.63833337 2.8638001 1 P 0 ;0,1=84,2=270.000000
L 3.63833337 2.8638001 3.64083356 2.86246663 1 P 0 ;0,1=84,2=270.000000
L 3.64083356 2.86246663 3.64208406 2.86006663 1 P 0 ;0,1=84,2=270.000000
L 3.64208406 2.86006663 3.64208406 2.85366654 1 P 0 ;0,1=84,2=270.000000
L 3.64875089 2.87513327 3.65083376 2.87673297 1 P 0 ;0,1=84,2=270.000000
L 3.65083376 2.87673297 3.65208346 2.8785997 1 P 0 ;0,1=84,2=270.000000
L 3.65208346 2.8785997 3.6525 2.8809997 1 P 0 ;0,1=84,2=270.000000
L 3.6525 2.8809997 3.65166693 2.8834002 1 P 0 ;0,1=84,2=270.000000
L 3.65166693 2.8834002 3.65000059 2.88526644 1 P 0 ;0,1=84,2=270.000000
L 3.65000059 2.88526644 3.64708376 2.8866 1 P 0 ;0,1=84,2=270.000000
L 3.64708376 2.8866 3.64375039 2.88686663 1 P 0 ;0,1=84,2=270.000000
L 3.64375039 2.88686663 3.64041703 2.88633337 1 P 0 ;0,1=84,2=270.000000
L 3.64041703 2.88633337 3.63833337 2.8849998 1 P 0 ;0,1=84,2=270.000000
L 3.63833337 2.8849998 3.63666703 2.88313307 1 P 0 ;0,1=84,2=270.000000
L 3.63666703 2.88313307 3.63625049 2.88126683 1 P 0 ;0,1=84,2=270.000000
L 3.63625049 2.88126683 3.63666703 2.8794 1 P 0 ;0,1=84,2=270.000000
L 3.63666703 2.8794 3.63833337 2.8770001 1 P 0 ;0,1=84,2=270.000000
L 3.63833337 2.8770001 3.6275 2.8777999 1 P 0 ;0,1=84,2=270.000000
L 3.6275 2.8777999 3.6275 2.8849998 1 P 0 ;0,1=84,2=270.000000
L 3.64875089 2.89713327 3.65083376 2.89873297 1 P 0 ;0,1=84,2=270.000000
L 3.65083376 2.89873297 3.65208346 2.9005997 1 P 0 ;0,1=84,2=270.000000
L 3.65208346 2.9005997 3.6525 2.9029997 1 P 0 ;0,1=84,2=270.000000
L 3.6525 2.9029997 3.65166693 2.9054002 1 P 0 ;0,1=84,2=270.000000
L 3.65166693 2.9054002 3.65000059 2.90726644 1 P 0 ;0,1=84,2=270.000000
L 3.65000059 2.90726644 3.64708376 2.9086 1 P 0 ;0,1=84,2=270.000000
L 3.64708376 2.9086 3.64375039 2.90886663 1 P 0 ;0,1=84,2=270.000000
L 3.64375039 2.90886663 3.64041703 2.90833337 1 P 0 ;0,1=84,2=270.000000
L 3.64041703 2.90833337 3.63833337 2.9069998 1 P 0 ;0,1=84,2=270.000000
L 3.63833337 2.9069998 3.63666703 2.90513307 1 P 0 ;0,1=84,2=270.000000
L 3.63666703 2.90513307 3.63625049 2.90326683 1 P 0 ;0,1=84,2=270.000000
L 3.63625049 2.90326683 3.63666703 2.9014 1 P 0 ;0,1=84,2=270.000000
L 3.63666703 2.9014 3.63833337 2.8990001 1 P 0 ;0,1=84,2=270.000000
L 3.63833337 2.8990001 3.6275 2.8997999 1 P 0 ;0,1=84,2=270.000000
L 3.6275 2.8997999 3.6275 2.9069998 1 P 0 ;0,1=84,2=270.000000
L 3.73349961 4.1455 3.73349961 4.1145 1 P 0 ;0,1=85,2=0.000000
L 3.72468337 4.1455 3.74231654 4.1455 1 P 0 ;0,1=85,2=0.000000
L 3.75683317 4.1145 3.75683317 4.1455 1 P 0 ;0,1=85,2=0.000000
L 3.75683317 4.1455 3.76603327 4.1455 1 P 0 ;0,1=85,2=0.000000
L 3.76603327 4.1455 3.7691 4.14394931 1 P 0 ;0,1=85,2=0.000000
L 3.7691 4.14394931 3.7714002 4.14033346 1 P 0 ;0,1=85,2=0.000000
L 3.7714002 4.14033346 3.77216673 4.1362 1 P 0 ;0,1=85,2=0.000000
L 3.77216673 4.1362 3.7714002 4.13206663 1 P 0 ;0,1=85,2=0.000000
L 3.7714002 4.13206663 3.76948327 4.12896634 1 P 0 ;0,1=85,2=0.000000
L 3.76948327 4.12896634 3.76603327 4.12741575 1 P 0 ;0,1=85,2=0.000000
L 3.76603327 4.12741575 3.75683317 4.12741575 1 P 0 ;0,1=85,2=0.000000
L 3.78706663 4.11914892 3.78936614 4.11656614 1 P 0 ;0,1=85,2=0.000000
L 3.78936614 4.11656614 3.79204961 4.11501654 1 P 0 ;0,1=85,2=0.000000
L 3.79204961 4.11501654 3.79549961 4.1145 1 P 0 ;0,1=85,2=0.000000
L 3.79549961 4.1145 3.7989503 4.11553307 1 P 0 ;0,1=85,2=0.000000
L 3.7989503 4.11553307 3.80163307 4.11759931 1 P 0 ;0,1=85,2=0.000000
L 3.80163307 4.11759931 3.80355 4.12121614 1 P 0 ;0,1=85,2=0.000000
L 3.80355 4.12121614 3.80393327 4.12534951 1 P 0 ;0,1=85,2=0.000000
L 3.80393327 4.12534951 3.80316673 4.12948287 1 P 0 ;0,1=85,2=0.000000
L 3.80316673 4.12948287 3.8012498 4.13206663 1 P 0 ;0,1=85,2=0.000000
L 3.8012498 4.13206663 3.79856634 4.13413287 1 P 0 ;0,1=85,2=0.000000
L 3.79856634 4.13413287 3.79588356 4.13464941 1 P 0 ;0,1=85,2=0.000000
L 3.79588356 4.13464941 3.7932001 4.13413287 1 P 0 ;0,1=85,2=0.000000
L 3.7932001 4.13413287 3.7897501 4.13206663 1 P 0 ;0,1=85,2=0.000000
L 3.7897501 4.13206663 3.7908999 4.1455 1 P 0 ;0,1=85,2=0.000000
L 3.7908999 4.1455 3.8012498 4.1455 1 P 0 ;0,1=85,2=0.000000
L 3.81998287 4.11811585 3.82266634 4.11553307 1 P 0 ;0,1=85,2=0.000000
L 3.82266634 4.11553307 3.82573307 4.1145 1 P 0 ;0,1=85,2=0.000000
L 3.82573307 4.1145 3.8287998 4.11553307 1 P 0 ;0,1=85,2=0.000000
L 3.8287998 4.11553307 3.83148327 4.11863238 1 P 0 ;0,1=85,2=0.000000
L 3.83148327 4.11863238 3.8334002 4.12328327 1 P 0 ;0,1=85,2=0.000000
L 3.8334002 4.12328327 3.83416673 4.12793327 1 P 0 ;0,1=85,2=0.000000
L 3.83416673 4.12793327 3.83416673 4.13361634 1 P 0 ;0,1=85,2=0.000000
L 3.83416673 4.13361634 3.8334002 4.13826624 1 P 0 ;0,1=85,2=0.000000
L 3.8334002 4.13826624 3.83148327 4.1423997 1 P 0 ;0,1=85,2=0.000000
L 3.83148327 4.1423997 3.82918307 4.14446683 1 P 0 ;0,1=85,2=0.000000
L 3.82918307 4.14446683 3.82649961 4.1455 1 P 0 ;0,1=85,2=0.000000
L 3.82649961 4.1455 3.82343287 4.14446683 1 P 0 ;0,1=85,2=0.000000
L 3.82343287 4.14446683 3.82113337 4.1423997 1 P 0 ;0,1=85,2=0.000000
L 3.82113337 4.1423997 3.8195997 4.1393003 1 P 0 ;0,1=85,2=0.000000
L 3.8195997 4.1393003 3.81883317 4.13516594 1 P 0 ;0,1=85,2=0.000000
L 3.81883317 4.13516594 3.8195997 4.1315501 1 P 0 ;0,1=85,2=0.000000
L 3.8195997 4.1315501 3.82151663 4.12793327 1 P 0 ;0,1=85,2=0.000000
L 3.82151663 4.12793327 3.82381683 4.12586604 1 P 0 ;0,1=85,2=0.000000
L 3.82381683 4.12586604 3.82649961 4.12534951 1 P 0 ;0,1=85,2=0.000000
L 3.82649961 4.12534951 3.82956634 4.12638268 1 P 0 ;0,1=85,2=0.000000
L 3.82956634 4.12638268 3.83186654 4.12896634 1 P 0 ;0,1=85,2=0.000000
L 3.83186654 4.12896634 3.83416673 4.13361634 1 P 0 ;0,1=85,2=0.000000
L 3.5219997 2.6725 3.5219997 2.6475 1 P 0 ;0,1=86,2=0.000000
L 3.51586673 2.6725 3.52813317 2.6725 1 P 0 ;0,1=86,2=0.000000
L 3.53866654 2.6475 3.53866654 2.6725 1 P 0 ;0,1=86,2=0.000000
L 3.53866654 2.6725 3.54506663 2.6725 1 P 0 ;0,1=86,2=0.000000
L 3.54506663 2.6725 3.5472 2.67124941 1 P 0 ;0,1=86,2=0.000000
L 3.5472 2.67124941 3.5488001 2.66833337 1 P 0 ;0,1=86,2=0.000000
L 3.5488001 2.66833337 3.54933337 2.665 1 P 0 ;0,1=86,2=0.000000
L 3.54933337 2.665 3.5488001 2.66166663 1 P 0 ;0,1=86,2=0.000000
L 3.5488001 2.66166663 3.54746663 2.65916644 1 P 0 ;0,1=86,2=0.000000
L 3.54746663 2.65916644 3.54506663 2.65791594 1 P 0 ;0,1=86,2=0.000000
L 3.54506663 2.65791594 3.53866654 2.65791594 1 P 0 ;0,1=86,2=0.000000
L 3.56013327 2.65124911 3.56173297 2.64916624 1 P 0 ;0,1=86,2=0.000000
L 3.56173297 2.64916624 3.5635997 2.64791654 1 P 0 ;0,1=86,2=0.000000
L 3.5635997 2.64791654 3.5659997 2.6475 1 P 0 ;0,1=86,2=0.000000
L 3.5659997 2.6475 3.5684002 2.64833307 1 P 0 ;0,1=86,2=0.000000
L 3.5684002 2.64833307 3.57026644 2.64999941 1 P 0 ;0,1=86,2=0.000000
L 3.57026644 2.64999941 3.5716 2.65291624 1 P 0 ;0,1=86,2=0.000000
L 3.5716 2.65291624 3.57186663 2.65624961 1 P 0 ;0,1=86,2=0.000000
L 3.57186663 2.65624961 3.57133337 2.65958297 1 P 0 ;0,1=86,2=0.000000
L 3.57133337 2.65958297 3.5699998 2.66166663 1 P 0 ;0,1=86,2=0.000000
L 3.5699998 2.66166663 3.56813307 2.66333297 1 P 0 ;0,1=86,2=0.000000
L 3.56813307 2.66333297 3.56626683 2.66374951 1 P 0 ;0,1=86,2=0.000000
L 3.56626683 2.66374951 3.5644 2.66333297 1 P 0 ;0,1=86,2=0.000000
L 3.5644 2.66333297 3.5620001 2.66166663 1 P 0 ;0,1=86,2=0.000000
L 3.5620001 2.66166663 3.5627999 2.6725 1 P 0 ;0,1=86,2=0.000000
L 3.5627999 2.6725 3.5699998 2.6725 1 P 0 ;0,1=86,2=0.000000
L 3.5879997 2.6475 3.58986644 2.64791654 1 P 0 ;0,1=86,2=0.000000
L 3.58986644 2.64791654 3.5919998 2.64916624 1 P 0 ;0,1=86,2=0.000000
L 3.5919998 2.64916624 3.59333337 2.65124911 1 P 0 ;0,1=86,2=0.000000
L 3.59333337 2.65124911 3.59386663 2.65416673 1 P 0 ;0,1=86,2=0.000000
L 3.59386663 2.65416673 3.59333337 2.65708278 1 P 0 ;0,1=86,2=0.000000
L 3.59333337 2.65708278 3.59173327 2.65958297 1 P 0 ;0,1=86,2=0.000000
L 3.59173327 2.65958297 3.58933327 2.66083346 1 P 0 ;0,1=86,2=0.000000
L 3.58933327 2.66083346 3.58666663 2.66083346 1 P 0 ;0,1=86,2=0.000000
L 3.58666663 2.66083346 3.58506654 2.66166663 1 P 0 ;0,1=86,2=0.000000
L 3.58506654 2.66166663 3.58373297 2.66374951 1 P 0 ;0,1=86,2=0.000000
L 3.58373297 2.66374951 3.5831998 2.66666634 1 P 0 ;0,1=86,2=0.000000
L 3.5831998 2.66666634 3.5840001 2.66958317 1 P 0 ;0,1=86,2=0.000000
L 3.5840001 2.66958317 3.58586634 2.67166683 1 P 0 ;0,1=86,2=0.000000
L 3.58586634 2.67166683 3.5879997 2.6725 1 P 0 ;0,1=86,2=0.000000
L 3.5879997 2.6725 3.59013307 2.67166683 1 P 0 ;0,1=86,2=0.000000
L 3.59013307 2.67166683 3.5919998 2.66958317 1 P 0 ;0,1=86,2=0.000000
L 3.5919998 2.66958317 3.5928001 2.66666634 1 P 0 ;0,1=86,2=0.000000
L 3.5928001 2.66666634 3.59226644 2.66374951 1 P 0 ;0,1=86,2=0.000000
L 3.59226644 2.66374951 3.59093337 2.66166663 1 P 0 ;0,1=86,2=0.000000
L 3.59093337 2.66166663 3.58933327 2.66083346 1 P 0 ;0,1=86,2=0.000000
L 3.58933327 2.66083346 3.58666663 2.66083346 1 P 0 ;0,1=86,2=0.000000
L 3.58666663 2.66083346 3.58426663 2.65958297 1 P 0 ;0,1=86,2=0.000000
L 3.58426663 2.65958297 3.58266654 2.65708278 1 P 0 ;0,1=86,2=0.000000
L 3.58266654 2.65708278 3.58213327 2.65416673 1 P 0 ;0,1=86,2=0.000000
L 3.58213327 2.65416673 3.58266654 2.65124911 1 P 0 ;0,1=86,2=0.000000
L 3.58266654 2.65124911 3.5840001 2.64916624 1 P 0 ;0,1=86,2=0.000000
L 3.5840001 2.64916624 3.58613346 2.64791654 1 P 0 ;0,1=86,2=0.000000
L 3.58613346 2.64791654 3.5879997 2.6475 1 P 0 ;0,1=86,2=0.000000
L 4.26349961 2.7005 4.26349961 2.6695 1 P 0 ;0,1=87,2=0.000000
L 4.25468337 2.7005 4.27231654 2.7005 1 P 0 ;0,1=87,2=0.000000
L 4.28683317 2.6695 4.28683317 2.7005 1 P 0 ;0,1=87,2=0.000000
L 4.28683317 2.7005 4.29603327 2.7005 1 P 0 ;0,1=87,2=0.000000
L 4.29603327 2.7005 4.2991 2.69894931 1 P 0 ;0,1=87,2=0.000000
L 4.2991 2.69894931 4.3014002 2.69533346 1 P 0 ;0,1=87,2=0.000000
L 4.3014002 2.69533346 4.30216673 2.6912 1 P 0 ;0,1=87,2=0.000000
L 4.30216673 2.6912 4.3014002 2.68706663 1 P 0 ;0,1=87,2=0.000000
L 4.3014002 2.68706663 4.29948327 2.68396634 1 P 0 ;0,1=87,2=0.000000
L 4.29948327 2.68396634 4.29603327 2.68241575 1 P 0 ;0,1=87,2=0.000000
L 4.29603327 2.68241575 4.28683317 2.68241575 1 P 0 ;0,1=87,2=0.000000
L 4.31706663 2.67414892 4.31936614 2.67156614 1 P 0 ;0,1=87,2=0.000000
L 4.31936614 2.67156614 4.32204961 2.67001654 1 P 0 ;0,1=87,2=0.000000
L 4.32204961 2.67001654 4.32549961 2.6695 1 P 0 ;0,1=87,2=0.000000
L 4.32549961 2.6695 4.3289503 2.67053307 1 P 0 ;0,1=87,2=0.000000
L 4.3289503 2.67053307 4.33163307 2.67259931 1 P 0 ;0,1=87,2=0.000000
L 4.33163307 2.67259931 4.33355 2.67621614 1 P 0 ;0,1=87,2=0.000000
L 4.33355 2.67621614 4.33393327 2.68034951 1 P 0 ;0,1=87,2=0.000000
L 4.33393327 2.68034951 4.33316673 2.68448287 1 P 0 ;0,1=87,2=0.000000
L 4.33316673 2.68448287 4.3312498 2.68706663 1 P 0 ;0,1=87,2=0.000000
L 4.3312498 2.68706663 4.32856634 2.68913287 1 P 0 ;0,1=87,2=0.000000
L 4.32856634 2.68913287 4.32588356 2.68964941 1 P 0 ;0,1=87,2=0.000000
L 4.32588356 2.68964941 4.3232001 2.68913287 1 P 0 ;0,1=87,2=0.000000
L 4.3232001 2.68913287 4.3197501 2.68706663 1 P 0 ;0,1=87,2=0.000000
L 4.3197501 2.68706663 4.3208999 2.7005 1 P 0 ;0,1=87,2=0.000000
L 4.3208999 2.7005 4.3312498 2.7005 1 P 0 ;0,1=87,2=0.000000
L 4.34806663 2.67569961 4.35036614 2.67208278 1 P 0 ;0,1=87,2=0.000000
L 4.35036614 2.67208278 4.35343287 2.67001654 1 P 0 ;0,1=87,2=0.000000
L 4.35343287 2.67001654 4.35688356 2.6695 1 P 0 ;0,1=87,2=0.000000
L 4.35688356 2.6695 4.3599503 2.67001654 1 P 0 ;0,1=87,2=0.000000
L 4.3599503 2.67001654 4.36301703 2.67259931 1 P 0 ;0,1=87,2=0.000000
L 4.36301703 2.67259931 4.36493327 2.67569961 1 P 0 ;0,1=87,2=0.000000
L 4.36493327 2.67569961 4.36531654 2.6787999 1 P 0 ;0,1=87,2=0.000000
L 4.36531654 2.6787999 4.36455 2.68241575 1 P 0 ;0,1=87,2=0.000000
L 4.36455 2.68241575 4.36186654 2.68499951 1 P 0 ;0,1=87,2=0.000000
L 4.36186654 2.68499951 4.35918307 2.68603356 1 P 0 ;0,1=87,2=0.000000
L 4.35918307 2.68603356 4.35573307 2.68603356 1 P 0 ;0,1=87,2=0.000000
L 4.35918307 2.68603356 4.36148327 2.68758317 1 P 0 ;0,1=87,2=0.000000
L 4.36148327 2.68758317 4.3634002 2.69016594 1 P 0 ;0,1=87,2=0.000000
L 4.3634002 2.69016594 4.36416673 2.69326624 1 P 0 ;0,1=87,2=0.000000
L 4.36416673 2.69326624 4.3634002 2.69636654 1 P 0 ;0,1=87,2=0.000000
L 4.3634002 2.69636654 4.36148327 2.69894931 1 P 0 ;0,1=87,2=0.000000
L 4.36148327 2.69894931 4.35803327 2.7005 1 P 0 ;0,1=87,2=0.000000
L 4.35803327 2.7005 4.35458337 2.69998337 1 P 0 ;0,1=87,2=0.000000
L 4.35458337 2.69998337 4.35113337 2.69791624 1 P 0 ;0,1=87,2=0.000000
L 5.35349961 0.7555 5.35349961 0.7245 1 P 0 ;0,1=88,2=0.000000
L 5.34468337 0.7555 5.36231654 0.7555 1 P 0 ;0,1=88,2=0.000000
L 5.37683317 0.7245 5.37683317 0.7555 1 P 0 ;0,1=88,2=0.000000
L 5.37683317 0.7555 5.38603327 0.7555 1 P 0 ;0,1=88,2=0.000000
L 5.38603327 0.7555 5.3891 0.75394931 1 P 0 ;0,1=88,2=0.000000
L 5.3891 0.75394931 5.3914002 0.75033346 1 P 0 ;0,1=88,2=0.000000
L 5.3914002 0.75033346 5.39216673 0.7462 1 P 0 ;0,1=88,2=0.000000
L 5.39216673 0.7462 5.3914002 0.74206663 1 P 0 ;0,1=88,2=0.000000
L 5.3914002 0.74206663 5.38948327 0.73896634 1 P 0 ;0,1=88,2=0.000000
L 5.38948327 0.73896634 5.38603327 0.73741575 1 P 0 ;0,1=88,2=0.000000
L 5.38603327 0.73741575 5.37683317 0.73741575 1 P 0 ;0,1=88,2=0.000000
L 5.40706663 0.72914892 5.40936614 0.72656614 1 P 0 ;0,1=88,2=0.000000
L 5.40936614 0.72656614 5.41204961 0.72501654 1 P 0 ;0,1=88,2=0.000000
L 5.41204961 0.72501654 5.41549961 0.7245 1 P 0 ;0,1=88,2=0.000000
L 5.41549961 0.7245 5.4189503 0.72553307 1 P 0 ;0,1=88,2=0.000000
L 5.4189503 0.72553307 5.42163307 0.72759931 1 P 0 ;0,1=88,2=0.000000
L 5.42163307 0.72759931 5.42355 0.73121614 1 P 0 ;0,1=88,2=0.000000
L 5.42355 0.73121614 5.42393327 0.73534951 1 P 0 ;0,1=88,2=0.000000
L 5.42393327 0.73534951 5.42316673 0.73948287 1 P 0 ;0,1=88,2=0.000000
L 5.42316673 0.73948287 5.4212498 0.74206663 1 P 0 ;0,1=88,2=0.000000
L 5.4212498 0.74206663 5.41856634 0.74413287 1 P 0 ;0,1=88,2=0.000000
L 5.41856634 0.74413287 5.41588356 0.74464941 1 P 0 ;0,1=88,2=0.000000
L 5.41588356 0.74464941 5.4132001 0.74413287 1 P 0 ;0,1=88,2=0.000000
L 5.4132001 0.74413287 5.4097501 0.74206663 1 P 0 ;0,1=88,2=0.000000
L 5.4097501 0.74206663 5.4108999 0.7555 1 P 0 ;0,1=88,2=0.000000
L 5.4108999 0.7555 5.4212498 0.7555 1 P 0 ;0,1=88,2=0.000000
L 5.44573307 0.7245 5.44649961 0.73121614 1 P 0 ;0,1=88,2=0.000000
L 5.44649961 0.73121614 5.4476501 0.73689921 1 P 0 ;0,1=88,2=0.000000
L 5.4476501 0.73689921 5.44918307 0.74206663 1 P 0 ;0,1=88,2=0.000000
L 5.44918307 0.74206663 5.4511 0.7477497 1 P 0 ;0,1=88,2=0.000000
L 5.4511 0.7477497 5.45416673 0.7555 1 P 0 ;0,1=88,2=0.000000
L 5.45416673 0.7555 5.43883317 0.7555 1 P 0 ;0,1=88,2=0.000000
L 4.8225 1.4059997 4.8475 1.4059997 1 P 0 ;0,1=89,2=270.000000
L 4.8225 1.39986673 4.8225 1.41213317 1 P 0 ;0,1=89,2=270.000000
L 4.8475 1.42266654 4.8225 1.42266654 1 P 0 ;0,1=89,2=270.000000
L 4.8225 1.42266654 4.8225 1.42906663 1 P 0 ;0,1=89,2=270.000000
L 4.8225 1.42906663 4.82375059 1.4312 1 P 0 ;0,1=89,2=270.000000
L 4.82375059 1.4312 4.82666663 1.4328001 1 P 0 ;0,1=89,2=270.000000
L 4.82666663 1.4328001 4.83 1.43333337 1 P 0 ;0,1=89,2=270.000000
L 4.83 1.43333337 4.83333337 1.4328001 1 P 0 ;0,1=89,2=270.000000
L 4.83333337 1.4328001 4.83583356 1.43146663 1 P 0 ;0,1=89,2=270.000000
L 4.83583356 1.43146663 4.83708406 1.42906663 1 P 0 ;0,1=89,2=270.000000
L 4.83708406 1.42906663 4.83708406 1.42266654 1 P 0 ;0,1=89,2=270.000000
L 4.8475 1.4499997 4.8225 1.4499997 1 P 0 ;0,1=89,2=270.000000
L 4.8225 1.4499997 4.8274997 1.4467999 1 P 0 ;0,1=89,2=270.000000
L 4.8475 1.4467999 4.8475 1.45319951 1 P 0 ;0,1=89,2=270.000000
L 4.84250039 1.46613327 4.84541713 1.46773297 1 P 0 ;0,1=89,2=270.000000
L 4.84541713 1.46773297 4.84708346 1.46986634 1 P 0 ;0,1=89,2=270.000000
L 4.84708346 1.46986634 4.8475 1.47226683 1 P 0 ;0,1=89,2=270.000000
L 4.8475 1.47226683 4.84708346 1.4744002 1 P 0 ;0,1=89,2=270.000000
L 4.84708346 1.4744002 4.84500059 1.47653356 1 P 0 ;0,1=89,2=270.000000
L 4.84500059 1.47653356 4.84250039 1.47786663 1 P 0 ;0,1=89,2=270.000000
L 4.84250039 1.47786663 4.8400001 1.47813317 1 P 0 ;0,1=89,2=270.000000
L 4.8400001 1.47813317 4.83708406 1.4776 1 P 0 ;0,1=89,2=270.000000
L 4.83708406 1.4776 4.83500039 1.47573327 1 P 0 ;0,1=89,2=270.000000
L 4.83500039 1.47573327 4.83416654 1.47386644 1 P 0 ;0,1=89,2=270.000000
L 4.83416654 1.47386644 4.83416654 1.47146654 1 P 0 ;0,1=89,2=270.000000
L 4.83416654 1.47386644 4.83291673 1.47546663 1 P 0 ;0,1=89,2=270.000000
L 4.83291673 1.47546663 4.83083386 1.4768001 1 P 0 ;0,1=89,2=270.000000
L 4.83083386 1.4768001 4.82833366 1.47733337 1 P 0 ;0,1=89,2=270.000000
L 4.82833366 1.47733337 4.82583346 1.4768001 1 P 0 ;0,1=89,2=270.000000
L 4.82583346 1.4768001 4.82375059 1.47546663 1 P 0 ;0,1=89,2=270.000000
L 4.82375059 1.47546663 4.8225 1.47306663 1 P 0 ;0,1=89,2=270.000000
L 4.8225 1.47306663 4.82291663 1.47066663 1 P 0 ;0,1=89,2=270.000000
L 4.82291663 1.47066663 4.82458366 1.46826663 1 P 0 ;0,1=89,2=270.000000
L 4.84458396 1.48946634 4.84666693 1.49133317 1 P 0 ;0,1=89,2=270.000000
L 4.84666693 1.49133317 4.8475 1.49346654 1 P 0 ;0,1=89,2=270.000000
L 4.8475 1.49346654 4.84666693 1.4955999 1 P 0 ;0,1=89,2=270.000000
L 4.84666693 1.4955999 4.84416742 1.49746663 1 P 0 ;0,1=89,2=270.000000
L 4.84416742 1.49746663 4.84041673 1.4988001 1 P 0 ;0,1=89,2=270.000000
L 4.84041673 1.4988001 4.83666673 1.49933337 1 P 0 ;0,1=89,2=270.000000
L 4.83666673 1.49933337 4.83208366 1.49933337 1 P 0 ;0,1=89,2=270.000000
L 4.83208366 1.49933337 4.82833366 1.4988001 1 P 0 ;0,1=89,2=270.000000
L 4.82833366 1.4988001 4.8250003 1.49746663 1 P 0 ;0,1=89,2=270.000000
L 4.8250003 1.49746663 4.82333317 1.49586644 1 P 0 ;0,1=89,2=270.000000
L 4.82333317 1.49586644 4.8225 1.4939997 1 P 0 ;0,1=89,2=270.000000
L 4.8225 1.4939997 4.82333317 1.49186634 1 P 0 ;0,1=89,2=270.000000
L 4.82333317 1.49186634 4.8250003 1.49026663 1 P 0 ;0,1=89,2=270.000000
L 4.8250003 1.49026663 4.8274997 1.4891998 1 P 0 ;0,1=89,2=270.000000
L 4.8274997 1.4891998 4.83083386 1.48866654 1 P 0 ;0,1=89,2=270.000000
L 4.83083386 1.48866654 4.8337499 1.4891998 1 P 0 ;0,1=89,2=270.000000
L 4.8337499 1.4891998 4.83666673 1.49053327 1 P 0 ;0,1=89,2=270.000000
L 4.83666673 1.49053327 4.83833386 1.49213346 1 P 0 ;0,1=89,2=270.000000
L 4.83833386 1.49213346 4.83875039 1.4939997 1 P 0 ;0,1=89,2=270.000000
L 4.83875039 1.4939997 4.83791722 1.49613307 1 P 0 ;0,1=89,2=270.000000
L 4.83791722 1.49613307 4.83583356 1.49773327 1 P 0 ;0,1=89,2=270.000000
L 4.83583356 1.49773327 4.83208366 1.49933337 1 P 0 ;0,1=89,2=270.000000
L 5.1105 1.4044997 5.1355 1.4044997 1 P 0 ;0,1=90,2=270.000000
L 5.1105 1.39836673 5.1105 1.41063317 1 P 0 ;0,1=90,2=270.000000
L 5.1355 1.42116654 5.1105 1.42116654 1 P 0 ;0,1=90,2=270.000000
L 5.1105 1.42116654 5.1105 1.42756663 1 P 0 ;0,1=90,2=270.000000
L 5.1105 1.42756663 5.11175059 1.4297 1 P 0 ;0,1=90,2=270.000000
L 5.11175059 1.4297 5.11466663 1.4313001 1 P 0 ;0,1=90,2=270.000000
L 5.11466663 1.4313001 5.118 1.43183337 1 P 0 ;0,1=90,2=270.000000
L 5.118 1.43183337 5.12133337 1.4313001 1 P 0 ;0,1=90,2=270.000000
L 5.12133337 1.4313001 5.12383356 1.42996663 1 P 0 ;0,1=90,2=270.000000
L 5.12383356 1.42996663 5.12508406 1.42756663 1 P 0 ;0,1=90,2=270.000000
L 5.12508406 1.42756663 5.12508406 1.42116654 1 P 0 ;0,1=90,2=270.000000
L 5.1355 1.4484997 5.1105 1.4484997 1 P 0 ;0,1=90,2=270.000000
L 5.1105 1.4484997 5.1154997 1.4452999 1 P 0 ;0,1=90,2=270.000000
L 5.1355 1.4452999 5.1355 1.45169951 1 P 0 ;0,1=90,2=270.000000
L 5.13050039 1.46463327 5.13341713 1.46623297 1 P 0 ;0,1=90,2=270.000000
L 5.13341713 1.46623297 5.13508346 1.46836634 1 P 0 ;0,1=90,2=270.000000
L 5.13508346 1.46836634 5.1355 1.47076683 1 P 0 ;0,1=90,2=270.000000
L 5.1355 1.47076683 5.13508346 1.4729002 1 P 0 ;0,1=90,2=270.000000
L 5.13508346 1.4729002 5.13300059 1.47503356 1 P 0 ;0,1=90,2=270.000000
L 5.13300059 1.47503356 5.13050039 1.47636663 1 P 0 ;0,1=90,2=270.000000
L 5.13050039 1.47636663 5.1280001 1.47663317 1 P 0 ;0,1=90,2=270.000000
L 5.1280001 1.47663317 5.12508406 1.4761 1 P 0 ;0,1=90,2=270.000000
L 5.12508406 1.4761 5.12300039 1.47423327 1 P 0 ;0,1=90,2=270.000000
L 5.12300039 1.47423327 5.12216654 1.47236644 1 P 0 ;0,1=90,2=270.000000
L 5.12216654 1.47236644 5.12216654 1.46996654 1 P 0 ;0,1=90,2=270.000000
L 5.12216654 1.47236644 5.12091673 1.47396663 1 P 0 ;0,1=90,2=270.000000
L 5.12091673 1.47396663 5.11883386 1.4753001 1 P 0 ;0,1=90,2=270.000000
L 5.11883386 1.4753001 5.11633366 1.47583337 1 P 0 ;0,1=90,2=270.000000
L 5.11633366 1.47583337 5.11383346 1.4753001 1 P 0 ;0,1=90,2=270.000000
L 5.11383346 1.4753001 5.11175059 1.47396663 1 P 0 ;0,1=90,2=270.000000
L 5.11175059 1.47396663 5.1105 1.47156663 1 P 0 ;0,1=90,2=270.000000
L 5.1105 1.47156663 5.11091663 1.46916663 1 P 0 ;0,1=90,2=270.000000
L 5.11091663 1.46916663 5.11258366 1.46676663 1 P 0 ;0,1=90,2=270.000000
L 5.1355 1.4924997 5.13508346 1.49436644 1 P 0 ;0,1=90,2=270.000000
L 5.13508346 1.49436644 5.13383376 1.4964998 1 P 0 ;0,1=90,2=270.000000
L 5.13383376 1.4964998 5.13175089 1.49783337 1 P 0 ;0,1=90,2=270.000000
L 5.13175089 1.49783337 5.12883327 1.49836663 1 P 0 ;0,1=90,2=270.000000
L 5.12883327 1.49836663 5.12591722 1.49783337 1 P 0 ;0,1=90,2=270.000000
L 5.12591722 1.49783337 5.12341703 1.49623327 1 P 0 ;0,1=90,2=270.000000
L 5.12341703 1.49623327 5.12216654 1.49383327 1 P 0 ;0,1=90,2=270.000000
L 5.12216654 1.49383327 5.12216654 1.49116663 1 P 0 ;0,1=90,2=270.000000
L 5.12216654 1.49116663 5.12133337 1.48956654 1 P 0 ;0,1=90,2=270.000000
L 5.12133337 1.48956654 5.11925049 1.48823297 1 P 0 ;0,1=90,2=270.000000
L 5.11925049 1.48823297 5.11633366 1.4876998 1 P 0 ;0,1=90,2=270.000000
L 5.11633366 1.4876998 5.11341683 1.4885001 1 P 0 ;0,1=90,2=270.000000
L 5.11341683 1.4885001 5.11133317 1.49036634 1 P 0 ;0,1=90,2=270.000000
L 5.11133317 1.49036634 5.1105 1.4924997 1 P 0 ;0,1=90,2=270.000000
L 5.1105 1.4924997 5.11133317 1.49463307 1 P 0 ;0,1=90,2=270.000000
L 5.11133317 1.49463307 5.11341683 1.4964998 1 P 0 ;0,1=90,2=270.000000
L 5.11341683 1.4964998 5.11633366 1.4973001 1 P 0 ;0,1=90,2=270.000000
L 5.11633366 1.4973001 5.11925049 1.49676644 1 P 0 ;0,1=90,2=270.000000
L 5.11925049 1.49676644 5.12133337 1.49543337 1 P 0 ;0,1=90,2=270.000000
L 5.12133337 1.49543337 5.12216654 1.49383327 1 P 0 ;0,1=90,2=270.000000
L 5.12216654 1.49383327 5.12216654 1.49116663 1 P 0 ;0,1=90,2=270.000000
L 5.12216654 1.49116663 5.12341703 1.48876663 1 P 0 ;0,1=90,2=270.000000
L 5.12341703 1.48876663 5.12591722 1.48716654 1 P 0 ;0,1=90,2=270.000000
L 5.12591722 1.48716654 5.12883327 1.48663327 1 P 0 ;0,1=90,2=270.000000
L 5.12883327 1.48663327 5.13175089 1.48716654 1 P 0 ;0,1=90,2=270.000000
L 5.13175089 1.48716654 5.13383376 1.4885001 1 P 0 ;0,1=90,2=270.000000
L 5.13383376 1.4885001 5.13508346 1.49063346 1 P 0 ;0,1=90,2=270.000000
L 5.13508346 1.49063346 5.1355 1.4924997 1 P 0 ;0,1=90,2=270.000000
L 3.37349961 2.0905 3.37349961 2.0595 1 P 0 ;0,1=91,2=0.000000
L 3.36468337 2.0905 3.38231654 2.0905 1 P 0 ;0,1=91,2=0.000000
L 3.39683317 2.0595 3.39683317 2.0905 1 P 0 ;0,1=91,2=0.000000
L 3.39683317 2.0905 3.40603327 2.0905 1 P 0 ;0,1=91,2=0.000000
L 3.40603327 2.0905 3.4091 2.08894931 1 P 0 ;0,1=91,2=0.000000
L 3.4091 2.08894931 3.4114002 2.08533346 1 P 0 ;0,1=91,2=0.000000
L 3.4114002 2.08533346 3.41216673 2.0812 1 P 0 ;0,1=91,2=0.000000
L 3.41216673 2.0812 3.4114002 2.07706663 1 P 0 ;0,1=91,2=0.000000
L 3.4114002 2.07706663 3.40948327 2.07396634 1 P 0 ;0,1=91,2=0.000000
L 3.40948327 2.07396634 3.40603327 2.07241575 1 P 0 ;0,1=91,2=0.000000
L 3.40603327 2.07241575 3.39683317 2.07241575 1 P 0 ;0,1=91,2=0.000000
L 3.42821644 2.07241575 3.4308999 2.07603356 1 P 0 ;0,1=91,2=0.000000
L 3.4308999 2.07603356 3.4332001 2.0780998 1 P 0 ;0,1=91,2=0.000000
L 3.4332001 2.0780998 3.43626683 2.07913287 1 P 0 ;0,1=91,2=0.000000
L 3.43626683 2.07913287 3.4389503 2.0780998 1 P 0 ;0,1=91,2=0.000000
L 3.4389503 2.0780998 3.44086654 2.07603356 1 P 0 ;0,1=91,2=0.000000
L 3.44086654 2.07603356 3.4424002 2.07293327 1 P 0 ;0,1=91,2=0.000000
L 3.4424002 2.07293327 3.44278346 2.06931644 1 P 0 ;0,1=91,2=0.000000
L 3.44278346 2.06931644 3.4424002 2.06621614 1 P 0 ;0,1=91,2=0.000000
L 3.4424002 2.06621614 3.44086654 2.06311585 1 P 0 ;0,1=91,2=0.000000
L 3.44086654 2.06311585 3.43856634 2.06053307 1 P 0 ;0,1=91,2=0.000000
L 3.43856634 2.06053307 3.43588356 2.0595 1 P 0 ;0,1=91,2=0.000000
L 3.43588356 2.0595 3.43281683 2.06053307 1 P 0 ;0,1=91,2=0.000000
L 3.43281683 2.06053307 3.43013337 2.06363238 1 P 0 ;0,1=91,2=0.000000
L 3.43013337 2.06363238 3.4285997 2.06828327 1 P 0 ;0,1=91,2=0.000000
L 3.4285997 2.06828327 3.42821644 2.0734498 1 P 0 ;0,1=91,2=0.000000
L 3.42821644 2.0734498 3.42898287 2.08016594 1 P 0 ;0,1=91,2=0.000000
L 3.42898287 2.08016594 3.43013337 2.08378376 1 P 0 ;0,1=91,2=0.000000
L 3.43013337 2.08378376 3.43204961 2.0873997 1 P 0 ;0,1=91,2=0.000000
L 3.43204961 2.0873997 3.43473307 2.08998337 1 P 0 ;0,1=91,2=0.000000
L 3.43473307 2.08998337 3.43741654 2.0905 1 P 0 ;0,1=91,2=0.000000
L 3.43741654 2.0905 3.4401 2.08946683 1 P 0 ;0,1=91,2=0.000000
L 3.4401 2.08946683 3.44201703 2.08688307 1 P 0 ;0,1=91,2=0.000000
L 3.46649961 2.0595 3.46649961 2.0905 1 P 0 ;0,1=91,2=0.000000
L 3.46649961 2.0905 3.4618999 2.0843003 1 P 0 ;0,1=91,2=0.000000
L 3.4618999 2.0595 3.47109931 2.0595 1 P 0 ;0,1=91,2=0.000000
L 3.2995 3.08899961 3.3305 3.08899961 1 P 0 ;0,1=92,2=270.000000
L 3.2995 3.08018337 3.2995 3.09781654 1 P 0 ;0,1=92,2=270.000000
L 3.3305 3.11233317 3.2995 3.11233317 1 P 0 ;0,1=92,2=270.000000
L 3.2995 3.11233317 3.2995 3.12153327 1 P 0 ;0,1=92,2=270.000000
L 3.2995 3.12153327 3.30105069 3.1246 1 P 0 ;0,1=92,2=270.000000
L 3.30105069 3.1246 3.30466654 3.1269002 1 P 0 ;0,1=92,2=270.000000
L 3.30466654 3.1269002 3.3088 3.12766673 1 P 0 ;0,1=92,2=270.000000
L 3.3088 3.12766673 3.31293337 3.1269002 1 P 0 ;0,1=92,2=270.000000
L 3.31293337 3.1269002 3.31603366 3.12498327 1 P 0 ;0,1=92,2=270.000000
L 3.31603366 3.12498327 3.31758425 3.12153327 1 P 0 ;0,1=92,2=270.000000
L 3.31758425 3.12153327 3.31758425 3.11233317 1 P 0 ;0,1=92,2=270.000000
L 3.3305 3.15099961 3.2995 3.15099961 1 P 0 ;0,1=92,2=270.000000
L 3.2995 3.15099961 3.3056997 3.1463999 1 P 0 ;0,1=92,2=270.000000
L 3.3305 3.1463999 3.3305 3.15559931 1 P 0 ;0,1=92,2=270.000000
L 5.51849961 1.5855 5.51849961 1.5545 1 P 0 ;0,1=93,2=0.000000
L 5.50968337 1.5855 5.52731654 1.5855 1 P 0 ;0,1=93,2=0.000000
L 5.54183317 1.5545 5.54183317 1.5855 1 P 0 ;0,1=93,2=0.000000
L 5.54183317 1.5855 5.55103327 1.5855 1 P 0 ;0,1=93,2=0.000000
L 5.55103327 1.5855 5.5541 1.58394931 1 P 0 ;0,1=93,2=0.000000
L 5.5541 1.58394931 5.5564002 1.58033346 1 P 0 ;0,1=93,2=0.000000
L 5.5564002 1.58033346 5.55716673 1.5762 1 P 0 ;0,1=93,2=0.000000
L 5.55716673 1.5762 5.5564002 1.57206663 1 P 0 ;0,1=93,2=0.000000
L 5.5564002 1.57206663 5.55448327 1.56896634 1 P 0 ;0,1=93,2=0.000000
L 5.55448327 1.56896634 5.55103327 1.56741575 1 P 0 ;0,1=93,2=0.000000
L 5.55103327 1.56741575 5.54183317 1.56741575 1 P 0 ;0,1=93,2=0.000000
L 5.57206663 1.55914892 5.57436614 1.55656614 1 P 0 ;0,1=93,2=0.000000
L 5.57436614 1.55656614 5.57704961 1.55501654 1 P 0 ;0,1=93,2=0.000000
L 5.57704961 1.55501654 5.58049961 1.5545 1 P 0 ;0,1=93,2=0.000000
L 5.58049961 1.5545 5.5839503 1.55553307 1 P 0 ;0,1=93,2=0.000000
L 5.5839503 1.55553307 5.58663307 1.55759931 1 P 0 ;0,1=93,2=0.000000
L 5.58663307 1.55759931 5.58855 1.56121614 1 P 0 ;0,1=93,2=0.000000
L 5.58855 1.56121614 5.58893327 1.56534951 1 P 0 ;0,1=93,2=0.000000
L 5.58893327 1.56534951 5.58816673 1.56948287 1 P 0 ;0,1=93,2=0.000000
L 5.58816673 1.56948287 5.5862498 1.57206663 1 P 0 ;0,1=93,2=0.000000
L 5.5862498 1.57206663 5.58356634 1.57413287 1 P 0 ;0,1=93,2=0.000000
L 5.58356634 1.57413287 5.58088356 1.57464941 1 P 0 ;0,1=93,2=0.000000
L 5.58088356 1.57464941 5.5782001 1.57413287 1 P 0 ;0,1=93,2=0.000000
L 5.5782001 1.57413287 5.5747501 1.57206663 1 P 0 ;0,1=93,2=0.000000
L 5.5747501 1.57206663 5.5758999 1.5855 1 P 0 ;0,1=93,2=0.000000
L 5.5758999 1.5855 5.5862498 1.5855 1 P 0 ;0,1=93,2=0.000000
L 5.6161 1.5545 5.6161 1.5855 1 P 0 ;0,1=93,2=0.000000
L 5.6161 1.5855 5.60191624 1.56328327 1 P 0 ;0,1=93,2=0.000000
L 5.60191624 1.56328327 5.62108366 1.56328327 1 P 0 ;0,1=93,2=0.000000
L 4.8725 1.5109997 4.8975 1.5109997 1 P 0 ;0,1=94,2=270.000000
L 4.8725 1.50486673 4.8725 1.51713317 1 P 0 ;0,1=94,2=270.000000
L 4.8975 1.52766654 4.8725 1.52766654 1 P 0 ;0,1=94,2=270.000000
L 4.8725 1.52766654 4.8725 1.53406663 1 P 0 ;0,1=94,2=270.000000
L 4.8725 1.53406663 4.87375059 1.5362 1 P 0 ;0,1=94,2=270.000000
L 4.87375059 1.5362 4.87666663 1.5378001 1 P 0 ;0,1=94,2=270.000000
L 4.87666663 1.5378001 4.88 1.53833337 1 P 0 ;0,1=94,2=270.000000
L 4.88 1.53833337 4.88333337 1.5378001 1 P 0 ;0,1=94,2=270.000000
L 4.88333337 1.5378001 4.88583356 1.53646663 1 P 0 ;0,1=94,2=270.000000
L 4.88583356 1.53646663 4.88708406 1.53406663 1 P 0 ;0,1=94,2=270.000000
L 4.88708406 1.53406663 4.88708406 1.52766654 1 P 0 ;0,1=94,2=270.000000
L 4.8975 1.5549997 4.8725 1.5549997 1 P 0 ;0,1=94,2=270.000000
L 4.8725 1.5549997 4.8774997 1.5517999 1 P 0 ;0,1=94,2=270.000000
L 4.8975 1.5517999 4.8975 1.55819951 1 P 0 ;0,1=94,2=270.000000
L 4.89250039 1.57113327 4.89541713 1.57273297 1 P 0 ;0,1=94,2=270.000000
L 4.89541713 1.57273297 4.89708346 1.57486634 1 P 0 ;0,1=94,2=270.000000
L 4.89708346 1.57486634 4.8975 1.57726683 1 P 0 ;0,1=94,2=270.000000
L 4.8975 1.57726683 4.89708346 1.5794002 1 P 0 ;0,1=94,2=270.000000
L 4.89708346 1.5794002 4.89500059 1.58153356 1 P 0 ;0,1=94,2=270.000000
L 4.89500059 1.58153356 4.89250039 1.58286663 1 P 0 ;0,1=94,2=270.000000
L 4.89250039 1.58286663 4.8900001 1.58313317 1 P 0 ;0,1=94,2=270.000000
L 4.8900001 1.58313317 4.88708406 1.5826 1 P 0 ;0,1=94,2=270.000000
L 4.88708406 1.5826 4.88500039 1.58073327 1 P 0 ;0,1=94,2=270.000000
L 4.88500039 1.58073327 4.88416654 1.57886644 1 P 0 ;0,1=94,2=270.000000
L 4.88416654 1.57886644 4.88416654 1.57646654 1 P 0 ;0,1=94,2=270.000000
L 4.88416654 1.57886644 4.88291673 1.58046663 1 P 0 ;0,1=94,2=270.000000
L 4.88291673 1.58046663 4.88083386 1.5818001 1 P 0 ;0,1=94,2=270.000000
L 4.88083386 1.5818001 4.87833366 1.58233337 1 P 0 ;0,1=94,2=270.000000
L 4.87833366 1.58233337 4.87583346 1.5818001 1 P 0 ;0,1=94,2=270.000000
L 4.87583346 1.5818001 4.87375059 1.58046663 1 P 0 ;0,1=94,2=270.000000
L 4.87375059 1.58046663 4.8725 1.57806663 1 P 0 ;0,1=94,2=270.000000
L 4.8725 1.57806663 4.87291663 1.57566663 1 P 0 ;0,1=94,2=270.000000
L 4.87291663 1.57566663 4.87458366 1.57326663 1 P 0 ;0,1=94,2=270.000000
L 4.8975 1.59846654 4.89208376 1.5989997 1 P 0 ;0,1=94,2=270.000000
L 4.89208376 1.5989997 4.88750069 1.5998 1 P 0 ;0,1=94,2=270.000000
L 4.88750069 1.5998 4.88333337 1.60086644 1 P 0 ;0,1=94,2=270.000000
L 4.88333337 1.60086644 4.8787502 1.6022 1 P 0 ;0,1=94,2=270.000000
L 4.8787502 1.6022 4.8725 1.60433337 1 P 0 ;0,1=94,2=270.000000
L 4.8725 1.60433337 4.8725 1.59366654 1 P 0 ;0,1=94,2=270.000000
L 5.0775 1.4059997 5.1025 1.4059997 1 P 0 ;0,1=95,2=270.000000
L 5.0775 1.39986673 5.0775 1.41213317 1 P 0 ;0,1=95,2=270.000000
L 5.1025 1.42266654 5.0775 1.42266654 1 P 0 ;0,1=95,2=270.000000
L 5.0775 1.42266654 5.0775 1.42906663 1 P 0 ;0,1=95,2=270.000000
L 5.0775 1.42906663 5.07875059 1.4312 1 P 0 ;0,1=95,2=270.000000
L 5.07875059 1.4312 5.08166663 1.4328001 1 P 0 ;0,1=95,2=270.000000
L 5.08166663 1.4328001 5.085 1.43333337 1 P 0 ;0,1=95,2=270.000000
L 5.085 1.43333337 5.08833337 1.4328001 1 P 0 ;0,1=95,2=270.000000
L 5.08833337 1.4328001 5.09083356 1.43146663 1 P 0 ;0,1=95,2=270.000000
L 5.09083356 1.43146663 5.09208406 1.42906663 1 P 0 ;0,1=95,2=270.000000
L 5.09208406 1.42906663 5.09208406 1.42266654 1 P 0 ;0,1=95,2=270.000000
L 5.1025 1.4499997 5.0775 1.4499997 1 P 0 ;0,1=95,2=270.000000
L 5.0775 1.4499997 5.0824997 1.4467999 1 P 0 ;0,1=95,2=270.000000
L 5.1025 1.4467999 5.1025 1.45319951 1 P 0 ;0,1=95,2=270.000000
L 5.09750039 1.46613327 5.10041713 1.46773297 1 P 0 ;0,1=95,2=270.000000
L 5.10041713 1.46773297 5.10208346 1.46986634 1 P 0 ;0,1=95,2=270.000000
L 5.10208346 1.46986634 5.1025 1.47226683 1 P 0 ;0,1=95,2=270.000000
L 5.1025 1.47226683 5.10208346 1.4744002 1 P 0 ;0,1=95,2=270.000000
L 5.10208346 1.4744002 5.10000059 1.47653356 1 P 0 ;0,1=95,2=270.000000
L 5.10000059 1.47653356 5.09750039 1.47786663 1 P 0 ;0,1=95,2=270.000000
L 5.09750039 1.47786663 5.0950001 1.47813317 1 P 0 ;0,1=95,2=270.000000
L 5.0950001 1.47813317 5.09208406 1.4776 1 P 0 ;0,1=95,2=270.000000
L 5.09208406 1.4776 5.09000039 1.47573327 1 P 0 ;0,1=95,2=270.000000
L 5.09000039 1.47573327 5.08916654 1.47386644 1 P 0 ;0,1=95,2=270.000000
L 5.08916654 1.47386644 5.08916654 1.47146654 1 P 0 ;0,1=95,2=270.000000
L 5.08916654 1.47386644 5.08791673 1.47546663 1 P 0 ;0,1=95,2=270.000000
L 5.08791673 1.47546663 5.08583386 1.4768001 1 P 0 ;0,1=95,2=270.000000
L 5.08583386 1.4768001 5.08333366 1.47733337 1 P 0 ;0,1=95,2=270.000000
L 5.08333366 1.47733337 5.08083346 1.4768001 1 P 0 ;0,1=95,2=270.000000
L 5.08083346 1.4768001 5.07875059 1.47546663 1 P 0 ;0,1=95,2=270.000000
L 5.07875059 1.47546663 5.0775 1.47306663 1 P 0 ;0,1=95,2=270.000000
L 5.0775 1.47306663 5.07791663 1.47066663 1 P 0 ;0,1=95,2=270.000000
L 5.07791663 1.47066663 5.07958366 1.46826663 1 P 0 ;0,1=95,2=270.000000
L 5.09875089 1.48813327 5.10083376 1.48973297 1 P 0 ;0,1=95,2=270.000000
L 5.10083376 1.48973297 5.10208346 1.4915997 1 P 0 ;0,1=95,2=270.000000
L 5.10208346 1.4915997 5.1025 1.4939997 1 P 0 ;0,1=95,2=270.000000
L 5.1025 1.4939997 5.10166693 1.4964002 1 P 0 ;0,1=95,2=270.000000
L 5.10166693 1.4964002 5.10000059 1.49826644 1 P 0 ;0,1=95,2=270.000000
L 5.10000059 1.49826644 5.09708376 1.4996 1 P 0 ;0,1=95,2=270.000000
L 5.09708376 1.4996 5.09375039 1.49986663 1 P 0 ;0,1=95,2=270.000000
L 5.09375039 1.49986663 5.09041703 1.49933337 1 P 0 ;0,1=95,2=270.000000
L 5.09041703 1.49933337 5.08833337 1.4979998 1 P 0 ;0,1=95,2=270.000000
L 5.08833337 1.4979998 5.08666703 1.49613307 1 P 0 ;0,1=95,2=270.000000
L 5.08666703 1.49613307 5.08625049 1.49426683 1 P 0 ;0,1=95,2=270.000000
L 5.08625049 1.49426683 5.08666703 1.4924 1 P 0 ;0,1=95,2=270.000000
L 5.08666703 1.4924 5.08833337 1.4900001 1 P 0 ;0,1=95,2=270.000000
L 5.08833337 1.4900001 5.0775 1.4907999 1 P 0 ;0,1=95,2=270.000000
L 5.0775 1.4907999 5.0775 1.4979998 1 P 0 ;0,1=95,2=270.000000
L 4.8075 1.5159997 4.8325 1.5159997 1 P 0 ;0,1=96,2=270.000000
L 4.8075 1.50986673 4.8075 1.52213317 1 P 0 ;0,1=96,2=270.000000
L 4.8325 1.53266654 4.8075 1.53266654 1 P 0 ;0,1=96,2=270.000000
L 4.8075 1.53266654 4.8075 1.53906663 1 P 0 ;0,1=96,2=270.000000
L 4.8075 1.53906663 4.80875059 1.5412 1 P 0 ;0,1=96,2=270.000000
L 4.80875059 1.5412 4.81166663 1.5428001 1 P 0 ;0,1=96,2=270.000000
L 4.81166663 1.5428001 4.815 1.54333337 1 P 0 ;0,1=96,2=270.000000
L 4.815 1.54333337 4.81833337 1.5428001 1 P 0 ;0,1=96,2=270.000000
L 4.81833337 1.5428001 4.82083356 1.54146663 1 P 0 ;0,1=96,2=270.000000
L 4.82083356 1.54146663 4.82208406 1.53906663 1 P 0 ;0,1=96,2=270.000000
L 4.82208406 1.53906663 4.82208406 1.53266654 1 P 0 ;0,1=96,2=270.000000
L 4.8325 1.5599997 4.8075 1.5599997 1 P 0 ;0,1=96,2=270.000000
L 4.8075 1.5599997 4.8124997 1.5567999 1 P 0 ;0,1=96,2=270.000000
L 4.8325 1.5567999 4.8325 1.56319951 1 P 0 ;0,1=96,2=270.000000
L 4.82750039 1.57613327 4.83041713 1.57773297 1 P 0 ;0,1=96,2=270.000000
L 4.83041713 1.57773297 4.83208346 1.57986634 1 P 0 ;0,1=96,2=270.000000
L 4.83208346 1.57986634 4.8325 1.58226683 1 P 0 ;0,1=96,2=270.000000
L 4.8325 1.58226683 4.83208346 1.5844002 1 P 0 ;0,1=96,2=270.000000
L 4.83208346 1.5844002 4.83000059 1.58653356 1 P 0 ;0,1=96,2=270.000000
L 4.83000059 1.58653356 4.82750039 1.58786663 1 P 0 ;0,1=96,2=270.000000
L 4.82750039 1.58786663 4.8250001 1.58813317 1 P 0 ;0,1=96,2=270.000000
L 4.8250001 1.58813317 4.82208406 1.5876 1 P 0 ;0,1=96,2=270.000000
L 4.82208406 1.5876 4.82000039 1.58573327 1 P 0 ;0,1=96,2=270.000000
L 4.82000039 1.58573327 4.81916654 1.58386644 1 P 0 ;0,1=96,2=270.000000
L 4.81916654 1.58386644 4.81916654 1.58146654 1 P 0 ;0,1=96,2=270.000000
L 4.81916654 1.58386644 4.81791673 1.58546663 1 P 0 ;0,1=96,2=270.000000
L 4.81791673 1.58546663 4.81583386 1.5868001 1 P 0 ;0,1=96,2=270.000000
L 4.81583386 1.5868001 4.81333366 1.58733337 1 P 0 ;0,1=96,2=270.000000
L 4.81333366 1.58733337 4.81083346 1.5868001 1 P 0 ;0,1=96,2=270.000000
L 4.81083346 1.5868001 4.80875059 1.58546663 1 P 0 ;0,1=96,2=270.000000
L 4.80875059 1.58546663 4.8075 1.58306663 1 P 0 ;0,1=96,2=270.000000
L 4.8075 1.58306663 4.80791663 1.58066663 1 P 0 ;0,1=96,2=270.000000
L 4.80791663 1.58066663 4.80958366 1.57826663 1 P 0 ;0,1=96,2=270.000000
L 4.82208406 1.59893317 4.81916654 1.6007999 1 P 0 ;0,1=96,2=270.000000
L 4.81916654 1.6007999 4.8175002 1.6024 1 P 0 ;0,1=96,2=270.000000
L 4.8175002 1.6024 4.81666703 1.60453337 1 P 0 ;0,1=96,2=270.000000
L 4.81666703 1.60453337 4.8175002 1.6064002 1 P 0 ;0,1=96,2=270.000000
L 4.8175002 1.6064002 4.81916654 1.60773327 1 P 0 ;0,1=96,2=270.000000
L 4.81916654 1.60773327 4.82166673 1.6088001 1 P 0 ;0,1=96,2=270.000000
L 4.82166673 1.6088001 4.82458356 1.60906673 1 P 0 ;0,1=96,2=270.000000
L 4.82458356 1.60906673 4.82708376 1.6088001 1 P 0 ;0,1=96,2=270.000000
L 4.82708376 1.6088001 4.82958396 1.60773327 1 P 0 ;0,1=96,2=270.000000
L 4.82958396 1.60773327 4.83166693 1.60613307 1 P 0 ;0,1=96,2=270.000000
L 4.83166693 1.60613307 4.8325 1.60426683 1 P 0 ;0,1=96,2=270.000000
L 4.8325 1.60426683 4.83166693 1.60213346 1 P 0 ;0,1=96,2=270.000000
L 4.83166693 1.60213346 4.82916742 1.60026663 1 P 0 ;0,1=96,2=270.000000
L 4.82916742 1.60026663 4.82541673 1.5991998 1 P 0 ;0,1=96,2=270.000000
L 4.82541673 1.5991998 4.8212502 1.59893317 1 P 0 ;0,1=96,2=270.000000
L 4.8212502 1.59893317 4.81583386 1.59946634 1 P 0 ;0,1=96,2=270.000000
L 4.81583386 1.59946634 4.81291634 1.60026663 1 P 0 ;0,1=96,2=270.000000
L 4.81291634 1.60026663 4.8100003 1.6015997 1 P 0 ;0,1=96,2=270.000000
L 4.8100003 1.6015997 4.80791663 1.60346654 1 P 0 ;0,1=96,2=270.000000
L 4.80791663 1.60346654 4.8075 1.60533327 1 P 0 ;0,1=96,2=270.000000
L 4.8075 1.60533327 4.80833317 1.6072 1 P 0 ;0,1=96,2=270.000000
L 4.80833317 1.6072 4.81041683 1.60853356 1 P 0 ;0,1=96,2=270.000000
L 5.0575 1.5259997 5.0825 1.5259997 1 P 0 ;0,1=97,2=270.000000
L 5.0575 1.51986673 5.0575 1.53213317 1 P 0 ;0,1=97,2=270.000000
L 5.0825 1.54266654 5.0575 1.54266654 1 P 0 ;0,1=97,2=270.000000
L 5.0575 1.54266654 5.0575 1.54906663 1 P 0 ;0,1=97,2=270.000000
L 5.0575 1.54906663 5.05875059 1.5512 1 P 0 ;0,1=97,2=270.000000
L 5.05875059 1.5512 5.06166663 1.5528001 1 P 0 ;0,1=97,2=270.000000
L 5.06166663 1.5528001 5.065 1.55333337 1 P 0 ;0,1=97,2=270.000000
L 5.065 1.55333337 5.06833337 1.5528001 1 P 0 ;0,1=97,2=270.000000
L 5.06833337 1.5528001 5.07083356 1.55146663 1 P 0 ;0,1=97,2=270.000000
L 5.07083356 1.55146663 5.07208406 1.54906663 1 P 0 ;0,1=97,2=270.000000
L 5.07208406 1.54906663 5.07208406 1.54266654 1 P 0 ;0,1=97,2=270.000000
L 5.0825 1.5699997 5.0575 1.5699997 1 P 0 ;0,1=97,2=270.000000
L 5.0575 1.5699997 5.0624997 1.5667999 1 P 0 ;0,1=97,2=270.000000
L 5.0825 1.5667999 5.0825 1.57319951 1 P 0 ;0,1=97,2=270.000000
L 5.07750039 1.58613327 5.08041713 1.58773297 1 P 0 ;0,1=97,2=270.000000
L 5.08041713 1.58773297 5.08208346 1.58986634 1 P 0 ;0,1=97,2=270.000000
L 5.08208346 1.58986634 5.0825 1.59226683 1 P 0 ;0,1=97,2=270.000000
L 5.0825 1.59226683 5.08208346 1.5944002 1 P 0 ;0,1=97,2=270.000000
L 5.08208346 1.5944002 5.08000059 1.59653356 1 P 0 ;0,1=97,2=270.000000
L 5.08000059 1.59653356 5.07750039 1.59786663 1 P 0 ;0,1=97,2=270.000000
L 5.07750039 1.59786663 5.0750001 1.59813317 1 P 0 ;0,1=97,2=270.000000
L 5.0750001 1.59813317 5.07208406 1.5976 1 P 0 ;0,1=97,2=270.000000
L 5.07208406 1.5976 5.07000039 1.59573327 1 P 0 ;0,1=97,2=270.000000
L 5.07000039 1.59573327 5.06916654 1.59386644 1 P 0 ;0,1=97,2=270.000000
L 5.06916654 1.59386644 5.06916654 1.59146654 1 P 0 ;0,1=97,2=270.000000
L 5.06916654 1.59386644 5.06791673 1.59546663 1 P 0 ;0,1=97,2=270.000000
L 5.06791673 1.59546663 5.06583386 1.5968001 1 P 0 ;0,1=97,2=270.000000
L 5.06583386 1.5968001 5.06333366 1.59733337 1 P 0 ;0,1=97,2=270.000000
L 5.06333366 1.59733337 5.06083346 1.5968001 1 P 0 ;0,1=97,2=270.000000
L 5.06083346 1.5968001 5.05875059 1.59546663 1 P 0 ;0,1=97,2=270.000000
L 5.05875059 1.59546663 5.0575 1.59306663 1 P 0 ;0,1=97,2=270.000000
L 5.0575 1.59306663 5.05791663 1.59066663 1 P 0 ;0,1=97,2=270.000000
L 5.05791663 1.59066663 5.05958366 1.58826663 1 P 0 ;0,1=97,2=270.000000
L 5.0825 1.6172 5.0575 1.6172 1 P 0 ;0,1=97,2=270.000000
L 5.0575 1.6172 5.07541673 1.60733297 1 P 0 ;0,1=97,2=270.000000
L 5.07541673 1.60733297 5.07541673 1.62066693 1 P 0 ;0,1=97,2=270.000000
L 0.7895 2.96899961 0.8205 2.96899961 1 P 0 ;0,1=98,2=270.000000
L 0.7895 2.96018337 0.7895 2.97781654 1 P 0 ;0,1=98,2=270.000000
L 0.8205 2.99233317 0.7895 2.99233317 1 P 0 ;0,1=98,2=270.000000
L 0.7895 2.99233317 0.7895 3.00153327 1 P 0 ;0,1=98,2=270.000000
L 0.7895 3.00153327 0.79105069 3.0046 1 P 0 ;0,1=98,2=270.000000
L 0.79105069 3.0046 0.79466654 3.0069002 1 P 0 ;0,1=98,2=270.000000
L 0.79466654 3.0069002 0.7988 3.00766673 1 P 0 ;0,1=98,2=270.000000
L 0.7988 3.00766673 0.80293337 3.0069002 1 P 0 ;0,1=98,2=270.000000
L 0.80293337 3.0069002 0.80603366 3.00498327 1 P 0 ;0,1=98,2=270.000000
L 0.80603366 3.00498327 0.80758425 3.00153327 1 P 0 ;0,1=98,2=270.000000
L 0.80758425 3.00153327 0.80758425 2.99233317 1 P 0 ;0,1=98,2=270.000000
L 0.80758425 3.02371644 0.80396644 3.0263999 1 P 0 ;0,1=98,2=270.000000
L 0.80396644 3.0263999 0.8019002 3.0287001 1 P 0 ;0,1=98,2=270.000000
L 0.8019002 3.0287001 0.80086713 3.03176683 1 P 0 ;0,1=98,2=270.000000
L 0.80086713 3.03176683 0.8019002 3.0344503 1 P 0 ;0,1=98,2=270.000000
L 0.8019002 3.0344503 0.80396644 3.03636654 1 P 0 ;0,1=98,2=270.000000
L 0.80396644 3.03636654 0.80706673 3.0379002 1 P 0 ;0,1=98,2=270.000000
L 0.80706673 3.0379002 0.81068356 3.03828346 1 P 0 ;0,1=98,2=270.000000
L 0.81068356 3.03828346 0.81378386 3.0379002 1 P 0 ;0,1=98,2=270.000000
L 0.81378386 3.0379002 0.81688415 3.03636654 1 P 0 ;0,1=98,2=270.000000
L 0.81688415 3.03636654 0.81946693 3.03406634 1 P 0 ;0,1=98,2=270.000000
L 0.81946693 3.03406634 0.8205 3.03138356 1 P 0 ;0,1=98,2=270.000000
L 0.8205 3.03138356 0.81946693 3.02831683 1 P 0 ;0,1=98,2=270.000000
L 0.81946693 3.02831683 0.81636762 3.02563337 1 P 0 ;0,1=98,2=270.000000
L 0.81636762 3.02563337 0.81171673 3.0240997 1 P 0 ;0,1=98,2=270.000000
L 0.81171673 3.0240997 0.8065502 3.02371644 1 P 0 ;0,1=98,2=270.000000
L 0.8065502 3.02371644 0.79983406 3.02448287 1 P 0 ;0,1=98,2=270.000000
L 0.79983406 3.02448287 0.79621624 3.02563337 1 P 0 ;0,1=98,2=270.000000
L 0.79621624 3.02563337 0.7926003 3.02754961 1 P 0 ;0,1=98,2=270.000000
L 0.7926003 3.02754961 0.79001663 3.03023307 1 P 0 ;0,1=98,2=270.000000
L 0.79001663 3.03023307 0.7895 3.03291654 1 P 0 ;0,1=98,2=270.000000
L 0.7895 3.03291654 0.79053317 3.0356 1 P 0 ;0,1=98,2=270.000000
L 0.79053317 3.0356 0.79311693 3.03751703 1 P 0 ;0,1=98,2=270.000000
L 3.8675 2.2169997 3.8925 2.2169997 1 P 0 ;0,1=99,2=270.000000
L 3.8675 2.21086673 3.8675 2.22313317 1 P 0 ;0,1=99,2=270.000000
L 3.8925 2.23366654 3.8675 2.23366654 1 P 0 ;0,1=99,2=270.000000
L 3.8675 2.23366654 3.8675 2.24006663 1 P 0 ;0,1=99,2=270.000000
L 3.8675 2.24006663 3.86875059 2.2422 1 P 0 ;0,1=99,2=270.000000
L 3.86875059 2.2422 3.87166663 2.2438001 1 P 0 ;0,1=99,2=270.000000
L 3.87166663 2.2438001 3.875 2.24433337 1 P 0 ;0,1=99,2=270.000000
L 3.875 2.24433337 3.87833337 2.2438001 1 P 0 ;0,1=99,2=270.000000
L 3.87833337 2.2438001 3.88083356 2.24246663 1 P 0 ;0,1=99,2=270.000000
L 3.88083356 2.24246663 3.88208406 2.24006663 1 P 0 ;0,1=99,2=270.000000
L 3.88208406 2.24006663 3.88208406 2.23366654 1 P 0 ;0,1=99,2=270.000000
L 3.8925 2.26046654 3.88708376 2.2609997 1 P 0 ;0,1=99,2=270.000000
L 3.88708376 2.2609997 3.88250069 2.2618 1 P 0 ;0,1=99,2=270.000000
L 3.88250069 2.2618 3.87833337 2.26286644 1 P 0 ;0,1=99,2=270.000000
L 3.87833337 2.26286644 3.8737502 2.2642 1 P 0 ;0,1=99,2=270.000000
L 3.8737502 2.2642 3.8675 2.26633337 1 P 0 ;0,1=99,2=270.000000
L 3.8675 2.26633337 3.8675 2.25566654 1 P 0 ;0,1=99,2=270.000000
L 3.8925 2.2829997 3.89208346 2.28486644 1 P 0 ;0,1=99,2=270.000000
L 3.89208346 2.28486644 3.89083376 2.2869998 1 P 0 ;0,1=99,2=270.000000
L 3.89083376 2.2869998 3.88875089 2.28833337 1 P 0 ;0,1=99,2=270.000000
L 3.88875089 2.28833337 3.88583327 2.28886663 1 P 0 ;0,1=99,2=270.000000
L 3.88583327 2.28886663 3.88291722 2.28833337 1 P 0 ;0,1=99,2=270.000000
L 3.88291722 2.28833337 3.88041703 2.28673327 1 P 0 ;0,1=99,2=270.000000
L 3.88041703 2.28673327 3.87916654 2.28433327 1 P 0 ;0,1=99,2=270.000000
L 3.87916654 2.28433327 3.87916654 2.28166663 1 P 0 ;0,1=99,2=270.000000
L 3.87916654 2.28166663 3.87833337 2.28006654 1 P 0 ;0,1=99,2=270.000000
L 3.87833337 2.28006654 3.87625049 2.27873297 1 P 0 ;0,1=99,2=270.000000
L 3.87625049 2.27873297 3.87333366 2.2781998 1 P 0 ;0,1=99,2=270.000000
L 3.87333366 2.2781998 3.87041683 2.2790001 1 P 0 ;0,1=99,2=270.000000
L 3.87041683 2.2790001 3.86833317 2.28086634 1 P 0 ;0,1=99,2=270.000000
L 3.86833317 2.28086634 3.8675 2.2829997 1 P 0 ;0,1=99,2=270.000000
L 3.8675 2.2829997 3.86833317 2.28513307 1 P 0 ;0,1=99,2=270.000000
L 3.86833317 2.28513307 3.87041683 2.2869998 1 P 0 ;0,1=99,2=270.000000
L 3.87041683 2.2869998 3.87333366 2.2878001 1 P 0 ;0,1=99,2=270.000000
L 3.87333366 2.2878001 3.87625049 2.28726644 1 P 0 ;0,1=99,2=270.000000
L 3.87625049 2.28726644 3.87833337 2.28593337 1 P 0 ;0,1=99,2=270.000000
L 3.87833337 2.28593337 3.87916654 2.28433327 1 P 0 ;0,1=99,2=270.000000
L 3.87916654 2.28433327 3.87916654 2.28166663 1 P 0 ;0,1=99,2=270.000000
L 3.87916654 2.28166663 3.88041703 2.27926663 1 P 0 ;0,1=99,2=270.000000
L 3.88041703 2.27926663 3.88291722 2.27766654 1 P 0 ;0,1=99,2=270.000000
L 3.88291722 2.27766654 3.88583327 2.27713327 1 P 0 ;0,1=99,2=270.000000
L 3.88583327 2.27713327 3.88875089 2.27766654 1 P 0 ;0,1=99,2=270.000000
L 3.88875089 2.27766654 3.89083376 2.2790001 1 P 0 ;0,1=99,2=270.000000
L 3.89083376 2.2790001 3.89208346 2.28113346 1 P 0 ;0,1=99,2=270.000000
L 3.89208346 2.28113346 3.8925 2.2829997 1 P 0 ;0,1=99,2=270.000000
L 3.8325 2.2159997 3.8575 2.2159997 1 P 0 ;0,1=100,2=270.000000
L 3.8325 2.20986673 3.8325 2.22213317 1 P 0 ;0,1=100,2=270.000000
L 3.8575 2.23266654 3.8325 2.23266654 1 P 0 ;0,1=100,2=270.000000
L 3.8325 2.23266654 3.8325 2.23906663 1 P 0 ;0,1=100,2=270.000000
L 3.8325 2.23906663 3.83375059 2.2412 1 P 0 ;0,1=100,2=270.000000
L 3.83375059 2.2412 3.83666663 2.2428001 1 P 0 ;0,1=100,2=270.000000
L 3.83666663 2.2428001 3.84 2.24333337 1 P 0 ;0,1=100,2=270.000000
L 3.84 2.24333337 3.84333337 2.2428001 1 P 0 ;0,1=100,2=270.000000
L 3.84333337 2.2428001 3.84583356 2.24146663 1 P 0 ;0,1=100,2=270.000000
L 3.84583356 2.24146663 3.84708406 2.23906663 1 P 0 ;0,1=100,2=270.000000
L 3.84708406 2.23906663 3.84708406 2.23266654 1 P 0 ;0,1=100,2=270.000000
L 3.8575 2.2599997 3.8325 2.2599997 1 P 0 ;0,1=100,2=270.000000
L 3.8325 2.2599997 3.8374997 2.2567999 1 P 0 ;0,1=100,2=270.000000
L 3.8575 2.2567999 3.8575 2.26319951 1 P 0 ;0,1=100,2=270.000000
L 3.8575 2.2819997 3.85708346 2.28386644 1 P 0 ;0,1=100,2=270.000000
L 3.85708346 2.28386644 3.85583376 2.2859998 1 P 0 ;0,1=100,2=270.000000
L 3.85583376 2.2859998 3.85375089 2.28733337 1 P 0 ;0,1=100,2=270.000000
L 3.85375089 2.28733337 3.85083327 2.28786663 1 P 0 ;0,1=100,2=270.000000
L 3.85083327 2.28786663 3.84791722 2.28733337 1 P 0 ;0,1=100,2=270.000000
L 3.84791722 2.28733337 3.84541703 2.28573327 1 P 0 ;0,1=100,2=270.000000
L 3.84541703 2.28573327 3.84416654 2.28333327 1 P 0 ;0,1=100,2=270.000000
L 3.84416654 2.28333327 3.84416654 2.28066663 1 P 0 ;0,1=100,2=270.000000
L 3.84416654 2.28066663 3.84333337 2.27906654 1 P 0 ;0,1=100,2=270.000000
L 3.84333337 2.27906654 3.84125049 2.27773297 1 P 0 ;0,1=100,2=270.000000
L 3.84125049 2.27773297 3.83833366 2.2771998 1 P 0 ;0,1=100,2=270.000000
L 3.83833366 2.2771998 3.83541683 2.2780001 1 P 0 ;0,1=100,2=270.000000
L 3.83541683 2.2780001 3.83333317 2.27986634 1 P 0 ;0,1=100,2=270.000000
L 3.83333317 2.27986634 3.8325 2.2819997 1 P 0 ;0,1=100,2=270.000000
L 3.8325 2.2819997 3.83333317 2.28413307 1 P 0 ;0,1=100,2=270.000000
L 3.83333317 2.28413307 3.83541683 2.2859998 1 P 0 ;0,1=100,2=270.000000
L 3.83541683 2.2859998 3.83833366 2.2868001 1 P 0 ;0,1=100,2=270.000000
L 3.83833366 2.2868001 3.84125049 2.28626644 1 P 0 ;0,1=100,2=270.000000
L 3.84125049 2.28626644 3.84333337 2.28493337 1 P 0 ;0,1=100,2=270.000000
L 3.84333337 2.28493337 3.84416654 2.28333327 1 P 0 ;0,1=100,2=270.000000
L 3.84416654 2.28333327 3.84416654 2.28066663 1 P 0 ;0,1=100,2=270.000000
L 3.84416654 2.28066663 3.84541703 2.27826663 1 P 0 ;0,1=100,2=270.000000
L 3.84541703 2.27826663 3.84791722 2.27666654 1 P 0 ;0,1=100,2=270.000000
L 3.84791722 2.27666654 3.85083327 2.27613327 1 P 0 ;0,1=100,2=270.000000
L 3.85083327 2.27613327 3.85375089 2.27666654 1 P 0 ;0,1=100,2=270.000000
L 3.85375089 2.27666654 3.85583376 2.2780001 1 P 0 ;0,1=100,2=270.000000
L 3.85583376 2.2780001 3.85708346 2.28013346 1 P 0 ;0,1=100,2=270.000000
L 3.85708346 2.28013346 3.8575 2.2819997 1 P 0 ;0,1=100,2=270.000000
L 3.8325 2.3039997 3.83333317 2.30186634 1 P 0 ;0,1=100,2=270.000000
L 3.83333317 2.30186634 3.83541683 2.30026663 1 P 0 ;0,1=100,2=270.000000
L 3.83541683 2.30026663 3.83791634 2.2991998 1 P 0 ;0,1=100,2=270.000000
L 3.83791634 2.2991998 3.84125049 2.2983999 1 P 0 ;0,1=100,2=270.000000
L 3.84125049 2.2983999 3.84500039 2.29813327 1 P 0 ;0,1=100,2=270.000000
L 3.84500039 2.29813327 3.84875039 2.2983999 1 P 0 ;0,1=100,2=270.000000
L 3.84875039 2.2983999 3.85208376 2.2991998 1 P 0 ;0,1=100,2=270.000000
L 3.85208376 2.2991998 3.85458396 2.30026663 1 P 0 ;0,1=100,2=270.000000
L 3.85458396 2.30026663 3.85666693 2.30186634 1 P 0 ;0,1=100,2=270.000000
L 3.85666693 2.30186634 3.8575 2.3039997 1 P 0 ;0,1=100,2=270.000000
L 3.8575 2.3039997 3.85666693 2.30613307 1 P 0 ;0,1=100,2=270.000000
L 3.85666693 2.30613307 3.85458396 2.30773327 1 P 0 ;0,1=100,2=270.000000
L 3.85458396 2.30773327 3.85208376 2.3088001 1 P 0 ;0,1=100,2=270.000000
L 3.85208376 2.3088001 3.84875039 2.3096 1 P 0 ;0,1=100,2=270.000000
L 3.84875039 2.3096 3.84500039 2.30986663 1 P 0 ;0,1=100,2=270.000000
L 3.84500039 2.30986663 3.84125049 2.3096 1 P 0 ;0,1=100,2=270.000000
L 3.84125049 2.3096 3.83791634 2.3088001 1 P 0 ;0,1=100,2=270.000000
L 3.83791634 2.3088001 3.83541683 2.30773327 1 P 0 ;0,1=100,2=270.000000
L 3.83541683 2.30773327 3.83333317 2.30613307 1 P 0 ;0,1=100,2=270.000000
L 3.83333317 2.30613307 3.8325 2.3039997 1 P 0 ;0,1=100,2=270.000000
L 4.2825 2.2209997 4.3075 2.2209997 1 P 0 ;0,1=101,2=270.000000
L 4.2825 2.21486673 4.2825 2.22713317 1 P 0 ;0,1=101,2=270.000000
L 4.3075 2.23766654 4.2825 2.23766654 1 P 0 ;0,1=101,2=270.000000
L 4.2825 2.23766654 4.2825 2.24406663 1 P 0 ;0,1=101,2=270.000000
L 4.2825 2.24406663 4.28375059 2.2462 1 P 0 ;0,1=101,2=270.000000
L 4.28375059 2.2462 4.28666663 2.2478001 1 P 0 ;0,1=101,2=270.000000
L 4.28666663 2.2478001 4.29 2.24833337 1 P 0 ;0,1=101,2=270.000000
L 4.29 2.24833337 4.29333337 2.2478001 1 P 0 ;0,1=101,2=270.000000
L 4.29333337 2.2478001 4.29583356 2.24646663 1 P 0 ;0,1=101,2=270.000000
L 4.29583356 2.24646663 4.29708406 2.24406663 1 P 0 ;0,1=101,2=270.000000
L 4.29708406 2.24406663 4.29708406 2.23766654 1 P 0 ;0,1=101,2=270.000000
L 4.3075 2.2649997 4.2825 2.2649997 1 P 0 ;0,1=101,2=270.000000
L 4.2825 2.2649997 4.2874997 2.2617999 1 P 0 ;0,1=101,2=270.000000
L 4.3075 2.2617999 4.3075 2.26819951 1 P 0 ;0,1=101,2=270.000000
L 4.3075 2.2869997 4.30708346 2.28886644 1 P 0 ;0,1=101,2=270.000000
L 4.30708346 2.28886644 4.30583376 2.2909998 1 P 0 ;0,1=101,2=270.000000
L 4.30583376 2.2909998 4.30375089 2.29233337 1 P 0 ;0,1=101,2=270.000000
L 4.30375089 2.29233337 4.30083327 2.29286663 1 P 0 ;0,1=101,2=270.000000
L 4.30083327 2.29286663 4.29791722 2.29233337 1 P 0 ;0,1=101,2=270.000000
L 4.29791722 2.29233337 4.29541703 2.29073327 1 P 0 ;0,1=101,2=270.000000
L 4.29541703 2.29073327 4.29416654 2.28833327 1 P 0 ;0,1=101,2=270.000000
L 4.29416654 2.28833327 4.29416654 2.28566663 1 P 0 ;0,1=101,2=270.000000
L 4.29416654 2.28566663 4.29333337 2.28406654 1 P 0 ;0,1=101,2=270.000000
L 4.29333337 2.28406654 4.29125049 2.28273297 1 P 0 ;0,1=101,2=270.000000
L 4.29125049 2.28273297 4.28833366 2.2821998 1 P 0 ;0,1=101,2=270.000000
L 4.28833366 2.2821998 4.28541683 2.2830001 1 P 0 ;0,1=101,2=270.000000
L 4.28541683 2.2830001 4.28333317 2.28486634 1 P 0 ;0,1=101,2=270.000000
L 4.28333317 2.28486634 4.2825 2.2869997 1 P 0 ;0,1=101,2=270.000000
L 4.2825 2.2869997 4.28333317 2.28913307 1 P 0 ;0,1=101,2=270.000000
L 4.28333317 2.28913307 4.28541683 2.2909998 1 P 0 ;0,1=101,2=270.000000
L 4.28541683 2.2909998 4.28833366 2.2918001 1 P 0 ;0,1=101,2=270.000000
L 4.28833366 2.2918001 4.29125049 2.29126644 1 P 0 ;0,1=101,2=270.000000
L 4.29125049 2.29126644 4.29333337 2.28993337 1 P 0 ;0,1=101,2=270.000000
L 4.29333337 2.28993337 4.29416654 2.28833327 1 P 0 ;0,1=101,2=270.000000
L 4.29416654 2.28833327 4.29416654 2.28566663 1 P 0 ;0,1=101,2=270.000000
L 4.29416654 2.28566663 4.29541703 2.28326663 1 P 0 ;0,1=101,2=270.000000
L 4.29541703 2.28326663 4.29791722 2.28166654 1 P 0 ;0,1=101,2=270.000000
L 4.29791722 2.28166654 4.30083327 2.28113327 1 P 0 ;0,1=101,2=270.000000
L 4.30083327 2.28113327 4.30375089 2.28166654 1 P 0 ;0,1=101,2=270.000000
L 4.30375089 2.28166654 4.30583376 2.2830001 1 P 0 ;0,1=101,2=270.000000
L 4.30583376 2.2830001 4.30708346 2.28513346 1 P 0 ;0,1=101,2=270.000000
L 4.30708346 2.28513346 4.3075 2.2869997 1 P 0 ;0,1=101,2=270.000000
L 4.30250039 2.30313327 4.30541713 2.30473297 1 P 0 ;0,1=101,2=270.000000
L 4.30541713 2.30473297 4.30708346 2.30686634 1 P 0 ;0,1=101,2=270.000000
L 4.30708346 2.30686634 4.3075 2.30926683 1 P 0 ;0,1=101,2=270.000000
L 4.3075 2.30926683 4.30708346 2.3114002 1 P 0 ;0,1=101,2=270.000000
L 4.30708346 2.3114002 4.30500059 2.31353356 1 P 0 ;0,1=101,2=270.000000
L 4.30500059 2.31353356 4.30250039 2.31486663 1 P 0 ;0,1=101,2=270.000000
L 4.30250039 2.31486663 4.3000001 2.31513317 1 P 0 ;0,1=101,2=270.000000
L 4.3000001 2.31513317 4.29708406 2.3146 1 P 0 ;0,1=101,2=270.000000
L 4.29708406 2.3146 4.29500039 2.31273327 1 P 0 ;0,1=101,2=270.000000
L 4.29500039 2.31273327 4.29416654 2.31086644 1 P 0 ;0,1=101,2=270.000000
L 4.29416654 2.31086644 4.29416654 2.30846654 1 P 0 ;0,1=101,2=270.000000
L 4.29416654 2.31086644 4.29291673 2.31246663 1 P 0 ;0,1=101,2=270.000000
L 4.29291673 2.31246663 4.29083386 2.3138001 1 P 0 ;0,1=101,2=270.000000
L 4.29083386 2.3138001 4.28833366 2.31433337 1 P 0 ;0,1=101,2=270.000000
L 4.28833366 2.31433337 4.28583346 2.3138001 1 P 0 ;0,1=101,2=270.000000
L 4.28583346 2.3138001 4.28375059 2.31246663 1 P 0 ;0,1=101,2=270.000000
L 4.28375059 2.31246663 4.2825 2.31006663 1 P 0 ;0,1=101,2=270.000000
L 4.2825 2.31006663 4.28291663 2.30766663 1 P 0 ;0,1=101,2=270.000000
L 4.28291663 2.30766663 4.28458366 2.30526663 1 P 0 ;0,1=101,2=270.000000
L 4.2925 2.3309997 4.3175 2.3309997 1 P 0 ;0,1=102,2=270.000000
L 4.2925 2.32486673 4.2925 2.33713317 1 P 0 ;0,1=102,2=270.000000
L 4.3175 2.34766654 4.2925 2.34766654 1 P 0 ;0,1=102,2=270.000000
L 4.2925 2.34766654 4.2925 2.35406663 1 P 0 ;0,1=102,2=270.000000
L 4.2925 2.35406663 4.29375059 2.3562 1 P 0 ;0,1=102,2=270.000000
L 4.29375059 2.3562 4.29666663 2.3578001 1 P 0 ;0,1=102,2=270.000000
L 4.29666663 2.3578001 4.3 2.35833337 1 P 0 ;0,1=102,2=270.000000
L 4.3 2.35833337 4.30333337 2.3578001 1 P 0 ;0,1=102,2=270.000000
L 4.30333337 2.3578001 4.30583356 2.35646663 1 P 0 ;0,1=102,2=270.000000
L 4.30583356 2.35646663 4.30708406 2.35406663 1 P 0 ;0,1=102,2=270.000000
L 4.30708406 2.35406663 4.30708406 2.34766654 1 P 0 ;0,1=102,2=270.000000
L 4.3175 2.3749997 4.2925 2.3749997 1 P 0 ;0,1=102,2=270.000000
L 4.2925 2.3749997 4.2974997 2.3717999 1 P 0 ;0,1=102,2=270.000000
L 4.3175 2.3717999 4.3175 2.37819951 1 P 0 ;0,1=102,2=270.000000
L 4.3175 2.3969997 4.31708346 2.39886644 1 P 0 ;0,1=102,2=270.000000
L 4.31708346 2.39886644 4.31583376 2.4009998 1 P 0 ;0,1=102,2=270.000000
L 4.31583376 2.4009998 4.31375089 2.40233337 1 P 0 ;0,1=102,2=270.000000
L 4.31375089 2.40233337 4.31083327 2.40286663 1 P 0 ;0,1=102,2=270.000000
L 4.31083327 2.40286663 4.30791722 2.40233337 1 P 0 ;0,1=102,2=270.000000
L 4.30791722 2.40233337 4.30541703 2.40073327 1 P 0 ;0,1=102,2=270.000000
L 4.30541703 2.40073327 4.30416654 2.39833327 1 P 0 ;0,1=102,2=270.000000
L 4.30416654 2.39833327 4.30416654 2.39566663 1 P 0 ;0,1=102,2=270.000000
L 4.30416654 2.39566663 4.30333337 2.39406654 1 P 0 ;0,1=102,2=270.000000
L 4.30333337 2.39406654 4.30125049 2.39273297 1 P 0 ;0,1=102,2=270.000000
L 4.30125049 2.39273297 4.29833366 2.3921998 1 P 0 ;0,1=102,2=270.000000
L 4.29833366 2.3921998 4.29541683 2.3930001 1 P 0 ;0,1=102,2=270.000000
L 4.29541683 2.3930001 4.29333317 2.39486634 1 P 0 ;0,1=102,2=270.000000
L 4.29333317 2.39486634 4.2925 2.3969997 1 P 0 ;0,1=102,2=270.000000
L 4.2925 2.3969997 4.29333317 2.39913307 1 P 0 ;0,1=102,2=270.000000
L 4.29333317 2.39913307 4.29541683 2.4009998 1 P 0 ;0,1=102,2=270.000000
L 4.29541683 2.4009998 4.29833366 2.4018001 1 P 0 ;0,1=102,2=270.000000
L 4.29833366 2.4018001 4.30125049 2.40126644 1 P 0 ;0,1=102,2=270.000000
L 4.30125049 2.40126644 4.30333337 2.39993337 1 P 0 ;0,1=102,2=270.000000
L 4.30333337 2.39993337 4.30416654 2.39833327 1 P 0 ;0,1=102,2=270.000000
L 4.30416654 2.39833327 4.30416654 2.39566663 1 P 0 ;0,1=102,2=270.000000
L 4.30416654 2.39566663 4.30541703 2.39326663 1 P 0 ;0,1=102,2=270.000000
L 4.30541703 2.39326663 4.30791722 2.39166654 1 P 0 ;0,1=102,2=270.000000
L 4.30791722 2.39166654 4.31083327 2.39113327 1 P 0 ;0,1=102,2=270.000000
L 4.31083327 2.39113327 4.31375089 2.39166654 1 P 0 ;0,1=102,2=270.000000
L 4.31375089 2.39166654 4.31583376 2.3930001 1 P 0 ;0,1=102,2=270.000000
L 4.31583376 2.3930001 4.31708346 2.39513346 1 P 0 ;0,1=102,2=270.000000
L 4.31708346 2.39513346 4.3175 2.3969997 1 P 0 ;0,1=102,2=270.000000
L 4.3175 2.4222 4.2925 2.4222 1 P 0 ;0,1=102,2=270.000000
L 4.2925 2.4222 4.31041673 2.41233297 1 P 0 ;0,1=102,2=270.000000
L 4.31041673 2.41233297 4.31041673 2.42566693 1 P 0 ;0,1=102,2=270.000000
L 4.3275 2.3309997 4.3525 2.3309997 1 P 0 ;0,1=103,2=270.000000
L 4.3275 2.32486673 4.3275 2.33713317 1 P 0 ;0,1=103,2=270.000000
L 4.3525 2.34766654 4.3275 2.34766654 1 P 0 ;0,1=103,2=270.000000
L 4.3275 2.34766654 4.3275 2.35406663 1 P 0 ;0,1=103,2=270.000000
L 4.3275 2.35406663 4.32875059 2.3562 1 P 0 ;0,1=103,2=270.000000
L 4.32875059 2.3562 4.33166663 2.3578001 1 P 0 ;0,1=103,2=270.000000
L 4.33166663 2.3578001 4.335 2.35833337 1 P 0 ;0,1=103,2=270.000000
L 4.335 2.35833337 4.33833337 2.3578001 1 P 0 ;0,1=103,2=270.000000
L 4.33833337 2.3578001 4.34083356 2.35646663 1 P 0 ;0,1=103,2=270.000000
L 4.34083356 2.35646663 4.34208406 2.35406663 1 P 0 ;0,1=103,2=270.000000
L 4.34208406 2.35406663 4.34208406 2.34766654 1 P 0 ;0,1=103,2=270.000000
L 4.3525 2.3749997 4.3275 2.3749997 1 P 0 ;0,1=103,2=270.000000
L 4.3275 2.3749997 4.3324997 2.3717999 1 P 0 ;0,1=103,2=270.000000
L 4.3525 2.3717999 4.3525 2.37819951 1 P 0 ;0,1=103,2=270.000000
L 4.3525 2.3969997 4.35208346 2.39886644 1 P 0 ;0,1=103,2=270.000000
L 4.35208346 2.39886644 4.35083376 2.4009998 1 P 0 ;0,1=103,2=270.000000
L 4.35083376 2.4009998 4.34875089 2.40233337 1 P 0 ;0,1=103,2=270.000000
L 4.34875089 2.40233337 4.34583327 2.40286663 1 P 0 ;0,1=103,2=270.000000
L 4.34583327 2.40286663 4.34291722 2.40233337 1 P 0 ;0,1=103,2=270.000000
L 4.34291722 2.40233337 4.34041703 2.40073327 1 P 0 ;0,1=103,2=270.000000
L 4.34041703 2.40073327 4.33916654 2.39833327 1 P 0 ;0,1=103,2=270.000000
L 4.33916654 2.39833327 4.33916654 2.39566663 1 P 0 ;0,1=103,2=270.000000
L 4.33916654 2.39566663 4.33833337 2.39406654 1 P 0 ;0,1=103,2=270.000000
L 4.33833337 2.39406654 4.33625049 2.39273297 1 P 0 ;0,1=103,2=270.000000
L 4.33625049 2.39273297 4.33333366 2.3921998 1 P 0 ;0,1=103,2=270.000000
L 4.33333366 2.3921998 4.33041683 2.3930001 1 P 0 ;0,1=103,2=270.000000
L 4.33041683 2.3930001 4.32833317 2.39486634 1 P 0 ;0,1=103,2=270.000000
L 4.32833317 2.39486634 4.3275 2.3969997 1 P 0 ;0,1=103,2=270.000000
L 4.3275 2.3969997 4.32833317 2.39913307 1 P 0 ;0,1=103,2=270.000000
L 4.32833317 2.39913307 4.33041683 2.4009998 1 P 0 ;0,1=103,2=270.000000
L 4.33041683 2.4009998 4.33333366 2.4018001 1 P 0 ;0,1=103,2=270.000000
L 4.33333366 2.4018001 4.33625049 2.40126644 1 P 0 ;0,1=103,2=270.000000
L 4.33625049 2.40126644 4.33833337 2.39993337 1 P 0 ;0,1=103,2=270.000000
L 4.33833337 2.39993337 4.33916654 2.39833327 1 P 0 ;0,1=103,2=270.000000
L 4.33916654 2.39833327 4.33916654 2.39566663 1 P 0 ;0,1=103,2=270.000000
L 4.33916654 2.39566663 4.34041703 2.39326663 1 P 0 ;0,1=103,2=270.000000
L 4.34041703 2.39326663 4.34291722 2.39166654 1 P 0 ;0,1=103,2=270.000000
L 4.34291722 2.39166654 4.34583327 2.39113327 1 P 0 ;0,1=103,2=270.000000
L 4.34583327 2.39113327 4.34875089 2.39166654 1 P 0 ;0,1=103,2=270.000000
L 4.34875089 2.39166654 4.35083376 2.3930001 1 P 0 ;0,1=103,2=270.000000
L 4.35083376 2.3930001 4.35208346 2.39513346 1 P 0 ;0,1=103,2=270.000000
L 4.35208346 2.39513346 4.3525 2.3969997 1 P 0 ;0,1=103,2=270.000000
L 4.34875089 2.41313327 4.35083376 2.41473297 1 P 0 ;0,1=103,2=270.000000
L 4.35083376 2.41473297 4.35208346 2.4165997 1 P 0 ;0,1=103,2=270.000000
L 4.35208346 2.4165997 4.3525 2.4189997 1 P 0 ;0,1=103,2=270.000000
L 4.3525 2.4189997 4.35166693 2.4214002 1 P 0 ;0,1=103,2=270.000000
L 4.35166693 2.4214002 4.35000059 2.42326644 1 P 0 ;0,1=103,2=270.000000
L 4.35000059 2.42326644 4.34708376 2.4246 1 P 0 ;0,1=103,2=270.000000
L 4.34708376 2.4246 4.34375039 2.42486663 1 P 0 ;0,1=103,2=270.000000
L 4.34375039 2.42486663 4.34041703 2.42433337 1 P 0 ;0,1=103,2=270.000000
L 4.34041703 2.42433337 4.33833337 2.4229998 1 P 0 ;0,1=103,2=270.000000
L 4.33833337 2.4229998 4.33666703 2.42113307 1 P 0 ;0,1=103,2=270.000000
L 4.33666703 2.42113307 4.33625049 2.41926683 1 P 0 ;0,1=103,2=270.000000
L 4.33625049 2.41926683 4.33666703 2.4174 1 P 0 ;0,1=103,2=270.000000
L 4.33666703 2.4174 4.33833337 2.4150001 1 P 0 ;0,1=103,2=270.000000
L 4.33833337 2.4150001 4.3275 2.4157999 1 P 0 ;0,1=103,2=270.000000
L 4.3275 2.4157999 4.3275 2.4229998 1 P 0 ;0,1=103,2=270.000000
L 4.0075 2.2259997 4.0325 2.2259997 1 P 0 ;0,1=104,2=270.000000
L 4.0075 2.21986673 4.0075 2.23213317 1 P 0 ;0,1=104,2=270.000000
L 4.0325 2.24266654 4.0075 2.24266654 1 P 0 ;0,1=104,2=270.000000
L 4.0075 2.24266654 4.0075 2.24906663 1 P 0 ;0,1=104,2=270.000000
L 4.0075 2.24906663 4.00875059 2.2512 1 P 0 ;0,1=104,2=270.000000
L 4.00875059 2.2512 4.01166663 2.2528001 1 P 0 ;0,1=104,2=270.000000
L 4.01166663 2.2528001 4.015 2.25333337 1 P 0 ;0,1=104,2=270.000000
L 4.015 2.25333337 4.01833337 2.2528001 1 P 0 ;0,1=104,2=270.000000
L 4.01833337 2.2528001 4.02083356 2.25146663 1 P 0 ;0,1=104,2=270.000000
L 4.02083356 2.25146663 4.02208406 2.24906663 1 P 0 ;0,1=104,2=270.000000
L 4.02208406 2.24906663 4.02208406 2.24266654 1 P 0 ;0,1=104,2=270.000000
L 4.0325 2.2699997 4.0075 2.2699997 1 P 0 ;0,1=104,2=270.000000
L 4.0075 2.2699997 4.0124997 2.2667999 1 P 0 ;0,1=104,2=270.000000
L 4.0325 2.2667999 4.0325 2.27319951 1 P 0 ;0,1=104,2=270.000000
L 4.0325 2.2919997 4.03208346 2.29386644 1 P 0 ;0,1=104,2=270.000000
L 4.03208346 2.29386644 4.03083376 2.2959998 1 P 0 ;0,1=104,2=270.000000
L 4.03083376 2.2959998 4.02875089 2.29733337 1 P 0 ;0,1=104,2=270.000000
L 4.02875089 2.29733337 4.02583327 2.29786663 1 P 0 ;0,1=104,2=270.000000
L 4.02583327 2.29786663 4.02291722 2.29733337 1 P 0 ;0,1=104,2=270.000000
L 4.02291722 2.29733337 4.02041703 2.29573327 1 P 0 ;0,1=104,2=270.000000
L 4.02041703 2.29573327 4.01916654 2.29333327 1 P 0 ;0,1=104,2=270.000000
L 4.01916654 2.29333327 4.01916654 2.29066663 1 P 0 ;0,1=104,2=270.000000
L 4.01916654 2.29066663 4.01833337 2.28906654 1 P 0 ;0,1=104,2=270.000000
L 4.01833337 2.28906654 4.01625049 2.28773297 1 P 0 ;0,1=104,2=270.000000
L 4.01625049 2.28773297 4.01333366 2.2871998 1 P 0 ;0,1=104,2=270.000000
L 4.01333366 2.2871998 4.01041683 2.2880001 1 P 0 ;0,1=104,2=270.000000
L 4.01041683 2.2880001 4.00833317 2.28986634 1 P 0 ;0,1=104,2=270.000000
L 4.00833317 2.28986634 4.0075 2.2919997 1 P 0 ;0,1=104,2=270.000000
L 4.0075 2.2919997 4.00833317 2.29413307 1 P 0 ;0,1=104,2=270.000000
L 4.00833317 2.29413307 4.01041683 2.2959998 1 P 0 ;0,1=104,2=270.000000
L 4.01041683 2.2959998 4.01333366 2.2968001 1 P 0 ;0,1=104,2=270.000000
L 4.01333366 2.2968001 4.01625049 2.29626644 1 P 0 ;0,1=104,2=270.000000
L 4.01625049 2.29626644 4.01833337 2.29493337 1 P 0 ;0,1=104,2=270.000000
L 4.01833337 2.29493337 4.01916654 2.29333327 1 P 0 ;0,1=104,2=270.000000
L 4.01916654 2.29333327 4.01916654 2.29066663 1 P 0 ;0,1=104,2=270.000000
L 4.01916654 2.29066663 4.02041703 2.28826663 1 P 0 ;0,1=104,2=270.000000
L 4.02041703 2.28826663 4.02291722 2.28666654 1 P 0 ;0,1=104,2=270.000000
L 4.02291722 2.28666654 4.02583327 2.28613327 1 P 0 ;0,1=104,2=270.000000
L 4.02583327 2.28613327 4.02875089 2.28666654 1 P 0 ;0,1=104,2=270.000000
L 4.02875089 2.28666654 4.03083376 2.2880001 1 P 0 ;0,1=104,2=270.000000
L 4.03083376 2.2880001 4.03208346 2.29013346 1 P 0 ;0,1=104,2=270.000000
L 4.03208346 2.29013346 4.0325 2.2919997 1 P 0 ;0,1=104,2=270.000000
L 4.02208406 2.30893317 4.01916654 2.3107999 1 P 0 ;0,1=104,2=270.000000
L 4.01916654 2.3107999 4.0175002 2.3124 1 P 0 ;0,1=104,2=270.000000
L 4.0175002 2.3124 4.01666703 2.31453337 1 P 0 ;0,1=104,2=270.000000
L 4.01666703 2.31453337 4.0175002 2.3164002 1 P 0 ;0,1=104,2=270.000000
L 4.0175002 2.3164002 4.01916654 2.31773327 1 P 0 ;0,1=104,2=270.000000
L 4.01916654 2.31773327 4.02166673 2.3188001 1 P 0 ;0,1=104,2=270.000000
L 4.02166673 2.3188001 4.02458356 2.31906673 1 P 0 ;0,1=104,2=270.000000
L 4.02458356 2.31906673 4.02708376 2.3188001 1 P 0 ;0,1=104,2=270.000000
L 4.02708376 2.3188001 4.02958396 2.31773327 1 P 0 ;0,1=104,2=270.000000
L 4.02958396 2.31773327 4.03166693 2.31613307 1 P 0 ;0,1=104,2=270.000000
L 4.03166693 2.31613307 4.0325 2.31426683 1 P 0 ;0,1=104,2=270.000000
L 4.0325 2.31426683 4.03166693 2.31213346 1 P 0 ;0,1=104,2=270.000000
L 4.03166693 2.31213346 4.02916742 2.31026663 1 P 0 ;0,1=104,2=270.000000
L 4.02916742 2.31026663 4.02541673 2.3091998 1 P 0 ;0,1=104,2=270.000000
L 4.02541673 2.3091998 4.0212502 2.30893317 1 P 0 ;0,1=104,2=270.000000
L 4.0212502 2.30893317 4.01583386 2.30946634 1 P 0 ;0,1=104,2=270.000000
L 4.01583386 2.30946634 4.01291634 2.31026663 1 P 0 ;0,1=104,2=270.000000
L 4.01291634 2.31026663 4.0100003 2.3115997 1 P 0 ;0,1=104,2=270.000000
L 4.0100003 2.3115997 4.00791663 2.31346654 1 P 0 ;0,1=104,2=270.000000
L 4.00791663 2.31346654 4.0075 2.31533327 1 P 0 ;0,1=104,2=270.000000
L 4.0075 2.31533327 4.00833317 2.3172 1 P 0 ;0,1=104,2=270.000000
L 4.00833317 2.3172 4.01041683 2.31853356 1 P 0 ;0,1=104,2=270.000000
L 4.3175 2.2209997 4.3425 2.2209997 1 P 0 ;0,1=105,2=270.000000
L 4.3175 2.21486673 4.3175 2.22713317 1 P 0 ;0,1=105,2=270.000000
L 4.3425 2.23766654 4.3175 2.23766654 1 P 0 ;0,1=105,2=270.000000
L 4.3175 2.23766654 4.3175 2.24406663 1 P 0 ;0,1=105,2=270.000000
L 4.3175 2.24406663 4.31875059 2.2462 1 P 0 ;0,1=105,2=270.000000
L 4.31875059 2.2462 4.32166663 2.2478001 1 P 0 ;0,1=105,2=270.000000
L 4.32166663 2.2478001 4.325 2.24833337 1 P 0 ;0,1=105,2=270.000000
L 4.325 2.24833337 4.32833337 2.2478001 1 P 0 ;0,1=105,2=270.000000
L 4.32833337 2.2478001 4.33083356 2.24646663 1 P 0 ;0,1=105,2=270.000000
L 4.33083356 2.24646663 4.33208406 2.24406663 1 P 0 ;0,1=105,2=270.000000
L 4.33208406 2.24406663 4.33208406 2.23766654 1 P 0 ;0,1=105,2=270.000000
L 4.3425 2.2649997 4.3175 2.2649997 1 P 0 ;0,1=105,2=270.000000
L 4.3175 2.2649997 4.3224997 2.2617999 1 P 0 ;0,1=105,2=270.000000
L 4.3425 2.2617999 4.3425 2.26819951 1 P 0 ;0,1=105,2=270.000000
L 4.3425 2.2869997 4.34208346 2.28886644 1 P 0 ;0,1=105,2=270.000000
L 4.34208346 2.28886644 4.34083376 2.2909998 1 P 0 ;0,1=105,2=270.000000
L 4.34083376 2.2909998 4.33875089 2.29233337 1 P 0 ;0,1=105,2=270.000000
L 4.33875089 2.29233337 4.33583327 2.29286663 1 P 0 ;0,1=105,2=270.000000
L 4.33583327 2.29286663 4.33291722 2.29233337 1 P 0 ;0,1=105,2=270.000000
L 4.33291722 2.29233337 4.33041703 2.29073327 1 P 0 ;0,1=105,2=270.000000
L 4.33041703 2.29073327 4.32916654 2.28833327 1 P 0 ;0,1=105,2=270.000000
L 4.32916654 2.28833327 4.32916654 2.28566663 1 P 0 ;0,1=105,2=270.000000
L 4.32916654 2.28566663 4.32833337 2.28406654 1 P 0 ;0,1=105,2=270.000000
L 4.32833337 2.28406654 4.32625049 2.28273297 1 P 0 ;0,1=105,2=270.000000
L 4.32625049 2.28273297 4.32333366 2.2821998 1 P 0 ;0,1=105,2=270.000000
L 4.32333366 2.2821998 4.32041683 2.2830001 1 P 0 ;0,1=105,2=270.000000
L 4.32041683 2.2830001 4.31833317 2.28486634 1 P 0 ;0,1=105,2=270.000000
L 4.31833317 2.28486634 4.3175 2.2869997 1 P 0 ;0,1=105,2=270.000000
L 4.3175 2.2869997 4.31833317 2.28913307 1 P 0 ;0,1=105,2=270.000000
L 4.31833317 2.28913307 4.32041683 2.2909998 1 P 0 ;0,1=105,2=270.000000
L 4.32041683 2.2909998 4.32333366 2.2918001 1 P 0 ;0,1=105,2=270.000000
L 4.32333366 2.2918001 4.32625049 2.29126644 1 P 0 ;0,1=105,2=270.000000
L 4.32625049 2.29126644 4.32833337 2.28993337 1 P 0 ;0,1=105,2=270.000000
L 4.32833337 2.28993337 4.32916654 2.28833327 1 P 0 ;0,1=105,2=270.000000
L 4.32916654 2.28833327 4.32916654 2.28566663 1 P 0 ;0,1=105,2=270.000000
L 4.32916654 2.28566663 4.33041703 2.28326663 1 P 0 ;0,1=105,2=270.000000
L 4.33041703 2.28326663 4.33291722 2.28166654 1 P 0 ;0,1=105,2=270.000000
L 4.33291722 2.28166654 4.33583327 2.28113327 1 P 0 ;0,1=105,2=270.000000
L 4.33583327 2.28113327 4.33875089 2.28166654 1 P 0 ;0,1=105,2=270.000000
L 4.33875089 2.28166654 4.34083376 2.2830001 1 P 0 ;0,1=105,2=270.000000
L 4.34083376 2.2830001 4.34208346 2.28513346 1 P 0 ;0,1=105,2=270.000000
L 4.34208346 2.28513346 4.3425 2.2869997 1 P 0 ;0,1=105,2=270.000000
L 4.3425 2.30846654 4.33708376 2.3089997 1 P 0 ;0,1=105,2=270.000000
L 4.33708376 2.3089997 4.33250069 2.3098 1 P 0 ;0,1=105,2=270.000000
L 4.33250069 2.3098 4.32833337 2.31086644 1 P 0 ;0,1=105,2=270.000000
L 4.32833337 2.31086644 4.3237502 2.3122 1 P 0 ;0,1=105,2=270.000000
L 4.3237502 2.3122 4.3175 2.31433337 1 P 0 ;0,1=105,2=270.000000
L 4.3175 2.31433337 4.3175 2.30366654 1 P 0 ;0,1=105,2=270.000000
L 4.3525 2.2209997 4.3775 2.2209997 1 P 0 ;0,1=106,2=270.000000
L 4.3525 2.21486673 4.3525 2.22713317 1 P 0 ;0,1=106,2=270.000000
L 4.3775 2.23766654 4.3525 2.23766654 1 P 0 ;0,1=106,2=270.000000
L 4.3525 2.23766654 4.3525 2.24406663 1 P 0 ;0,1=106,2=270.000000
L 4.3525 2.24406663 4.35375059 2.2462 1 P 0 ;0,1=106,2=270.000000
L 4.35375059 2.2462 4.35666663 2.2478001 1 P 0 ;0,1=106,2=270.000000
L 4.35666663 2.2478001 4.36 2.24833337 1 P 0 ;0,1=106,2=270.000000
L 4.36 2.24833337 4.36333337 2.2478001 1 P 0 ;0,1=106,2=270.000000
L 4.36333337 2.2478001 4.36583356 2.24646663 1 P 0 ;0,1=106,2=270.000000
L 4.36583356 2.24646663 4.36708406 2.24406663 1 P 0 ;0,1=106,2=270.000000
L 4.36708406 2.24406663 4.36708406 2.23766654 1 P 0 ;0,1=106,2=270.000000
L 4.3775 2.2649997 4.3525 2.2649997 1 P 0 ;0,1=106,2=270.000000
L 4.3525 2.2649997 4.3574997 2.2617999 1 P 0 ;0,1=106,2=270.000000
L 4.3775 2.2617999 4.3775 2.26819951 1 P 0 ;0,1=106,2=270.000000
L 4.3775 2.2869997 4.37708346 2.28886644 1 P 0 ;0,1=106,2=270.000000
L 4.37708346 2.28886644 4.37583376 2.2909998 1 P 0 ;0,1=106,2=270.000000
L 4.37583376 2.2909998 4.37375089 2.29233337 1 P 0 ;0,1=106,2=270.000000
L 4.37375089 2.29233337 4.37083327 2.29286663 1 P 0 ;0,1=106,2=270.000000
L 4.37083327 2.29286663 4.36791722 2.29233337 1 P 0 ;0,1=106,2=270.000000
L 4.36791722 2.29233337 4.36541703 2.29073327 1 P 0 ;0,1=106,2=270.000000
L 4.36541703 2.29073327 4.36416654 2.28833327 1 P 0 ;0,1=106,2=270.000000
L 4.36416654 2.28833327 4.36416654 2.28566663 1 P 0 ;0,1=106,2=270.000000
L 4.36416654 2.28566663 4.36333337 2.28406654 1 P 0 ;0,1=106,2=270.000000
L 4.36333337 2.28406654 4.36125049 2.28273297 1 P 0 ;0,1=106,2=270.000000
L 4.36125049 2.28273297 4.35833366 2.2821998 1 P 0 ;0,1=106,2=270.000000
L 4.35833366 2.2821998 4.35541683 2.2830001 1 P 0 ;0,1=106,2=270.000000
L 4.35541683 2.2830001 4.35333317 2.28486634 1 P 0 ;0,1=106,2=270.000000
L 4.35333317 2.28486634 4.3525 2.2869997 1 P 0 ;0,1=106,2=270.000000
L 4.3525 2.2869997 4.35333317 2.28913307 1 P 0 ;0,1=106,2=270.000000
L 4.35333317 2.28913307 4.35541683 2.2909998 1 P 0 ;0,1=106,2=270.000000
L 4.35541683 2.2909998 4.35833366 2.2918001 1 P 0 ;0,1=106,2=270.000000
L 4.35833366 2.2918001 4.36125049 2.29126644 1 P 0 ;0,1=106,2=270.000000
L 4.36125049 2.29126644 4.36333337 2.28993337 1 P 0 ;0,1=106,2=270.000000
L 4.36333337 2.28993337 4.36416654 2.28833327 1 P 0 ;0,1=106,2=270.000000
L 4.36416654 2.28833327 4.36416654 2.28566663 1 P 0 ;0,1=106,2=270.000000
L 4.36416654 2.28566663 4.36541703 2.28326663 1 P 0 ;0,1=106,2=270.000000
L 4.36541703 2.28326663 4.36791722 2.28166654 1 P 0 ;0,1=106,2=270.000000
L 4.36791722 2.28166654 4.37083327 2.28113327 1 P 0 ;0,1=106,2=270.000000
L 4.37083327 2.28113327 4.37375089 2.28166654 1 P 0 ;0,1=106,2=270.000000
L 4.37375089 2.28166654 4.37583376 2.2830001 1 P 0 ;0,1=106,2=270.000000
L 4.37583376 2.2830001 4.37708346 2.28513346 1 P 0 ;0,1=106,2=270.000000
L 4.37708346 2.28513346 4.3775 2.2869997 1 P 0 ;0,1=106,2=270.000000
L 4.3775 2.3089997 4.37708346 2.31086644 1 P 0 ;0,1=106,2=270.000000
L 4.37708346 2.31086644 4.37583376 2.3129998 1 P 0 ;0,1=106,2=270.000000
L 4.37583376 2.3129998 4.37375089 2.31433337 1 P 0 ;0,1=106,2=270.000000
L 4.37375089 2.31433337 4.37083327 2.31486663 1 P 0 ;0,1=106,2=270.000000
L 4.37083327 2.31486663 4.36791722 2.31433337 1 P 0 ;0,1=106,2=270.000000
L 4.36791722 2.31433337 4.36541703 2.31273327 1 P 0 ;0,1=106,2=270.000000
L 4.36541703 2.31273327 4.36416654 2.31033327 1 P 0 ;0,1=106,2=270.000000
L 4.36416654 2.31033327 4.36416654 2.30766663 1 P 0 ;0,1=106,2=270.000000
L 4.36416654 2.30766663 4.36333337 2.30606654 1 P 0 ;0,1=106,2=270.000000
L 4.36333337 2.30606654 4.36125049 2.30473297 1 P 0 ;0,1=106,2=270.000000
L 4.36125049 2.30473297 4.35833366 2.3041998 1 P 0 ;0,1=106,2=270.000000
L 4.35833366 2.3041998 4.35541683 2.3050001 1 P 0 ;0,1=106,2=270.000000
L 4.35541683 2.3050001 4.35333317 2.30686634 1 P 0 ;0,1=106,2=270.000000
L 4.35333317 2.30686634 4.3525 2.3089997 1 P 0 ;0,1=106,2=270.000000
L 4.3525 2.3089997 4.35333317 2.31113307 1 P 0 ;0,1=106,2=270.000000
L 4.35333317 2.31113307 4.35541683 2.3129998 1 P 0 ;0,1=106,2=270.000000
L 4.35541683 2.3129998 4.35833366 2.3138001 1 P 0 ;0,1=106,2=270.000000
L 4.35833366 2.3138001 4.36125049 2.31326644 1 P 0 ;0,1=106,2=270.000000
L 4.36125049 2.31326644 4.36333337 2.31193337 1 P 0 ;0,1=106,2=270.000000
L 4.36333337 2.31193337 4.36416654 2.31033327 1 P 0 ;0,1=106,2=270.000000
L 4.36416654 2.31033327 4.36416654 2.30766663 1 P 0 ;0,1=106,2=270.000000
L 4.36416654 2.30766663 4.36541703 2.30526663 1 P 0 ;0,1=106,2=270.000000
L 4.36541703 2.30526663 4.36791722 2.30366654 1 P 0 ;0,1=106,2=270.000000
L 4.36791722 2.30366654 4.37083327 2.30313327 1 P 0 ;0,1=106,2=270.000000
L 4.37083327 2.30313327 4.37375089 2.30366654 1 P 0 ;0,1=106,2=270.000000
L 4.37375089 2.30366654 4.37583376 2.3050001 1 P 0 ;0,1=106,2=270.000000
L 4.37583376 2.3050001 4.37708346 2.30713346 1 P 0 ;0,1=106,2=270.000000
L 4.37708346 2.30713346 4.3775 2.3089997 1 P 0 ;0,1=106,2=270.000000
L 4.7759997 1.1675 4.7759997 1.1425 1 P 0 ;0,1=107,2=0.000000
L 4.76986673 1.1675 4.78213317 1.1675 1 P 0 ;0,1=107,2=0.000000
L 4.79266654 1.1425 4.79266654 1.1675 1 P 0 ;0,1=107,2=0.000000
L 4.79266654 1.1675 4.79906663 1.1675 1 P 0 ;0,1=107,2=0.000000
L 4.79906663 1.1675 4.8012 1.16624941 1 P 0 ;0,1=107,2=0.000000
L 4.8012 1.16624941 4.8028001 1.16333337 1 P 0 ;0,1=107,2=0.000000
L 4.8028001 1.16333337 4.80333337 1.16 1 P 0 ;0,1=107,2=0.000000
L 4.80333337 1.16 4.8028001 1.15666663 1 P 0 ;0,1=107,2=0.000000
L 4.8028001 1.15666663 4.80146663 1.15416644 1 P 0 ;0,1=107,2=0.000000
L 4.80146663 1.15416644 4.79906663 1.15291594 1 P 0 ;0,1=107,2=0.000000
L 4.79906663 1.15291594 4.79266654 1.15291594 1 P 0 ;0,1=107,2=0.000000
L 4.8199997 1.1425 4.8199997 1.1675 1 P 0 ;0,1=107,2=0.000000
L 4.8199997 1.1675 4.8167999 1.1625003 1 P 0 ;0,1=107,2=0.000000
L 4.8167999 1.1425 4.82319951 1.1425 1 P 0 ;0,1=107,2=0.000000
L 4.83746634 1.14541604 4.83933317 1.14333307 1 P 0 ;0,1=107,2=0.000000
L 4.83933317 1.14333307 4.84146654 1.1425 1 P 0 ;0,1=107,2=0.000000
L 4.84146654 1.1425 4.8435999 1.14333307 1 P 0 ;0,1=107,2=0.000000
L 4.8435999 1.14333307 4.84546663 1.14583258 1 P 0 ;0,1=107,2=0.000000
L 4.84546663 1.14583258 4.8468001 1.14958327 1 P 0 ;0,1=107,2=0.000000
L 4.8468001 1.14958327 4.84733337 1.15333327 1 P 0 ;0,1=107,2=0.000000
L 4.84733337 1.15333327 4.84733337 1.15791634 1 P 0 ;0,1=107,2=0.000000
L 4.84733337 1.15791634 4.8468001 1.16166634 1 P 0 ;0,1=107,2=0.000000
L 4.8468001 1.16166634 4.84546663 1.1649997 1 P 0 ;0,1=107,2=0.000000
L 4.84546663 1.1649997 4.84386644 1.16666683 1 P 0 ;0,1=107,2=0.000000
L 4.84386644 1.16666683 4.8419997 1.1675 1 P 0 ;0,1=107,2=0.000000
L 4.8419997 1.1675 4.83986634 1.16666683 1 P 0 ;0,1=107,2=0.000000
L 4.83986634 1.16666683 4.83826663 1.1649997 1 P 0 ;0,1=107,2=0.000000
L 4.83826663 1.1649997 4.8371998 1.1625003 1 P 0 ;0,1=107,2=0.000000
L 4.8371998 1.1625003 4.83666654 1.15916614 1 P 0 ;0,1=107,2=0.000000
L 4.83666654 1.15916614 4.8371998 1.1562501 1 P 0 ;0,1=107,2=0.000000
L 4.8371998 1.1562501 4.83853327 1.15333327 1 P 0 ;0,1=107,2=0.000000
L 4.83853327 1.15333327 4.84013346 1.15166614 1 P 0 ;0,1=107,2=0.000000
L 4.84013346 1.15166614 4.8419997 1.15124961 1 P 0 ;0,1=107,2=0.000000
L 4.8419997 1.15124961 4.84413307 1.15208278 1 P 0 ;0,1=107,2=0.000000
L 4.84413307 1.15208278 4.84573327 1.15416644 1 P 0 ;0,1=107,2=0.000000
L 4.84573327 1.15416644 4.84733337 1.15791634 1 P 0 ;0,1=107,2=0.000000
L 4.85813327 1.14749961 4.85973297 1.14458287 1 P 0 ;0,1=107,2=0.000000
L 4.85973297 1.14458287 4.86186634 1.14291654 1 P 0 ;0,1=107,2=0.000000
L 4.86186634 1.14291654 4.86426683 1.1425 1 P 0 ;0,1=107,2=0.000000
L 4.86426683 1.1425 4.8664002 1.14291654 1 P 0 ;0,1=107,2=0.000000
L 4.8664002 1.14291654 4.86853356 1.14499941 1 P 0 ;0,1=107,2=0.000000
L 4.86853356 1.14499941 4.86986663 1.14749961 1 P 0 ;0,1=107,2=0.000000
L 4.86986663 1.14749961 4.87013317 1.1499999 1 P 0 ;0,1=107,2=0.000000
L 4.87013317 1.1499999 4.8696 1.15291594 1 P 0 ;0,1=107,2=0.000000
L 4.8696 1.15291594 4.86773327 1.15499961 1 P 0 ;0,1=107,2=0.000000
L 4.86773327 1.15499961 4.86586644 1.15583346 1 P 0 ;0,1=107,2=0.000000
L 4.86586644 1.15583346 4.86346654 1.15583346 1 P 0 ;0,1=107,2=0.000000
L 4.86586644 1.15583346 4.86746663 1.15708327 1 P 0 ;0,1=107,2=0.000000
L 4.86746663 1.15708327 4.8688001 1.15916614 1 P 0 ;0,1=107,2=0.000000
L 4.8688001 1.15916614 4.86933337 1.16166634 1 P 0 ;0,1=107,2=0.000000
L 4.86933337 1.16166634 4.8688001 1.16416654 1 P 0 ;0,1=107,2=0.000000
L 4.8688001 1.16416654 4.86746663 1.16624941 1 P 0 ;0,1=107,2=0.000000
L 4.86746663 1.16624941 4.86506663 1.1675 1 P 0 ;0,1=107,2=0.000000
L 4.86506663 1.1675 4.86266663 1.16708337 1 P 0 ;0,1=107,2=0.000000
L 4.86266663 1.16708337 4.86026663 1.16541634 1 P 0 ;0,1=107,2=0.000000
L 4.8109997 1.0625 4.8109997 1.0375 1 P 0 ;0,1=108,2=0.000000
L 4.80486673 1.0625 4.81713317 1.0625 1 P 0 ;0,1=108,2=0.000000
L 4.82766654 1.0375 4.82766654 1.0625 1 P 0 ;0,1=108,2=0.000000
L 4.82766654 1.0625 4.83406663 1.0625 1 P 0 ;0,1=108,2=0.000000
L 4.83406663 1.0625 4.8362 1.06124941 1 P 0 ;0,1=108,2=0.000000
L 4.8362 1.06124941 4.8378001 1.05833337 1 P 0 ;0,1=108,2=0.000000
L 4.8378001 1.05833337 4.83833337 1.055 1 P 0 ;0,1=108,2=0.000000
L 4.83833337 1.055 4.8378001 1.05166663 1 P 0 ;0,1=108,2=0.000000
L 4.8378001 1.05166663 4.83646663 1.04916644 1 P 0 ;0,1=108,2=0.000000
L 4.83646663 1.04916644 4.83406663 1.04791594 1 P 0 ;0,1=108,2=0.000000
L 4.83406663 1.04791594 4.82766654 1.04791594 1 P 0 ;0,1=108,2=0.000000
L 4.8549997 1.0375 4.8549997 1.0625 1 P 0 ;0,1=108,2=0.000000
L 4.8549997 1.0625 4.8517999 1.0575003 1 P 0 ;0,1=108,2=0.000000
L 4.8517999 1.0375 4.85819951 1.0375 1 P 0 ;0,1=108,2=0.000000
L 4.87246634 1.04041604 4.87433317 1.03833307 1 P 0 ;0,1=108,2=0.000000
L 4.87433317 1.03833307 4.87646654 1.0375 1 P 0 ;0,1=108,2=0.000000
L 4.87646654 1.0375 4.8785999 1.03833307 1 P 0 ;0,1=108,2=0.000000
L 4.8785999 1.03833307 4.88046663 1.04083258 1 P 0 ;0,1=108,2=0.000000
L 4.88046663 1.04083258 4.8818001 1.04458327 1 P 0 ;0,1=108,2=0.000000
L 4.8818001 1.04458327 4.88233337 1.04833327 1 P 0 ;0,1=108,2=0.000000
L 4.88233337 1.04833327 4.88233337 1.05291634 1 P 0 ;0,1=108,2=0.000000
L 4.88233337 1.05291634 4.8818001 1.05666634 1 P 0 ;0,1=108,2=0.000000
L 4.8818001 1.05666634 4.88046663 1.0599997 1 P 0 ;0,1=108,2=0.000000
L 4.88046663 1.0599997 4.87886644 1.06166683 1 P 0 ;0,1=108,2=0.000000
L 4.87886644 1.06166683 4.8769997 1.0625 1 P 0 ;0,1=108,2=0.000000
L 4.8769997 1.0625 4.87486634 1.06166683 1 P 0 ;0,1=108,2=0.000000
L 4.87486634 1.06166683 4.87326663 1.0599997 1 P 0 ;0,1=108,2=0.000000
L 4.87326663 1.0599997 4.8721998 1.0575003 1 P 0 ;0,1=108,2=0.000000
L 4.8721998 1.0575003 4.87166654 1.05416614 1 P 0 ;0,1=108,2=0.000000
L 4.87166654 1.05416614 4.8721998 1.0512501 1 P 0 ;0,1=108,2=0.000000
L 4.8721998 1.0512501 4.87353327 1.04833327 1 P 0 ;0,1=108,2=0.000000
L 4.87353327 1.04833327 4.87513346 1.04666614 1 P 0 ;0,1=108,2=0.000000
L 4.87513346 1.04666614 4.8769997 1.04624961 1 P 0 ;0,1=108,2=0.000000
L 4.8769997 1.04624961 4.87913307 1.04708278 1 P 0 ;0,1=108,2=0.000000
L 4.87913307 1.04708278 4.88073327 1.04916644 1 P 0 ;0,1=108,2=0.000000
L 4.88073327 1.04916644 4.88233337 1.05291634 1 P 0 ;0,1=108,2=0.000000
L 4.9022 1.0375 4.9022 1.0625 1 P 0 ;0,1=108,2=0.000000
L 4.9022 1.0625 4.89233297 1.04458327 1 P 0 ;0,1=108,2=0.000000
L 4.89233297 1.04458327 4.90566693 1.04458327 1 P 0 ;0,1=108,2=0.000000
L 4.1375 1.1159997 4.1625 1.1159997 1 P 0 ;0,1=109,2=270.000000
L 4.1375 1.10986673 4.1375 1.12213317 1 P 0 ;0,1=109,2=270.000000
L 4.1625 1.13266654 4.1375 1.13266654 1 P 0 ;0,1=109,2=270.000000
L 4.1375 1.13266654 4.1375 1.13906663 1 P 0 ;0,1=109,2=270.000000
L 4.1375 1.13906663 4.13875059 1.1412 1 P 0 ;0,1=109,2=270.000000
L 4.13875059 1.1412 4.14166663 1.1428001 1 P 0 ;0,1=109,2=270.000000
L 4.14166663 1.1428001 4.145 1.14333337 1 P 0 ;0,1=109,2=270.000000
L 4.145 1.14333337 4.14833337 1.1428001 1 P 0 ;0,1=109,2=270.000000
L 4.14833337 1.1428001 4.15083356 1.14146663 1 P 0 ;0,1=109,2=270.000000
L 4.15083356 1.14146663 4.15208406 1.13906663 1 P 0 ;0,1=109,2=270.000000
L 4.15208406 1.13906663 4.15208406 1.13266654 1 P 0 ;0,1=109,2=270.000000
L 4.1625 1.1599997 4.1375 1.1599997 1 P 0 ;0,1=109,2=270.000000
L 4.1375 1.1599997 4.1424997 1.1567999 1 P 0 ;0,1=109,2=270.000000
L 4.1625 1.1567999 4.1625 1.16319951 1 P 0 ;0,1=109,2=270.000000
L 4.15958396 1.17746634 4.16166693 1.17933317 1 P 0 ;0,1=109,2=270.000000
L 4.16166693 1.17933317 4.1625 1.18146654 1 P 0 ;0,1=109,2=270.000000
L 4.1625 1.18146654 4.16166693 1.1835999 1 P 0 ;0,1=109,2=270.000000
L 4.16166693 1.1835999 4.15916742 1.18546663 1 P 0 ;0,1=109,2=270.000000
L 4.15916742 1.18546663 4.15541673 1.1868001 1 P 0 ;0,1=109,2=270.000000
L 4.15541673 1.1868001 4.15166673 1.18733337 1 P 0 ;0,1=109,2=270.000000
L 4.15166673 1.18733337 4.14708366 1.18733337 1 P 0 ;0,1=109,2=270.000000
L 4.14708366 1.18733337 4.14333366 1.1868001 1 P 0 ;0,1=109,2=270.000000
L 4.14333366 1.1868001 4.1400003 1.18546663 1 P 0 ;0,1=109,2=270.000000
L 4.1400003 1.18546663 4.13833317 1.18386644 1 P 0 ;0,1=109,2=270.000000
L 4.13833317 1.18386644 4.1375 1.1819997 1 P 0 ;0,1=109,2=270.000000
L 4.1375 1.1819997 4.13833317 1.17986634 1 P 0 ;0,1=109,2=270.000000
L 4.13833317 1.17986634 4.1400003 1.17826663 1 P 0 ;0,1=109,2=270.000000
L 4.1400003 1.17826663 4.1424997 1.1771998 1 P 0 ;0,1=109,2=270.000000
L 4.1424997 1.1771998 4.14583386 1.17666654 1 P 0 ;0,1=109,2=270.000000
L 4.14583386 1.17666654 4.1487499 1.1771998 1 P 0 ;0,1=109,2=270.000000
L 4.1487499 1.1771998 4.15166673 1.17853327 1 P 0 ;0,1=109,2=270.000000
L 4.15166673 1.17853327 4.15333386 1.18013346 1 P 0 ;0,1=109,2=270.000000
L 4.15333386 1.18013346 4.15375039 1.1819997 1 P 0 ;0,1=109,2=270.000000
L 4.15375039 1.1819997 4.15291722 1.18413307 1 P 0 ;0,1=109,2=270.000000
L 4.15291722 1.18413307 4.15083356 1.18573327 1 P 0 ;0,1=109,2=270.000000
L 4.15083356 1.18573327 4.14708366 1.18733337 1 P 0 ;0,1=109,2=270.000000
L 4.15208406 1.19893317 4.14916654 1.2007999 1 P 0 ;0,1=109,2=270.000000
L 4.14916654 1.2007999 4.1475002 1.2024 1 P 0 ;0,1=109,2=270.000000
L 4.1475002 1.2024 4.14666703 1.20453337 1 P 0 ;0,1=109,2=270.000000
L 4.14666703 1.20453337 4.1475002 1.2064002 1 P 0 ;0,1=109,2=270.000000
L 4.1475002 1.2064002 4.14916654 1.20773327 1 P 0 ;0,1=109,2=270.000000
L 4.14916654 1.20773327 4.15166673 1.2088001 1 P 0 ;0,1=109,2=270.000000
L 4.15166673 1.2088001 4.15458356 1.20906673 1 P 0 ;0,1=109,2=270.000000
L 4.15458356 1.20906673 4.15708376 1.2088001 1 P 0 ;0,1=109,2=270.000000
L 4.15708376 1.2088001 4.15958396 1.20773327 1 P 0 ;0,1=109,2=270.000000
L 4.15958396 1.20773327 4.16166693 1.20613307 1 P 0 ;0,1=109,2=270.000000
L 4.16166693 1.20613307 4.1625 1.20426683 1 P 0 ;0,1=109,2=270.000000
L 4.1625 1.20426683 4.16166693 1.20213346 1 P 0 ;0,1=109,2=270.000000
L 4.16166693 1.20213346 4.15916742 1.20026663 1 P 0 ;0,1=109,2=270.000000
L 4.15916742 1.20026663 4.15541673 1.1991998 1 P 0 ;0,1=109,2=270.000000
L 4.15541673 1.1991998 4.1512502 1.19893317 1 P 0 ;0,1=109,2=270.000000
L 4.1512502 1.19893317 4.14583386 1.19946634 1 P 0 ;0,1=109,2=270.000000
L 4.14583386 1.19946634 4.14291634 1.20026663 1 P 0 ;0,1=109,2=270.000000
L 4.14291634 1.20026663 4.1400003 1.2015997 1 P 0 ;0,1=109,2=270.000000
L 4.1400003 1.2015997 4.13791663 1.20346654 1 P 0 ;0,1=109,2=270.000000
L 4.13791663 1.20346654 4.1375 1.20533327 1 P 0 ;0,1=109,2=270.000000
L 4.1375 1.20533327 4.13833317 1.2072 1 P 0 ;0,1=109,2=270.000000
L 4.13833317 1.2072 4.14041683 1.20853356 1 P 0 ;0,1=109,2=270.000000
L 4.8725 1.2959997 4.8975 1.2959997 1 P 0 ;0,1=110,2=270.000000
L 4.8725 1.28986673 4.8725 1.30213317 1 P 0 ;0,1=110,2=270.000000
L 4.8975 1.31266654 4.8725 1.31266654 1 P 0 ;0,1=110,2=270.000000
L 4.8725 1.31266654 4.8725 1.31906663 1 P 0 ;0,1=110,2=270.000000
L 4.8725 1.31906663 4.87375059 1.3212 1 P 0 ;0,1=110,2=270.000000
L 4.87375059 1.3212 4.87666663 1.3228001 1 P 0 ;0,1=110,2=270.000000
L 4.87666663 1.3228001 4.88 1.32333337 1 P 0 ;0,1=110,2=270.000000
L 4.88 1.32333337 4.88333337 1.3228001 1 P 0 ;0,1=110,2=270.000000
L 4.88333337 1.3228001 4.88583356 1.32146663 1 P 0 ;0,1=110,2=270.000000
L 4.88583356 1.32146663 4.88708406 1.31906663 1 P 0 ;0,1=110,2=270.000000
L 4.88708406 1.31906663 4.88708406 1.31266654 1 P 0 ;0,1=110,2=270.000000
L 4.8975 1.3399997 4.8725 1.3399997 1 P 0 ;0,1=110,2=270.000000
L 4.8725 1.3399997 4.8774997 1.3367999 1 P 0 ;0,1=110,2=270.000000
L 4.8975 1.3367999 4.8975 1.34319951 1 P 0 ;0,1=110,2=270.000000
L 4.89458396 1.35746634 4.89666693 1.35933317 1 P 0 ;0,1=110,2=270.000000
L 4.89666693 1.35933317 4.8975 1.36146654 1 P 0 ;0,1=110,2=270.000000
L 4.8975 1.36146654 4.89666693 1.3635999 1 P 0 ;0,1=110,2=270.000000
L 4.89666693 1.3635999 4.89416742 1.36546663 1 P 0 ;0,1=110,2=270.000000
L 4.89416742 1.36546663 4.89041673 1.3668001 1 P 0 ;0,1=110,2=270.000000
L 4.89041673 1.3668001 4.88666673 1.36733337 1 P 0 ;0,1=110,2=270.000000
L 4.88666673 1.36733337 4.88208366 1.36733337 1 P 0 ;0,1=110,2=270.000000
L 4.88208366 1.36733337 4.87833366 1.3668001 1 P 0 ;0,1=110,2=270.000000
L 4.87833366 1.3668001 4.8750003 1.36546663 1 P 0 ;0,1=110,2=270.000000
L 4.8750003 1.36546663 4.87333317 1.36386644 1 P 0 ;0,1=110,2=270.000000
L 4.87333317 1.36386644 4.8725 1.3619997 1 P 0 ;0,1=110,2=270.000000
L 4.8725 1.3619997 4.87333317 1.35986634 1 P 0 ;0,1=110,2=270.000000
L 4.87333317 1.35986634 4.8750003 1.35826663 1 P 0 ;0,1=110,2=270.000000
L 4.8750003 1.35826663 4.8774997 1.3571998 1 P 0 ;0,1=110,2=270.000000
L 4.8774997 1.3571998 4.88083386 1.35666654 1 P 0 ;0,1=110,2=270.000000
L 4.88083386 1.35666654 4.8837499 1.3571998 1 P 0 ;0,1=110,2=270.000000
L 4.8837499 1.3571998 4.88666673 1.35853327 1 P 0 ;0,1=110,2=270.000000
L 4.88666673 1.35853327 4.88833386 1.36013346 1 P 0 ;0,1=110,2=270.000000
L 4.88833386 1.36013346 4.88875039 1.3619997 1 P 0 ;0,1=110,2=270.000000
L 4.88875039 1.3619997 4.88791722 1.36413307 1 P 0 ;0,1=110,2=270.000000
L 4.88791722 1.36413307 4.88583356 1.36573327 1 P 0 ;0,1=110,2=270.000000
L 4.88583356 1.36573327 4.88208366 1.36733337 1 P 0 ;0,1=110,2=270.000000
L 4.89458396 1.37946634 4.89666693 1.38133317 1 P 0 ;0,1=110,2=270.000000
L 4.89666693 1.38133317 4.8975 1.38346654 1 P 0 ;0,1=110,2=270.000000
L 4.8975 1.38346654 4.89666693 1.3855999 1 P 0 ;0,1=110,2=270.000000
L 4.89666693 1.3855999 4.89416742 1.38746663 1 P 0 ;0,1=110,2=270.000000
L 4.89416742 1.38746663 4.89041673 1.3888001 1 P 0 ;0,1=110,2=270.000000
L 4.89041673 1.3888001 4.88666673 1.38933337 1 P 0 ;0,1=110,2=270.000000
L 4.88666673 1.38933337 4.88208366 1.38933337 1 P 0 ;0,1=110,2=270.000000
L 4.88208366 1.38933337 4.87833366 1.3888001 1 P 0 ;0,1=110,2=270.000000
L 4.87833366 1.3888001 4.8750003 1.38746663 1 P 0 ;0,1=110,2=270.000000
L 4.8750003 1.38746663 4.87333317 1.38586644 1 P 0 ;0,1=110,2=270.000000
L 4.87333317 1.38586644 4.8725 1.3839997 1 P 0 ;0,1=110,2=270.000000
L 4.8725 1.3839997 4.87333317 1.38186634 1 P 0 ;0,1=110,2=270.000000
L 4.87333317 1.38186634 4.8750003 1.38026663 1 P 0 ;0,1=110,2=270.000000
L 4.8750003 1.38026663 4.8774997 1.3791998 1 P 0 ;0,1=110,2=270.000000
L 4.8774997 1.3791998 4.88083386 1.37866654 1 P 0 ;0,1=110,2=270.000000
L 4.88083386 1.37866654 4.8837499 1.3791998 1 P 0 ;0,1=110,2=270.000000
L 4.8837499 1.3791998 4.88666673 1.38053327 1 P 0 ;0,1=110,2=270.000000
L 4.88666673 1.38053327 4.88833386 1.38213346 1 P 0 ;0,1=110,2=270.000000
L 4.88833386 1.38213346 4.88875039 1.3839997 1 P 0 ;0,1=110,2=270.000000
L 4.88875039 1.3839997 4.88791722 1.38613307 1 P 0 ;0,1=110,2=270.000000
L 4.88791722 1.38613307 4.88583356 1.38773327 1 P 0 ;0,1=110,2=270.000000
L 4.88583356 1.38773327 4.88208366 1.38933337 1 P 0 ;0,1=110,2=270.000000
L 4.2125 1.1209997 4.2375 1.1209997 1 P 0 ;0,1=111,2=270.000000
L 4.2125 1.11486673 4.2125 1.12713317 1 P 0 ;0,1=111,2=270.000000
L 4.2375 1.13766654 4.2125 1.13766654 1 P 0 ;0,1=111,2=270.000000
L 4.2125 1.13766654 4.2125 1.14406663 1 P 0 ;0,1=111,2=270.000000
L 4.2125 1.14406663 4.21375059 1.1462 1 P 0 ;0,1=111,2=270.000000
L 4.21375059 1.1462 4.21666663 1.1478001 1 P 0 ;0,1=111,2=270.000000
L 4.21666663 1.1478001 4.22 1.14833337 1 P 0 ;0,1=111,2=270.000000
L 4.22 1.14833337 4.22333337 1.1478001 1 P 0 ;0,1=111,2=270.000000
L 4.22333337 1.1478001 4.22583356 1.14646663 1 P 0 ;0,1=111,2=270.000000
L 4.22583356 1.14646663 4.22708406 1.14406663 1 P 0 ;0,1=111,2=270.000000
L 4.22708406 1.14406663 4.22708406 1.13766654 1 P 0 ;0,1=111,2=270.000000
L 4.21666663 1.15993317 4.21416713 1.16153327 1 P 0 ;0,1=111,2=270.000000
L 4.21416713 1.16153327 4.21291663 1.1634 1 P 0 ;0,1=111,2=270.000000
L 4.21291663 1.1634 4.2125 1.16553337 1 P 0 ;0,1=111,2=270.000000
L 4.2125 1.16553337 4.21333317 1.1682 1 P 0 ;0,1=111,2=270.000000
L 4.21333317 1.1682 4.21541683 1.17006673 1 P 0 ;0,1=111,2=270.000000
L 4.21541683 1.17006673 4.21791634 1.1706 1 P 0 ;0,1=111,2=270.000000
L 4.21791634 1.1706 4.22041732 1.17033337 1 P 0 ;0,1=111,2=270.000000
L 4.22041732 1.17033337 4.2225002 1.16926644 1 P 0 ;0,1=111,2=270.000000
L 4.2225002 1.16926644 4.22666673 1.16393327 1 P 0 ;0,1=111,2=270.000000
L 4.22666673 1.16393327 4.22958356 1.16153327 1 P 0 ;0,1=111,2=270.000000
L 4.22958356 1.16153327 4.23375089 1.15993317 1 P 0 ;0,1=111,2=270.000000
L 4.23375089 1.15993317 4.2375 1.1593999 1 P 0 ;0,1=111,2=270.000000
L 4.2375 1.1593999 4.2375 1.1706 1 P 0 ;0,1=111,2=270.000000
L 4.2125 1.1869997 4.21333317 1.18486634 1 P 0 ;0,1=111,2=270.000000
L 4.21333317 1.18486634 4.21541683 1.18326663 1 P 0 ;0,1=111,2=270.000000
L 4.21541683 1.18326663 4.21791634 1.1821998 1 P 0 ;0,1=111,2=270.000000
L 4.21791634 1.1821998 4.22125049 1.1813999 1 P 0 ;0,1=111,2=270.000000
L 4.22125049 1.1813999 4.22500039 1.18113327 1 P 0 ;0,1=111,2=270.000000
L 4.22500039 1.18113327 4.22875039 1.1813999 1 P 0 ;0,1=111,2=270.000000
L 4.22875039 1.1813999 4.23208376 1.1821998 1 P 0 ;0,1=111,2=270.000000
L 4.23208376 1.1821998 4.23458396 1.18326663 1 P 0 ;0,1=111,2=270.000000
L 4.23458396 1.18326663 4.23666693 1.18486634 1 P 0 ;0,1=111,2=270.000000
L 4.23666693 1.18486634 4.2375 1.1869997 1 P 0 ;0,1=111,2=270.000000
L 4.2375 1.1869997 4.23666693 1.18913307 1 P 0 ;0,1=111,2=270.000000
L 4.23666693 1.18913307 4.23458396 1.19073327 1 P 0 ;0,1=111,2=270.000000
L 4.23458396 1.19073327 4.23208376 1.1918001 1 P 0 ;0,1=111,2=270.000000
L 4.23208376 1.1918001 4.22875039 1.1926 1 P 0 ;0,1=111,2=270.000000
L 4.22875039 1.1926 4.22500039 1.19286663 1 P 0 ;0,1=111,2=270.000000
L 4.22500039 1.19286663 4.22125049 1.1926 1 P 0 ;0,1=111,2=270.000000
L 4.22125049 1.1926 4.21791634 1.1918001 1 P 0 ;0,1=111,2=270.000000
L 4.21791634 1.1918001 4.21541683 1.19073327 1 P 0 ;0,1=111,2=270.000000
L 4.21541683 1.19073327 4.21333317 1.18913307 1 P 0 ;0,1=111,2=270.000000
L 4.21333317 1.18913307 4.2125 1.1869997 1 P 0 ;0,1=111,2=270.000000
L 4.2125 1.2089997 4.21333317 1.20686634 1 P 0 ;0,1=111,2=270.000000
L 4.21333317 1.20686634 4.21541683 1.20526663 1 P 0 ;0,1=111,2=270.000000
L 4.21541683 1.20526663 4.21791634 1.2041998 1 P 0 ;0,1=111,2=270.000000
L 4.21791634 1.2041998 4.22125049 1.2033999 1 P 0 ;0,1=111,2=270.000000
L 4.22125049 1.2033999 4.22500039 1.20313327 1 P 0 ;0,1=111,2=270.000000
L 4.22500039 1.20313327 4.22875039 1.2033999 1 P 0 ;0,1=111,2=270.000000
L 4.22875039 1.2033999 4.23208376 1.2041998 1 P 0 ;0,1=111,2=270.000000
L 4.23208376 1.2041998 4.23458396 1.20526663 1 P 0 ;0,1=111,2=270.000000
L 4.23458396 1.20526663 4.23666693 1.20686634 1 P 0 ;0,1=111,2=270.000000
L 4.23666693 1.20686634 4.2375 1.2089997 1 P 0 ;0,1=111,2=270.000000
L 4.2375 1.2089997 4.23666693 1.21113307 1 P 0 ;0,1=111,2=270.000000
L 4.23666693 1.21113307 4.23458396 1.21273327 1 P 0 ;0,1=111,2=270.000000
L 4.23458396 1.21273327 4.23208376 1.2138001 1 P 0 ;0,1=111,2=270.000000
L 4.23208376 1.2138001 4.22875039 1.2146 1 P 0 ;0,1=111,2=270.000000
L 4.22875039 1.2146 4.22500039 1.21486663 1 P 0 ;0,1=111,2=270.000000
L 4.22500039 1.21486663 4.22125049 1.2146 1 P 0 ;0,1=111,2=270.000000
L 4.22125049 1.2146 4.21791634 1.2138001 1 P 0 ;0,1=111,2=270.000000
L 4.21791634 1.2138001 4.21541683 1.21273327 1 P 0 ;0,1=111,2=270.000000
L 4.21541683 1.21273327 4.21333317 1.21113307 1 P 0 ;0,1=111,2=270.000000
L 4.21333317 1.21113307 4.2125 1.2089997 1 P 0 ;0,1=111,2=270.000000
L 4.8109997 1.2125 4.8109997 1.1875 1 P 0 ;0,1=112,2=0.000000
L 4.80486673 1.2125 4.81713317 1.2125 1 P 0 ;0,1=112,2=0.000000
L 4.82766654 1.1875 4.82766654 1.2125 1 P 0 ;0,1=112,2=0.000000
L 4.82766654 1.2125 4.83406663 1.2125 1 P 0 ;0,1=112,2=0.000000
L 4.83406663 1.2125 4.8362 1.21124941 1 P 0 ;0,1=112,2=0.000000
L 4.8362 1.21124941 4.8378001 1.20833337 1 P 0 ;0,1=112,2=0.000000
L 4.8378001 1.20833337 4.83833337 1.205 1 P 0 ;0,1=112,2=0.000000
L 4.83833337 1.205 4.8378001 1.20166663 1 P 0 ;0,1=112,2=0.000000
L 4.8378001 1.20166663 4.83646663 1.19916644 1 P 0 ;0,1=112,2=0.000000
L 4.83646663 1.19916644 4.83406663 1.19791594 1 P 0 ;0,1=112,2=0.000000
L 4.83406663 1.19791594 4.82766654 1.19791594 1 P 0 ;0,1=112,2=0.000000
L 4.84993317 1.20833337 4.85153327 1.21083287 1 P 0 ;0,1=112,2=0.000000
L 4.85153327 1.21083287 4.8534 1.21208337 1 P 0 ;0,1=112,2=0.000000
L 4.8534 1.21208337 4.85553337 1.2125 1 P 0 ;0,1=112,2=0.000000
L 4.85553337 1.2125 4.8582 1.21166683 1 P 0 ;0,1=112,2=0.000000
L 4.8582 1.21166683 4.86006673 1.20958317 1 P 0 ;0,1=112,2=0.000000
L 4.86006673 1.20958317 4.8606 1.20708366 1 P 0 ;0,1=112,2=0.000000
L 4.8606 1.20708366 4.86033337 1.20458268 1 P 0 ;0,1=112,2=0.000000
L 4.86033337 1.20458268 4.85926644 1.2024998 1 P 0 ;0,1=112,2=0.000000
L 4.85926644 1.2024998 4.85393327 1.19833327 1 P 0 ;0,1=112,2=0.000000
L 4.85393327 1.19833327 4.85153327 1.19541644 1 P 0 ;0,1=112,2=0.000000
L 4.85153327 1.19541644 4.84993317 1.19124911 1 P 0 ;0,1=112,2=0.000000
L 4.84993317 1.19124911 4.8493999 1.1875 1 P 0 ;0,1=112,2=0.000000
L 4.8493999 1.1875 4.8606 1.1875 1 P 0 ;0,1=112,2=0.000000
L 4.8769997 1.2125 4.87486634 1.21166683 1 P 0 ;0,1=112,2=0.000000
L 4.87486634 1.21166683 4.87326663 1.20958317 1 P 0 ;0,1=112,2=0.000000
L 4.87326663 1.20958317 4.8721998 1.20708366 1 P 0 ;0,1=112,2=0.000000
L 4.8721998 1.20708366 4.8713999 1.20374951 1 P 0 ;0,1=112,2=0.000000
L 4.8713999 1.20374951 4.87113327 1.19999961 1 P 0 ;0,1=112,2=0.000000
L 4.87113327 1.19999961 4.8713999 1.19624961 1 P 0 ;0,1=112,2=0.000000
L 4.8713999 1.19624961 4.8721998 1.19291624 1 P 0 ;0,1=112,2=0.000000
L 4.8721998 1.19291624 4.87326663 1.19041604 1 P 0 ;0,1=112,2=0.000000
L 4.87326663 1.19041604 4.87486634 1.18833307 1 P 0 ;0,1=112,2=0.000000
L 4.87486634 1.18833307 4.8769997 1.1875 1 P 0 ;0,1=112,2=0.000000
L 4.8769997 1.1875 4.87913307 1.18833307 1 P 0 ;0,1=112,2=0.000000
L 4.87913307 1.18833307 4.88073327 1.19041604 1 P 0 ;0,1=112,2=0.000000
L 4.88073327 1.19041604 4.8818001 1.19291624 1 P 0 ;0,1=112,2=0.000000
L 4.8818001 1.19291624 4.8826 1.19624961 1 P 0 ;0,1=112,2=0.000000
L 4.8826 1.19624961 4.88286663 1.19999961 1 P 0 ;0,1=112,2=0.000000
L 4.88286663 1.19999961 4.8826 1.20374951 1 P 0 ;0,1=112,2=0.000000
L 4.8826 1.20374951 4.8818001 1.20708366 1 P 0 ;0,1=112,2=0.000000
L 4.8818001 1.20708366 4.88073327 1.20958317 1 P 0 ;0,1=112,2=0.000000
L 4.88073327 1.20958317 4.87913307 1.21166683 1 P 0 ;0,1=112,2=0.000000
L 4.87913307 1.21166683 4.8769997 1.2125 1 P 0 ;0,1=112,2=0.000000
L 4.8989997 1.1875 4.8989997 1.2125 1 P 0 ;0,1=112,2=0.000000
L 4.8989997 1.2125 4.8957999 1.2075003 1 P 0 ;0,1=112,2=0.000000
L 4.8957999 1.1875 4.90219951 1.1875 1 P 0 ;0,1=112,2=0.000000
L 4.7025 1.0009997 4.7275 1.0009997 1 P 0 ;0,1=113,2=270.000000
L 4.7025 0.99486673 4.7025 1.00713317 1 P 0 ;0,1=113,2=270.000000
L 4.7275 1.01766654 4.7025 1.01766654 1 P 0 ;0,1=113,2=270.000000
L 4.7025 1.01766654 4.7025 1.02406663 1 P 0 ;0,1=113,2=270.000000
L 4.7025 1.02406663 4.70375059 1.0262 1 P 0 ;0,1=113,2=270.000000
L 4.70375059 1.0262 4.70666663 1.0278001 1 P 0 ;0,1=113,2=270.000000
L 4.70666663 1.0278001 4.71 1.02833337 1 P 0 ;0,1=113,2=270.000000
L 4.71 1.02833337 4.71333337 1.0278001 1 P 0 ;0,1=113,2=270.000000
L 4.71333337 1.0278001 4.71583356 1.02646663 1 P 0 ;0,1=113,2=270.000000
L 4.71583356 1.02646663 4.71708406 1.02406663 1 P 0 ;0,1=113,2=270.000000
L 4.71708406 1.02406663 4.71708406 1.01766654 1 P 0 ;0,1=113,2=270.000000
L 4.70666663 1.03993317 4.70416713 1.04153327 1 P 0 ;0,1=113,2=270.000000
L 4.70416713 1.04153327 4.70291663 1.0434 1 P 0 ;0,1=113,2=270.000000
L 4.70291663 1.0434 4.7025 1.04553337 1 P 0 ;0,1=113,2=270.000000
L 4.7025 1.04553337 4.70333317 1.0482 1 P 0 ;0,1=113,2=270.000000
L 4.70333317 1.0482 4.70541683 1.05006673 1 P 0 ;0,1=113,2=270.000000
L 4.70541683 1.05006673 4.70791634 1.0506 1 P 0 ;0,1=113,2=270.000000
L 4.70791634 1.0506 4.71041732 1.05033337 1 P 0 ;0,1=113,2=270.000000
L 4.71041732 1.05033337 4.7125002 1.04926644 1 P 0 ;0,1=113,2=270.000000
L 4.7125002 1.04926644 4.71666673 1.04393327 1 P 0 ;0,1=113,2=270.000000
L 4.71666673 1.04393327 4.71958356 1.04153327 1 P 0 ;0,1=113,2=270.000000
L 4.71958356 1.04153327 4.72375089 1.03993317 1 P 0 ;0,1=113,2=270.000000
L 4.72375089 1.03993317 4.7275 1.0393999 1 P 0 ;0,1=113,2=270.000000
L 4.7275 1.0393999 4.7275 1.0506 1 P 0 ;0,1=113,2=270.000000
L 4.7025 1.0669997 4.70333317 1.06486634 1 P 0 ;0,1=113,2=270.000000
L 4.70333317 1.06486634 4.70541683 1.06326663 1 P 0 ;0,1=113,2=270.000000
L 4.70541683 1.06326663 4.70791634 1.0621998 1 P 0 ;0,1=113,2=270.000000
L 4.70791634 1.0621998 4.71125049 1.0613999 1 P 0 ;0,1=113,2=270.000000
L 4.71125049 1.0613999 4.71500039 1.06113327 1 P 0 ;0,1=113,2=270.000000
L 4.71500039 1.06113327 4.71875039 1.0613999 1 P 0 ;0,1=113,2=270.000000
L 4.71875039 1.0613999 4.72208376 1.0621998 1 P 0 ;0,1=113,2=270.000000
L 4.72208376 1.0621998 4.72458396 1.06326663 1 P 0 ;0,1=113,2=270.000000
L 4.72458396 1.06326663 4.72666693 1.06486634 1 P 0 ;0,1=113,2=270.000000
L 4.72666693 1.06486634 4.7275 1.0669997 1 P 0 ;0,1=113,2=270.000000
L 4.7275 1.0669997 4.72666693 1.06913307 1 P 0 ;0,1=113,2=270.000000
L 4.72666693 1.06913307 4.72458396 1.07073327 1 P 0 ;0,1=113,2=270.000000
L 4.72458396 1.07073327 4.72208376 1.0718001 1 P 0 ;0,1=113,2=270.000000
L 4.72208376 1.0718001 4.71875039 1.0726 1 P 0 ;0,1=113,2=270.000000
L 4.71875039 1.0726 4.71500039 1.07286663 1 P 0 ;0,1=113,2=270.000000
L 4.71500039 1.07286663 4.71125049 1.0726 1 P 0 ;0,1=113,2=270.000000
L 4.71125049 1.0726 4.70791634 1.0718001 1 P 0 ;0,1=113,2=270.000000
L 4.70791634 1.0718001 4.70541683 1.07073327 1 P 0 ;0,1=113,2=270.000000
L 4.70541683 1.07073327 4.70333317 1.06913307 1 P 0 ;0,1=113,2=270.000000
L 4.70333317 1.06913307 4.7025 1.0669997 1 P 0 ;0,1=113,2=270.000000
L 4.70666663 1.08393317 4.70416713 1.08553327 1 P 0 ;0,1=113,2=270.000000
L 4.70416713 1.08553327 4.70291663 1.0874 1 P 0 ;0,1=113,2=270.000000
L 4.70291663 1.0874 4.7025 1.08953337 1 P 0 ;0,1=113,2=270.000000
L 4.7025 1.08953337 4.70333317 1.0922 1 P 0 ;0,1=113,2=270.000000
L 4.70333317 1.0922 4.70541683 1.09406673 1 P 0 ;0,1=113,2=270.000000
L 4.70541683 1.09406673 4.70791634 1.0946 1 P 0 ;0,1=113,2=270.000000
L 4.70791634 1.0946 4.71041732 1.09433337 1 P 0 ;0,1=113,2=270.000000
L 4.71041732 1.09433337 4.7125002 1.09326644 1 P 0 ;0,1=113,2=270.000000
L 4.7125002 1.09326644 4.71666673 1.08793327 1 P 0 ;0,1=113,2=270.000000
L 4.71666673 1.08793327 4.71958356 1.08553327 1 P 0 ;0,1=113,2=270.000000
L 4.71958356 1.08553327 4.72375089 1.08393317 1 P 0 ;0,1=113,2=270.000000
L 4.72375089 1.08393317 4.7275 1.0833999 1 P 0 ;0,1=113,2=270.000000
L 4.7275 1.0833999 4.7275 1.0946 1 P 0 ;0,1=113,2=270.000000
L 4.7425 1.0009997 4.7675 1.0009997 1 P 0 ;0,1=114,2=270.000000
L 4.7425 0.99486673 4.7425 1.00713317 1 P 0 ;0,1=114,2=270.000000
L 4.7675 1.01766654 4.7425 1.01766654 1 P 0 ;0,1=114,2=270.000000
L 4.7425 1.01766654 4.7425 1.02406663 1 P 0 ;0,1=114,2=270.000000
L 4.7425 1.02406663 4.74375059 1.0262 1 P 0 ;0,1=114,2=270.000000
L 4.74375059 1.0262 4.74666663 1.0278001 1 P 0 ;0,1=114,2=270.000000
L 4.74666663 1.0278001 4.75 1.02833337 1 P 0 ;0,1=114,2=270.000000
L 4.75 1.02833337 4.75333337 1.0278001 1 P 0 ;0,1=114,2=270.000000
L 4.75333337 1.0278001 4.75583356 1.02646663 1 P 0 ;0,1=114,2=270.000000
L 4.75583356 1.02646663 4.75708406 1.02406663 1 P 0 ;0,1=114,2=270.000000
L 4.75708406 1.02406663 4.75708406 1.01766654 1 P 0 ;0,1=114,2=270.000000
L 4.74666663 1.03993317 4.74416713 1.04153327 1 P 0 ;0,1=114,2=270.000000
L 4.74416713 1.04153327 4.74291663 1.0434 1 P 0 ;0,1=114,2=270.000000
L 4.74291663 1.0434 4.7425 1.04553337 1 P 0 ;0,1=114,2=270.000000
L 4.7425 1.04553337 4.74333317 1.0482 1 P 0 ;0,1=114,2=270.000000
L 4.74333317 1.0482 4.74541683 1.05006673 1 P 0 ;0,1=114,2=270.000000
L 4.74541683 1.05006673 4.74791634 1.0506 1 P 0 ;0,1=114,2=270.000000
L 4.74791634 1.0506 4.75041732 1.05033337 1 P 0 ;0,1=114,2=270.000000
L 4.75041732 1.05033337 4.7525002 1.04926644 1 P 0 ;0,1=114,2=270.000000
L 4.7525002 1.04926644 4.75666673 1.04393327 1 P 0 ;0,1=114,2=270.000000
L 4.75666673 1.04393327 4.75958356 1.04153327 1 P 0 ;0,1=114,2=270.000000
L 4.75958356 1.04153327 4.76375089 1.03993317 1 P 0 ;0,1=114,2=270.000000
L 4.76375089 1.03993317 4.7675 1.0393999 1 P 0 ;0,1=114,2=270.000000
L 4.7675 1.0393999 4.7675 1.0506 1 P 0 ;0,1=114,2=270.000000
L 4.7425 1.0669997 4.74333317 1.06486634 1 P 0 ;0,1=114,2=270.000000
L 4.74333317 1.06486634 4.74541683 1.06326663 1 P 0 ;0,1=114,2=270.000000
L 4.74541683 1.06326663 4.74791634 1.0621998 1 P 0 ;0,1=114,2=270.000000
L 4.74791634 1.0621998 4.75125049 1.0613999 1 P 0 ;0,1=114,2=270.000000
L 4.75125049 1.0613999 4.75500039 1.06113327 1 P 0 ;0,1=114,2=270.000000
L 4.75500039 1.06113327 4.75875039 1.0613999 1 P 0 ;0,1=114,2=270.000000
L 4.75875039 1.0613999 4.76208376 1.0621998 1 P 0 ;0,1=114,2=270.000000
L 4.76208376 1.0621998 4.76458396 1.06326663 1 P 0 ;0,1=114,2=270.000000
L 4.76458396 1.06326663 4.76666693 1.06486634 1 P 0 ;0,1=114,2=270.000000
L 4.76666693 1.06486634 4.7675 1.0669997 1 P 0 ;0,1=114,2=270.000000
L 4.7675 1.0669997 4.76666693 1.06913307 1 P 0 ;0,1=114,2=270.000000
L 4.76666693 1.06913307 4.76458396 1.07073327 1 P 0 ;0,1=114,2=270.000000
L 4.76458396 1.07073327 4.76208376 1.0718001 1 P 0 ;0,1=114,2=270.000000
L 4.76208376 1.0718001 4.75875039 1.0726 1 P 0 ;0,1=114,2=270.000000
L 4.75875039 1.0726 4.75500039 1.07286663 1 P 0 ;0,1=114,2=270.000000
L 4.75500039 1.07286663 4.75125049 1.0726 1 P 0 ;0,1=114,2=270.000000
L 4.75125049 1.0726 4.74791634 1.0718001 1 P 0 ;0,1=114,2=270.000000
L 4.74791634 1.0718001 4.74541683 1.07073327 1 P 0 ;0,1=114,2=270.000000
L 4.74541683 1.07073327 4.74333317 1.06913307 1 P 0 ;0,1=114,2=270.000000
L 4.74333317 1.06913307 4.7425 1.0669997 1 P 0 ;0,1=114,2=270.000000
L 4.76250039 1.08313327 4.76541713 1.08473297 1 P 0 ;0,1=114,2=270.000000
L 4.76541713 1.08473297 4.76708346 1.08686634 1 P 0 ;0,1=114,2=270.000000
L 4.76708346 1.08686634 4.7675 1.08926683 1 P 0 ;0,1=114,2=270.000000
L 4.7675 1.08926683 4.76708346 1.0914002 1 P 0 ;0,1=114,2=270.000000
L 4.76708346 1.0914002 4.76500059 1.09353356 1 P 0 ;0,1=114,2=270.000000
L 4.76500059 1.09353356 4.76250039 1.09486663 1 P 0 ;0,1=114,2=270.000000
L 4.76250039 1.09486663 4.7600001 1.09513317 1 P 0 ;0,1=114,2=270.000000
L 4.7600001 1.09513317 4.75708406 1.0946 1 P 0 ;0,1=114,2=270.000000
L 4.75708406 1.0946 4.75500039 1.09273327 1 P 0 ;0,1=114,2=270.000000
L 4.75500039 1.09273327 4.75416654 1.09086644 1 P 0 ;0,1=114,2=270.000000
L 4.75416654 1.09086644 4.75416654 1.08846654 1 P 0 ;0,1=114,2=270.000000
L 4.75416654 1.09086644 4.75291673 1.09246663 1 P 0 ;0,1=114,2=270.000000
L 4.75291673 1.09246663 4.75083386 1.0938001 1 P 0 ;0,1=114,2=270.000000
L 4.75083386 1.0938001 4.74833366 1.09433337 1 P 0 ;0,1=114,2=270.000000
L 4.74833366 1.09433337 4.74583346 1.0938001 1 P 0 ;0,1=114,2=270.000000
L 4.74583346 1.0938001 4.74375059 1.09246663 1 P 0 ;0,1=114,2=270.000000
L 4.74375059 1.09246663 4.7425 1.09006663 1 P 0 ;0,1=114,2=270.000000
L 4.7425 1.09006663 4.74291663 1.08766663 1 P 0 ;0,1=114,2=270.000000
L 4.74291663 1.08766663 4.74458366 1.08526663 1 P 0 ;0,1=114,2=270.000000
L 4.2709997 1.2025 4.2709997 1.1775 1 P 0 ;0,1=115,2=0.000000
L 4.26486673 1.2025 4.27713317 1.2025 1 P 0 ;0,1=115,2=0.000000
L 4.28766654 1.1775 4.28766654 1.2025 1 P 0 ;0,1=115,2=0.000000
L 4.28766654 1.2025 4.29406663 1.2025 1 P 0 ;0,1=115,2=0.000000
L 4.29406663 1.2025 4.2962 1.20124941 1 P 0 ;0,1=115,2=0.000000
L 4.2962 1.20124941 4.2978001 1.19833337 1 P 0 ;0,1=115,2=0.000000
L 4.2978001 1.19833337 4.29833337 1.195 1 P 0 ;0,1=115,2=0.000000
L 4.29833337 1.195 4.2978001 1.19166663 1 P 0 ;0,1=115,2=0.000000
L 4.2978001 1.19166663 4.29646663 1.18916644 1 P 0 ;0,1=115,2=0.000000
L 4.29646663 1.18916644 4.29406663 1.18791594 1 P 0 ;0,1=115,2=0.000000
L 4.29406663 1.18791594 4.28766654 1.18791594 1 P 0 ;0,1=115,2=0.000000
L 4.30993317 1.19833337 4.31153327 1.20083287 1 P 0 ;0,1=115,2=0.000000
L 4.31153327 1.20083287 4.3134 1.20208337 1 P 0 ;0,1=115,2=0.000000
L 4.3134 1.20208337 4.31553337 1.2025 1 P 0 ;0,1=115,2=0.000000
L 4.31553337 1.2025 4.3182 1.20166683 1 P 0 ;0,1=115,2=0.000000
L 4.3182 1.20166683 4.32006673 1.19958317 1 P 0 ;0,1=115,2=0.000000
L 4.32006673 1.19958317 4.3206 1.19708366 1 P 0 ;0,1=115,2=0.000000
L 4.3206 1.19708366 4.32033337 1.19458268 1 P 0 ;0,1=115,2=0.000000
L 4.32033337 1.19458268 4.31926644 1.1924998 1 P 0 ;0,1=115,2=0.000000
L 4.31926644 1.1924998 4.31393327 1.18833327 1 P 0 ;0,1=115,2=0.000000
L 4.31393327 1.18833327 4.31153327 1.18541644 1 P 0 ;0,1=115,2=0.000000
L 4.31153327 1.18541644 4.30993317 1.18124911 1 P 0 ;0,1=115,2=0.000000
L 4.30993317 1.18124911 4.3093999 1.1775 1 P 0 ;0,1=115,2=0.000000
L 4.3093999 1.1775 4.3206 1.1775 1 P 0 ;0,1=115,2=0.000000
L 4.3369997 1.2025 4.33486634 1.20166683 1 P 0 ;0,1=115,2=0.000000
L 4.33486634 1.20166683 4.33326663 1.19958317 1 P 0 ;0,1=115,2=0.000000
L 4.33326663 1.19958317 4.3321998 1.19708366 1 P 0 ;0,1=115,2=0.000000
L 4.3321998 1.19708366 4.3313999 1.19374951 1 P 0 ;0,1=115,2=0.000000
L 4.3313999 1.19374951 4.33113327 1.18999961 1 P 0 ;0,1=115,2=0.000000
L 4.33113327 1.18999961 4.3313999 1.18624961 1 P 0 ;0,1=115,2=0.000000
L 4.3313999 1.18624961 4.3321998 1.18291624 1 P 0 ;0,1=115,2=0.000000
L 4.3321998 1.18291624 4.33326663 1.18041604 1 P 0 ;0,1=115,2=0.000000
L 4.33326663 1.18041604 4.33486634 1.17833307 1 P 0 ;0,1=115,2=0.000000
L 4.33486634 1.17833307 4.3369997 1.1775 1 P 0 ;0,1=115,2=0.000000
L 4.3369997 1.1775 4.33913307 1.17833307 1 P 0 ;0,1=115,2=0.000000
L 4.33913307 1.17833307 4.34073327 1.18041604 1 P 0 ;0,1=115,2=0.000000
L 4.34073327 1.18041604 4.3418001 1.18291624 1 P 0 ;0,1=115,2=0.000000
L 4.3418001 1.18291624 4.3426 1.18624961 1 P 0 ;0,1=115,2=0.000000
L 4.3426 1.18624961 4.34286663 1.18999961 1 P 0 ;0,1=115,2=0.000000
L 4.34286663 1.18999961 4.3426 1.19374951 1 P 0 ;0,1=115,2=0.000000
L 4.3426 1.19374951 4.3418001 1.19708366 1 P 0 ;0,1=115,2=0.000000
L 4.3418001 1.19708366 4.34073327 1.19958317 1 P 0 ;0,1=115,2=0.000000
L 4.34073327 1.19958317 4.33913307 1.20166683 1 P 0 ;0,1=115,2=0.000000
L 4.33913307 1.20166683 4.3369997 1.2025 1 P 0 ;0,1=115,2=0.000000
L 4.3622 1.1775 4.3622 1.2025 1 P 0 ;0,1=115,2=0.000000
L 4.3622 1.2025 4.35233297 1.18458327 1 P 0 ;0,1=115,2=0.000000
L 4.35233297 1.18458327 4.36566693 1.18458327 1 P 0 ;0,1=115,2=0.000000
L 2.32649961 3.971 2.32649961 3.94 1 P 0 ;0,1=116,2=0.000000
L 2.31768337 3.971 2.33531654 3.971 1 P 0 ;0,1=116,2=0.000000
L 2.34983317 3.94 2.34983317 3.971 1 P 0 ;0,1=116,2=0.000000
L 2.34983317 3.971 2.35903327 3.971 1 P 0 ;0,1=116,2=0.000000
L 2.35903327 3.971 2.3621 3.96944931 1 P 0 ;0,1=116,2=0.000000
L 2.3621 3.96944931 2.3644002 3.96583346 1 P 0 ;0,1=116,2=0.000000
L 2.3644002 3.96583346 2.36516673 3.9617 1 P 0 ;0,1=116,2=0.000000
L 2.36516673 3.9617 2.3644002 3.95756663 1 P 0 ;0,1=116,2=0.000000
L 2.3644002 3.95756663 2.36248327 3.95446634 1 P 0 ;0,1=116,2=0.000000
L 2.36248327 3.95446634 2.35903327 3.95291575 1 P 0 ;0,1=116,2=0.000000
L 2.35903327 3.95291575 2.34983317 3.95291575 1 P 0 ;0,1=116,2=0.000000
L 2.38121644 3.95291575 2.3838999 3.95653356 1 P 0 ;0,1=116,2=0.000000
L 2.3838999 3.95653356 2.3862001 3.9585998 1 P 0 ;0,1=116,2=0.000000
L 2.3862001 3.9585998 2.38926683 3.95963287 1 P 0 ;0,1=116,2=0.000000
L 2.38926683 3.95963287 2.3919503 3.9585998 1 P 0 ;0,1=116,2=0.000000
L 2.3919503 3.9585998 2.39386654 3.95653356 1 P 0 ;0,1=116,2=0.000000
L 2.39386654 3.95653356 2.3954002 3.95343327 1 P 0 ;0,1=116,2=0.000000
L 2.3954002 3.95343327 2.39578346 3.94981644 1 P 0 ;0,1=116,2=0.000000
L 2.39578346 3.94981644 2.3954002 3.94671614 1 P 0 ;0,1=116,2=0.000000
L 2.3954002 3.94671614 2.39386654 3.94361585 1 P 0 ;0,1=116,2=0.000000
L 2.39386654 3.94361585 2.39156634 3.94103307 1 P 0 ;0,1=116,2=0.000000
L 2.39156634 3.94103307 2.38888356 3.94 1 P 0 ;0,1=116,2=0.000000
L 2.38888356 3.94 2.38581683 3.94103307 1 P 0 ;0,1=116,2=0.000000
L 2.38581683 3.94103307 2.38313337 3.94413238 1 P 0 ;0,1=116,2=0.000000
L 2.38313337 3.94413238 2.3815997 3.94878327 1 P 0 ;0,1=116,2=0.000000
L 2.3815997 3.94878327 2.38121644 3.9539498 1 P 0 ;0,1=116,2=0.000000
L 2.38121644 3.9539498 2.38198287 3.96066594 1 P 0 ;0,1=116,2=0.000000
L 2.38198287 3.96066594 2.38313337 3.96428376 1 P 0 ;0,1=116,2=0.000000
L 2.38313337 3.96428376 2.38504961 3.9678997 1 P 0 ;0,1=116,2=0.000000
L 2.38504961 3.9678997 2.38773307 3.97048337 1 P 0 ;0,1=116,2=0.000000
L 2.38773307 3.97048337 2.39041654 3.971 1 P 0 ;0,1=116,2=0.000000
L 2.39041654 3.971 2.3931 3.96996683 1 P 0 ;0,1=116,2=0.000000
L 2.3931 3.96996683 2.39501703 3.96738307 1 P 0 ;0,1=116,2=0.000000
L 2.41949961 3.971 2.41643287 3.96996683 1 P 0 ;0,1=116,2=0.000000
L 2.41643287 3.96996683 2.41413337 3.96738307 1 P 0 ;0,1=116,2=0.000000
L 2.41413337 3.96738307 2.4125997 3.96428376 1 P 0 ;0,1=116,2=0.000000
L 2.4125997 3.96428376 2.4114499 3.96014941 1 P 0 ;0,1=116,2=0.000000
L 2.4114499 3.96014941 2.41106663 3.95549951 1 P 0 ;0,1=116,2=0.000000
L 2.41106663 3.95549951 2.4114499 3.95084951 1 P 0 ;0,1=116,2=0.000000
L 2.4114499 3.95084951 2.4125997 3.94671614 1 P 0 ;0,1=116,2=0.000000
L 2.4125997 3.94671614 2.41413337 3.94361585 1 P 0 ;0,1=116,2=0.000000
L 2.41413337 3.94361585 2.41643287 3.94103307 1 P 0 ;0,1=116,2=0.000000
L 2.41643287 3.94103307 2.41949961 3.94 1 P 0 ;0,1=116,2=0.000000
L 2.41949961 3.94 2.42256634 3.94103307 1 P 0 ;0,1=116,2=0.000000
L 2.42256634 3.94103307 2.42486654 3.94361585 1 P 0 ;0,1=116,2=0.000000
L 2.42486654 3.94361585 2.4264002 3.94671614 1 P 0 ;0,1=116,2=0.000000
L 2.4264002 3.94671614 2.42755 3.95084951 1 P 0 ;0,1=116,2=0.000000
L 2.42755 3.95084951 2.42793327 3.95549951 1 P 0 ;0,1=116,2=0.000000
L 2.42793327 3.95549951 2.42755 3.96014941 1 P 0 ;0,1=116,2=0.000000
L 2.42755 3.96014941 2.4264002 3.96428376 1 P 0 ;0,1=116,2=0.000000
L 2.4264002 3.96428376 2.42486654 3.96738307 1 P 0 ;0,1=116,2=0.000000
L 2.42486654 3.96738307 2.42256634 3.96996683 1 P 0 ;0,1=116,2=0.000000
L 2.42256634 3.96996683 2.41949961 3.971 1 P 0 ;0,1=116,2=0.000000
L 5.27849961 2.3655 5.27849961 2.3345 1 P 0 ;0,1=117,2=0.000000
L 5.26968337 2.3655 5.28731654 2.3655 1 P 0 ;0,1=117,2=0.000000
L 5.30183317 2.3345 5.30183317 2.3655 1 P 0 ;0,1=117,2=0.000000
L 5.30183317 2.3655 5.31103327 2.3655 1 P 0 ;0,1=117,2=0.000000
L 5.31103327 2.3655 5.3141 2.36394931 1 P 0 ;0,1=117,2=0.000000
L 5.3141 2.36394931 5.3164002 2.36033346 1 P 0 ;0,1=117,2=0.000000
L 5.3164002 2.36033346 5.31716673 2.3562 1 P 0 ;0,1=117,2=0.000000
L 5.31716673 2.3562 5.3164002 2.35206663 1 P 0 ;0,1=117,2=0.000000
L 5.3164002 2.35206663 5.31448327 2.34896634 1 P 0 ;0,1=117,2=0.000000
L 5.31448327 2.34896634 5.31103327 2.34741575 1 P 0 ;0,1=117,2=0.000000
L 5.31103327 2.34741575 5.30183317 2.34741575 1 P 0 ;0,1=117,2=0.000000
L 5.33206663 2.33914892 5.33436614 2.33656614 1 P 0 ;0,1=117,2=0.000000
L 5.33436614 2.33656614 5.33704961 2.33501654 1 P 0 ;0,1=117,2=0.000000
L 5.33704961 2.33501654 5.34049961 2.3345 1 P 0 ;0,1=117,2=0.000000
L 5.34049961 2.3345 5.3439503 2.33553307 1 P 0 ;0,1=117,2=0.000000
L 5.3439503 2.33553307 5.34663307 2.33759931 1 P 0 ;0,1=117,2=0.000000
L 5.34663307 2.33759931 5.34855 2.34121614 1 P 0 ;0,1=117,2=0.000000
L 5.34855 2.34121614 5.34893327 2.34534951 1 P 0 ;0,1=117,2=0.000000
L 5.34893327 2.34534951 5.34816673 2.34948287 1 P 0 ;0,1=117,2=0.000000
L 5.34816673 2.34948287 5.3462498 2.35206663 1 P 0 ;0,1=117,2=0.000000
L 5.3462498 2.35206663 5.34356634 2.35413287 1 P 0 ;0,1=117,2=0.000000
L 5.34356634 2.35413287 5.34088356 2.35464941 1 P 0 ;0,1=117,2=0.000000
L 5.34088356 2.35464941 5.3382001 2.35413287 1 P 0 ;0,1=117,2=0.000000
L 5.3382001 2.35413287 5.3347501 2.35206663 1 P 0 ;0,1=117,2=0.000000
L 5.3347501 2.35206663 5.3358999 2.3655 1 P 0 ;0,1=117,2=0.000000
L 5.3358999 2.3655 5.3462498 2.3655 1 P 0 ;0,1=117,2=0.000000
L 5.36421644 2.36033346 5.36651663 2.36343278 1 P 0 ;0,1=117,2=0.000000
L 5.36651663 2.36343278 5.3692001 2.36498337 1 P 0 ;0,1=117,2=0.000000
L 5.3692001 2.36498337 5.37226683 2.3655 1 P 0 ;0,1=117,2=0.000000
L 5.37226683 2.3655 5.3761 2.36446683 1 P 0 ;0,1=117,2=0.000000
L 5.3761 2.36446683 5.37878346 2.36188307 1 P 0 ;0,1=117,2=0.000000
L 5.37878346 2.36188307 5.37955 2.35878376 1 P 0 ;0,1=117,2=0.000000
L 5.37955 2.35878376 5.37916673 2.35568258 1 P 0 ;0,1=117,2=0.000000
L 5.37916673 2.35568258 5.37763307 2.3530998 1 P 0 ;0,1=117,2=0.000000
L 5.37763307 2.3530998 5.36996663 2.34793327 1 P 0 ;0,1=117,2=0.000000
L 5.36996663 2.34793327 5.36651663 2.34431644 1 P 0 ;0,1=117,2=0.000000
L 5.36651663 2.34431644 5.36421644 2.33914892 1 P 0 ;0,1=117,2=0.000000
L 5.36421644 2.33914892 5.3634499 2.3345 1 P 0 ;0,1=117,2=0.000000
L 5.3634499 2.3345 5.37955 2.3345 1 P 0 ;0,1=117,2=0.000000
L 0.85693002 1.70756004 0.85693002 1.34243996 1 P 0 
L 0.65306998 1.70756004 0.85693002 1.70756004 1 P 0 
L 0.85693002 1.34243996 0.65306998 1.34243996 1 P 0 
L 0.65306998 1.34243996 0.65306998 1.70756004 1 P 0 
L 0.86999961 1.6795 0.86999961 1.7105 1 P 0 ;0,1=2,2=0.000000
L 0.86999961 1.7105 0.8653999 1.7043003 1 P 0 ;0,1=2,2=0.000000
L 0.8653999 1.6795 0.87459931 1.6795 1 P 0 ;0,1=2,2=0.000000
L 0.87183317 1.58069961 0.8737501 1.57759931 1 P 0 ;0,1=118,2=0.000000
L 0.8737501 1.57759931 0.87604961 1.57553307 1 P 0 ;0,1=118,2=0.000000
L 0.87604961 1.57553307 0.87873307 1.5745 1 P 0 ;0,1=118,2=0.000000
L 0.87873307 1.5745 0.8817998 1.57553307 1 P 0 ;0,1=118,2=0.000000
L 0.8817998 1.57553307 0.8841 1.57759931 1 P 0 ;0,1=118,2=0.000000
L 0.8841 1.57759931 0.8864002 1.58069961 1 P 0 ;0,1=118,2=0.000000
L 0.8864002 1.58069961 0.88716673 1.58483297 1 P 0 ;0,1=118,2=0.000000
L 0.88716673 1.58483297 0.88716673 1.6055 1 P 0 ;0,1=118,2=0.000000
L 0.90398287 1.57811585 0.90666634 1.57553307 1 P 0 ;0,1=118,2=0.000000
L 0.90666634 1.57553307 0.90973307 1.5745 1 P 0 ;0,1=118,2=0.000000
L 0.90973307 1.5745 0.9127998 1.57553307 1 P 0 ;0,1=118,2=0.000000
L 0.9127998 1.57553307 0.91548327 1.57863238 1 P 0 ;0,1=118,2=0.000000
L 0.91548327 1.57863238 0.9174002 1.58328327 1 P 0 ;0,1=118,2=0.000000
L 0.9174002 1.58328327 0.91816673 1.58793327 1 P 0 ;0,1=118,2=0.000000
L 0.91816673 1.58793327 0.91816673 1.59361634 1 P 0 ;0,1=118,2=0.000000
L 0.91816673 1.59361634 0.9174002 1.59826624 1 P 0 ;0,1=118,2=0.000000
L 0.9174002 1.59826624 0.91548327 1.6023997 1 P 0 ;0,1=118,2=0.000000
L 0.91548327 1.6023997 0.91318307 1.60446683 1 P 0 ;0,1=118,2=0.000000
L 0.91318307 1.60446683 0.91049961 1.6055 1 P 0 ;0,1=118,2=0.000000
L 0.91049961 1.6055 0.90743287 1.60446683 1 P 0 ;0,1=118,2=0.000000
L 0.90743287 1.60446683 0.90513337 1.6023997 1 P 0 ;0,1=118,2=0.000000
L 0.90513337 1.6023997 0.9035997 1.5993003 1 P 0 ;0,1=118,2=0.000000
L 0.9035997 1.5993003 0.90283317 1.59516594 1 P 0 ;0,1=118,2=0.000000
L 0.90283317 1.59516594 0.9035997 1.5915501 1 P 0 ;0,1=118,2=0.000000
L 0.9035997 1.5915501 0.90551663 1.58793327 1 P 0 ;0,1=118,2=0.000000
L 0.90551663 1.58793327 0.90781683 1.58586604 1 P 0 ;0,1=118,2=0.000000
L 0.90781683 1.58586604 0.91049961 1.58534951 1 P 0 ;0,1=118,2=0.000000
L 0.91049961 1.58534951 0.91356634 1.58638268 1 P 0 ;0,1=118,2=0.000000
L 0.91356634 1.58638268 0.91586654 1.58896634 1 P 0 ;0,1=118,2=0.000000
L 0.91586654 1.58896634 0.91816673 1.59361634 1 P 0 ;0,1=118,2=0.000000
L 0.87271644 1.40533346 0.87501663 1.40843278 1 P 0 ;0,1=4,2=0.000000
L 0.87501663 1.40843278 0.8777001 1.40998337 1 P 0 ;0,1=4,2=0.000000
L 0.8777001 1.40998337 0.88076683 1.4105 1 P 0 ;0,1=4,2=0.000000
L 0.88076683 1.4105 0.8846 1.40946683 1 P 0 ;0,1=4,2=0.000000
L 0.8846 1.40946683 0.88728346 1.40688307 1 P 0 ;0,1=4,2=0.000000
L 0.88728346 1.40688307 0.88805 1.40378376 1 P 0 ;0,1=4,2=0.000000
L 0.88805 1.40378376 0.88766673 1.40068258 1 P 0 ;0,1=4,2=0.000000
L 0.88766673 1.40068258 0.88613307 1.3980998 1 P 0 ;0,1=4,2=0.000000
L 0.88613307 1.3980998 0.87846663 1.39293327 1 P 0 ;0,1=4,2=0.000000
L 0.87846663 1.39293327 0.87501663 1.38931644 1 P 0 ;0,1=4,2=0.000000
L 0.87501663 1.38931644 0.87271644 1.38414892 1 P 0 ;0,1=4,2=0.000000
L 0.87271644 1.38414892 0.8719499 1.3795 1 P 0 ;0,1=4,2=0.000000
L 0.8719499 1.3795 0.88805 1.3795 1 P 0 ;0,1=4,2=0.000000
L 0.68656663 1.72569961 0.68886614 1.72208278 1 P 0 ;0,1=10,2=0.000000
L 0.68886614 1.72208278 0.69193287 1.72001654 1 P 0 ;0,1=10,2=0.000000
L 0.69193287 1.72001654 0.69538356 1.7195 1 P 0 ;0,1=10,2=0.000000
L 0.69538356 1.7195 0.6984503 1.72001654 1 P 0 ;0,1=10,2=0.000000
L 0.6984503 1.72001654 0.70151703 1.72259931 1 P 0 ;0,1=10,2=0.000000
L 0.70151703 1.72259931 0.70343327 1.72569961 1 P 0 ;0,1=10,2=0.000000
L 0.70343327 1.72569961 0.70381654 1.7287999 1 P 0 ;0,1=10,2=0.000000
L 0.70381654 1.7287999 0.70305 1.73241575 1 P 0 ;0,1=10,2=0.000000
L 0.70305 1.73241575 0.70036654 1.73499951 1 P 0 ;0,1=10,2=0.000000
L 0.70036654 1.73499951 0.69768307 1.73603356 1 P 0 ;0,1=10,2=0.000000
L 0.69768307 1.73603356 0.69423307 1.73603356 1 P 0 ;0,1=10,2=0.000000
L 0.69768307 1.73603356 0.69998327 1.73758317 1 P 0 ;0,1=10,2=0.000000
L 0.69998327 1.73758317 0.7019002 1.74016594 1 P 0 ;0,1=10,2=0.000000
L 0.7019002 1.74016594 0.70266673 1.74326624 1 P 0 ;0,1=10,2=0.000000
L 0.70266673 1.74326624 0.7019002 1.74636654 1 P 0 ;0,1=10,2=0.000000
L 0.7019002 1.74636654 0.69998327 1.74894931 1 P 0 ;0,1=10,2=0.000000
L 0.69998327 1.74894931 0.69653327 1.7505 1 P 0 ;0,1=10,2=0.000000
L 0.69653327 1.7505 0.69308337 1.74998337 1 P 0 ;0,1=10,2=0.000000
L 0.69308337 1.74998337 0.68963337 1.74791624 1 P 0 ;0,1=10,2=0.000000
L 0.7196 1.3045 0.7196 1.3355 1 P 0 ;0,1=11,2=0.000000
L 0.7196 1.3355 0.70541624 1.31328327 1 P 0 ;0,1=11,2=0.000000
L 0.70541624 1.31328327 0.72458366 1.31328327 1 P 0 ;0,1=11,2=0.000000
L 3.52256004 2.91693002 3.52256004 2.71306998 1 P 0 
L 3.15743996 2.91693002 3.52256004 2.91693002 1 P 0 
L 3.15743996 2.71306998 3.15743996 2.91693002 1 P 0 
L 3.52256004 2.71306998 3.15743996 2.71306998 1 P 0 
L 3.53999961 2.7845 3.53999961 2.8155 1 P 0 ;0,1=2,2=0.000000
L 3.53999961 2.8155 3.5353999 2.8093003 1 P 0 ;0,1=2,2=0.000000
L 3.5353999 2.7845 3.54459931 2.7845 1 P 0 ;0,1=2,2=0.000000
L 3.46156663 2.93069961 3.46386614 2.92708278 1 P 0 ;0,1=10,2=0.000000
L 3.46386614 2.92708278 3.46693287 2.92501654 1 P 0 ;0,1=10,2=0.000000
L 3.46693287 2.92501654 3.47038356 2.9245 1 P 0 ;0,1=10,2=0.000000
L 3.47038356 2.9245 3.4734503 2.92501654 1 P 0 ;0,1=10,2=0.000000
L 3.4734503 2.92501654 3.47651703 2.92759931 1 P 0 ;0,1=10,2=0.000000
L 3.47651703 2.92759931 3.47843327 2.93069961 1 P 0 ;0,1=10,2=0.000000
L 3.47843327 2.93069961 3.47881654 2.9337999 1 P 0 ;0,1=10,2=0.000000
L 3.47881654 2.9337999 3.47805 2.93741575 1 P 0 ;0,1=10,2=0.000000
L 3.47805 2.93741575 3.47536654 2.93999951 1 P 0 ;0,1=10,2=0.000000
L 3.47536654 2.93999951 3.47268307 2.94103356 1 P 0 ;0,1=10,2=0.000000
L 3.47268307 2.94103356 3.46923307 2.94103356 1 P 0 ;0,1=10,2=0.000000
L 3.47268307 2.94103356 3.47498327 2.94258317 1 P 0 ;0,1=10,2=0.000000
L 3.47498327 2.94258317 3.4769002 2.94516594 1 P 0 ;0,1=10,2=0.000000
L 3.4769002 2.94516594 3.47766673 2.94826624 1 P 0 ;0,1=10,2=0.000000
L 3.47766673 2.94826624 3.4769002 2.95136654 1 P 0 ;0,1=10,2=0.000000
L 3.4769002 2.95136654 3.47498327 2.95394931 1 P 0 ;0,1=10,2=0.000000
L 3.47498327 2.95394931 3.47153327 2.9555 1 P 0 ;0,1=10,2=0.000000
L 3.47153327 2.9555 3.46808337 2.95498337 1 P 0 ;0,1=10,2=0.000000
L 3.46808337 2.95498337 3.46463337 2.95291624 1 P 0 ;0,1=10,2=0.000000
L 3.27133317 2.94069961 3.2732501 2.93759931 1 P 0 ;0,1=119,2=0.000000
L 3.2732501 2.93759931 3.27554961 2.93553307 1 P 0 ;0,1=119,2=0.000000
L 3.27554961 2.93553307 3.27823307 2.9345 1 P 0 ;0,1=119,2=0.000000
L 3.27823307 2.9345 3.2812998 2.93553307 1 P 0 ;0,1=119,2=0.000000
L 3.2812998 2.93553307 3.2836 2.93759931 1 P 0 ;0,1=119,2=0.000000
L 3.2836 2.93759931 3.2859002 2.94069961 1 P 0 ;0,1=119,2=0.000000
L 3.2859002 2.94069961 3.28666673 2.94483297 1 P 0 ;0,1=119,2=0.000000
L 3.28666673 2.94483297 3.28666673 2.9655 1 P 0 ;0,1=119,2=0.000000
L 3.30999961 2.9345 3.30999961 2.9655 1 P 0 ;0,1=119,2=0.000000
L 3.30999961 2.9655 3.3053999 2.9593003 1 P 0 ;0,1=119,2=0.000000
L 3.3053999 2.9345 3.31459931 2.9345 1 P 0 ;0,1=119,2=0.000000
L 3.34023307 2.9345 3.34099961 2.94121614 1 P 0 ;0,1=119,2=0.000000
L 3.34099961 2.94121614 3.3421501 2.94689921 1 P 0 ;0,1=119,2=0.000000
L 3.3421501 2.94689921 3.34368307 2.95206663 1 P 0 ;0,1=119,2=0.000000
L 3.34368307 2.95206663 3.3456 2.9577497 1 P 0 ;0,1=119,2=0.000000
L 3.3456 2.9577497 3.34866673 2.9655 1 P 0 ;0,1=119,2=0.000000
L 3.34866673 2.9655 3.33333317 2.9655 1 P 0 ;0,1=119,2=0.000000
L 3.1396 2.8845 3.1396 2.9155 1 P 0 ;0,1=11,2=0.000000
L 3.1396 2.9155 3.12541624 2.89328327 1 P 0 ;0,1=11,2=0.000000
L 3.12541624 2.89328327 3.14458366 2.89328327 1 P 0 ;0,1=11,2=0.000000
L 3.12771644 2.81533346 3.13001663 2.81843278 1 P 0 ;0,1=4,2=0.000000
L 3.13001663 2.81843278 3.1327001 2.81998337 1 P 0 ;0,1=4,2=0.000000
L 3.1327001 2.81998337 3.13576683 2.8205 1 P 0 ;0,1=4,2=0.000000
L 3.13576683 2.8205 3.1396 2.81946683 1 P 0 ;0,1=4,2=0.000000
L 3.1396 2.81946683 3.14228346 2.81688307 1 P 0 ;0,1=4,2=0.000000
L 3.14228346 2.81688307 3.14305 2.81378376 1 P 0 ;0,1=4,2=0.000000
L 3.14305 2.81378376 3.14266673 2.81068258 1 P 0 ;0,1=4,2=0.000000
L 3.14266673 2.81068258 3.14113307 2.8080998 1 P 0 ;0,1=4,2=0.000000
L 3.14113307 2.8080998 3.13346663 2.80293327 1 P 0 ;0,1=4,2=0.000000
L 3.13346663 2.80293327 3.13001663 2.79931644 1 P 0 ;0,1=4,2=0.000000
L 3.13001663 2.79931644 3.12771644 2.79414892 1 P 0 ;0,1=4,2=0.000000
L 3.12771644 2.79414892 3.1269499 2.7895 1 P 0 ;0,1=4,2=0.000000
L 3.1269499 2.7895 3.14305 2.7895 1 P 0 ;0,1=4,2=0.000000
L 0.31538996 1.43846004 0.31538996 1.12846004 1 P 0 
L -0.38898002 1.43846004 0.31538996 1.43846004 1 P 0 
L -0.38898002 1.12846004 -0.38898002 1.43846004 1 P 0 
L 0.31538996 1.12846004 -0.38898002 1.12846004 1 P 0 
L 0.34683317 1.32069961 0.3487501 1.31759931 1 P 0 ;0,1=120,2=0.000000
L 0.3487501 1.31759931 0.35104961 1.31553307 1 P 0 ;0,1=120,2=0.000000
L 0.35104961 1.31553307 0.35373307 1.3145 1 P 0 ;0,1=120,2=0.000000
L 0.35373307 1.3145 0.3567998 1.31553307 1 P 0 ;0,1=120,2=0.000000
L 0.3567998 1.31553307 0.3591 1.31759931 1 P 0 ;0,1=120,2=0.000000
L 0.3591 1.31759931 0.3614002 1.32069961 1 P 0 ;0,1=120,2=0.000000
L 0.3614002 1.32069961 0.36216673 1.32483297 1 P 0 ;0,1=120,2=0.000000
L 0.36216673 1.32483297 0.36216673 1.3455 1 P 0 ;0,1=120,2=0.000000
L 0.38549961 1.3145 0.38549961 1.3455 1 P 0 ;0,1=120,2=0.000000
L 0.38549961 1.3455 0.3808999 1.3393003 1 P 0 ;0,1=120,2=0.000000
L 0.3808999 1.3145 0.39009931 1.3145 1 P 0 ;0,1=120,2=0.000000
L 0.23998986 1.46195965 0.24532343 1.46195965 1 P 0 ;0,1=121,2=0.000000
L 0.24532343 1.46195965 0.24532343 1.45445965 1 P 0 ;0,1=121,2=0.000000
L 0.24532343 1.45445965 0.24372333 1.45195945 1 P 0 ;0,1=121,2=0.000000
L 0.24372333 1.45195945 0.24185659 1.45029311 1 P 0 ;0,1=121,2=0.000000
L 0.24185659 1.45029311 0.23918996 1.44946004 1 P 0 ;0,1=121,2=0.000000
L 0.23918996 1.44946004 0.23652343 1.45029311 1 P 0 ;0,1=121,2=0.000000
L 0.23652343 1.45029311 0.23465659 1.45195945 1 P 0 ;0,1=121,2=0.000000
L 0.23465659 1.45195945 0.2330565 1.45445965 1 P 0 ;0,1=121,2=0.000000
L 0.2330565 1.45445965 0.23198957 1.45737648 1 P 0 ;0,1=121,2=0.000000
L 0.23198957 1.45737648 0.2314564 1.46070984 1 P 0 ;0,1=121,2=0.000000
L 0.2314564 1.46070984 0.2314564 1.46362667 1 P 0 ;0,1=121,2=0.000000
L 0.2314564 1.46362667 0.23198957 1.46612618 1 P 0 ;0,1=121,2=0.000000
L 0.23198957 1.46612618 0.2330565 1.4690437 1 P 0 ;0,1=121,2=0.000000
L 0.2330565 1.4690437 0.23465659 1.47154321 1 P 0 ;0,1=121,2=0.000000
L 0.23465659 1.47154321 0.2362563 1.47320945 1 P 0 ;0,1=121,2=0.000000
L 0.2362563 1.47320945 0.23838967 1.47446004 1 P 0 ;0,1=121,2=0.000000
L 0.23838967 1.47446004 0.2402564 1.47446004 1 P 0 ;0,1=121,2=0.000000
L 0.2402564 1.47446004 0.24238976 1.47362687 1 P 0 ;0,1=121,2=0.000000
L 0.24238976 1.47362687 0.24398996 1.47195974 1 P 0 ;0,1=121,2=0.000000
L 0.25478986 1.44946004 0.25478986 1.47446004 1 P 0 ;0,1=121,2=0.000000
L 0.26598996 1.47446004 0.26598996 1.44946004 1 P 0 ;0,1=121,2=0.000000
L 0.26598996 1.46195965 0.25478986 1.46195965 1 P 0 ;0,1=121,2=0.000000
L 0.27732313 1.47029341 0.27892323 1.47279291 1 P 0 ;0,1=121,2=0.000000
L 0.27892323 1.47279291 0.28078996 1.47404341 1 P 0 ;0,1=121,2=0.000000
L 0.28078996 1.47404341 0.28292333 1.47446004 1 P 0 ;0,1=121,2=0.000000
L 0.28292333 1.47446004 0.28558996 1.47362687 1 P 0 ;0,1=121,2=0.000000
L 0.28558996 1.47362687 0.28745669 1.47154321 1 P 0 ;0,1=121,2=0.000000
L 0.28745669 1.47154321 0.28798996 1.4690437 1 P 0 ;0,1=121,2=0.000000
L 0.28798996 1.4690437 0.28772333 1.46654272 1 P 0 ;0,1=121,2=0.000000
L 0.28772333 1.46654272 0.2866564 1.46445984 1 P 0 ;0,1=121,2=0.000000
L 0.2866564 1.46445984 0.28132323 1.46029331 1 P 0 ;0,1=121,2=0.000000
L 0.28132323 1.46029331 0.27892323 1.45737648 1 P 0 ;0,1=121,2=0.000000
L 0.27892323 1.45737648 0.27732313 1.45320915 1 P 0 ;0,1=121,2=0.000000
L 0.27732313 1.45320915 0.27678986 1.44946004 1 P 0 ;0,1=121,2=0.000000
L 0.27678986 1.44946004 0.28798996 1.44946004 1 P 0 ;0,1=121,2=0.000000
L 0.32999961 1.2695 0.32999961 1.3005 1 P 0 ;0,1=2,2=0.000000
L 0.32999961 1.3005 0.3253999 1.2943003 1 P 0 ;0,1=2,2=0.000000
L 0.3253999 1.2695 0.33459931 1.2695 1 P 0 ;0,1=2,2=0.000000
L 0.2295999 1.10999961 0.23493346 1.10999961 1 P 0 ;0,1=122,2=0.000000
L 0.23493346 1.10999961 0.23493346 1.10249961 1 P 0 ;0,1=122,2=0.000000
L 0.23493346 1.10249961 0.23333337 1.09999941 1 P 0 ;0,1=122,2=0.000000
L 0.23333337 1.09999941 0.23146663 1.09833307 1 P 0 ;0,1=122,2=0.000000
L 0.23146663 1.09833307 0.2288 1.0975 1 P 0 ;0,1=122,2=0.000000
L 0.2288 1.0975 0.22613346 1.09833307 1 P 0 ;0,1=122,2=0.000000
L 0.22613346 1.09833307 0.22426663 1.09999941 1 P 0 ;0,1=122,2=0.000000
L 0.22426663 1.09999941 0.22266654 1.10249961 1 P 0 ;0,1=122,2=0.000000
L 0.22266654 1.10249961 0.22159961 1.10541644 1 P 0 ;0,1=122,2=0.000000
L 0.22159961 1.10541644 0.22106644 1.1087498 1 P 0 ;0,1=122,2=0.000000
L 0.22106644 1.1087498 0.22106644 1.11166663 1 P 0 ;0,1=122,2=0.000000
L 0.22106644 1.11166663 0.22159961 1.11416614 1 P 0 ;0,1=122,2=0.000000
L 0.22159961 1.11416614 0.22266654 1.11708366 1 P 0 ;0,1=122,2=0.000000
L 0.22266654 1.11708366 0.22426663 1.11958317 1 P 0 ;0,1=122,2=0.000000
L 0.22426663 1.11958317 0.22586634 1.12124941 1 P 0 ;0,1=122,2=0.000000
L 0.22586634 1.12124941 0.2279997 1.1225 1 P 0 ;0,1=122,2=0.000000
L 0.2279997 1.1225 0.22986644 1.1225 1 P 0 ;0,1=122,2=0.000000
L 0.22986644 1.1225 0.2319998 1.12166683 1 P 0 ;0,1=122,2=0.000000
L 0.2319998 1.12166683 0.2336 1.1199997 1 P 0 ;0,1=122,2=0.000000
L 0.2443999 1.0975 0.2443999 1.1225 1 P 0 ;0,1=122,2=0.000000
L 0.2556 1.1225 0.2556 1.0975 1 P 0 ;0,1=122,2=0.000000
L 0.2556 1.10999961 0.2443999 1.10999961 1 P 0 ;0,1=122,2=0.000000
L 0.2752 1.0975 0.2752 1.1225 1 P 0 ;0,1=122,2=0.000000
L 0.2752 1.1225 0.26533297 1.10458327 1 P 0 ;0,1=122,2=0.000000
L 0.26533297 1.10458327 0.27866693 1.10458327 1 P 0 ;0,1=122,2=0.000000
L 0.1395999 1.45499961 0.14493346 1.45499961 1 P 0 ;0,1=123,2=0.000000
L 0.14493346 1.45499961 0.14493346 1.44749961 1 P 0 ;0,1=123,2=0.000000
L 0.14493346 1.44749961 0.14333337 1.44499941 1 P 0 ;0,1=123,2=0.000000
L 0.14333337 1.44499941 0.14146663 1.44333307 1 P 0 ;0,1=123,2=0.000000
L 0.14146663 1.44333307 0.1388 1.4425 1 P 0 ;0,1=123,2=0.000000
L 0.1388 1.4425 0.13613346 1.44333307 1 P 0 ;0,1=123,2=0.000000
L 0.13613346 1.44333307 0.13426663 1.44499941 1 P 0 ;0,1=123,2=0.000000
L 0.13426663 1.44499941 0.13266654 1.44749961 1 P 0 ;0,1=123,2=0.000000
L 0.13266654 1.44749961 0.13159961 1.45041644 1 P 0 ;0,1=123,2=0.000000
L 0.13159961 1.45041644 0.13106644 1.4537498 1 P 0 ;0,1=123,2=0.000000
L 0.13106644 1.4537498 0.13106644 1.45666663 1 P 0 ;0,1=123,2=0.000000
L 0.13106644 1.45666663 0.13159961 1.45916614 1 P 0 ;0,1=123,2=0.000000
L 0.13159961 1.45916614 0.13266654 1.46208366 1 P 0 ;0,1=123,2=0.000000
L 0.13266654 1.46208366 0.13426663 1.46458317 1 P 0 ;0,1=123,2=0.000000
L 0.13426663 1.46458317 0.13586634 1.46624941 1 P 0 ;0,1=123,2=0.000000
L 0.13586634 1.46624941 0.1379997 1.4675 1 P 0 ;0,1=123,2=0.000000
L 0.1379997 1.4675 0.13986644 1.4675 1 P 0 ;0,1=123,2=0.000000
L 0.13986644 1.4675 0.1419998 1.46666683 1 P 0 ;0,1=123,2=0.000000
L 0.1419998 1.46666683 0.1436 1.4649997 1 P 0 ;0,1=123,2=0.000000
L 0.1543999 1.4425 0.1543999 1.4675 1 P 0 ;0,1=123,2=0.000000
L 0.1656 1.4675 0.1656 1.4425 1 P 0 ;0,1=123,2=0.000000
L 0.1656 1.45499961 0.1543999 1.45499961 1 P 0 ;0,1=123,2=0.000000
L 0.1819997 1.4425 0.1819997 1.4675 1 P 0 ;0,1=123,2=0.000000
L 0.1819997 1.4675 0.1787999 1.4625003 1 P 0 ;0,1=123,2=0.000000
L 0.1787999 1.4425 0.18519951 1.4425 1 P 0 ;0,1=123,2=0.000000
L 0.0795999 1.11499961 0.08493346 1.11499961 1 P 0 ;0,1=124,2=0.000000
L 0.08493346 1.11499961 0.08493346 1.10749961 1 P 0 ;0,1=124,2=0.000000
L 0.08493346 1.10749961 0.08333337 1.10499941 1 P 0 ;0,1=124,2=0.000000
L 0.08333337 1.10499941 0.08146663 1.10333307 1 P 0 ;0,1=124,2=0.000000
L 0.08146663 1.10333307 0.0788 1.1025 1 P 0 ;0,1=124,2=0.000000
L 0.0788 1.1025 0.07613346 1.10333307 1 P 0 ;0,1=124,2=0.000000
L 0.07613346 1.10333307 0.07426663 1.10499941 1 P 0 ;0,1=124,2=0.000000
L 0.07426663 1.10499941 0.07266654 1.10749961 1 P 0 ;0,1=124,2=0.000000
L 0.07266654 1.10749961 0.07159961 1.11041644 1 P 0 ;0,1=124,2=0.000000
L 0.07159961 1.11041644 0.07106644 1.1137498 1 P 0 ;0,1=124,2=0.000000
L 0.07106644 1.1137498 0.07106644 1.11666663 1 P 0 ;0,1=124,2=0.000000
L 0.07106644 1.11666663 0.07159961 1.11916614 1 P 0 ;0,1=124,2=0.000000
L 0.07159961 1.11916614 0.07266654 1.12208366 1 P 0 ;0,1=124,2=0.000000
L 0.07266654 1.12208366 0.07426663 1.12458317 1 P 0 ;0,1=124,2=0.000000
L 0.07426663 1.12458317 0.07586634 1.12624941 1 P 0 ;0,1=124,2=0.000000
L 0.07586634 1.12624941 0.0779997 1.1275 1 P 0 ;0,1=124,2=0.000000
L 0.0779997 1.1275 0.07986644 1.1275 1 P 0 ;0,1=124,2=0.000000
L 0.07986644 1.1275 0.0819998 1.12666683 1 P 0 ;0,1=124,2=0.000000
L 0.0819998 1.12666683 0.0836 1.1249997 1 P 0 ;0,1=124,2=0.000000
L 0.0943999 1.1025 0.0943999 1.1275 1 P 0 ;0,1=124,2=0.000000
L 0.1056 1.1275 0.1056 1.1025 1 P 0 ;0,1=124,2=0.000000
L 0.1056 1.11499961 0.0943999 1.11499961 1 P 0 ;0,1=124,2=0.000000
L 0.11613327 1.10749961 0.11773297 1.10458287 1 P 0 ;0,1=124,2=0.000000
L 0.11773297 1.10458287 0.11986634 1.10291654 1 P 0 ;0,1=124,2=0.000000
L 0.11986634 1.10291654 0.12226683 1.1025 1 P 0 ;0,1=124,2=0.000000
L 0.12226683 1.1025 0.1244002 1.10291654 1 P 0 ;0,1=124,2=0.000000
L 0.1244002 1.10291654 0.12653356 1.10499941 1 P 0 ;0,1=124,2=0.000000
L 0.12653356 1.10499941 0.12786663 1.10749961 1 P 0 ;0,1=124,2=0.000000
L 0.12786663 1.10749961 0.12813317 1.1099999 1 P 0 ;0,1=124,2=0.000000
L 0.12813317 1.1099999 0.1276 1.11291594 1 P 0 ;0,1=124,2=0.000000
L 0.1276 1.11291594 0.12573327 1.11499961 1 P 0 ;0,1=124,2=0.000000
L 0.12573327 1.11499961 0.12386644 1.11583346 1 P 0 ;0,1=124,2=0.000000
L 0.12386644 1.11583346 0.12146654 1.11583346 1 P 0 ;0,1=124,2=0.000000
L 0.12386644 1.11583346 0.12546663 1.11708327 1 P 0 ;0,1=124,2=0.000000
L 0.12546663 1.11708327 0.1268001 1.11916614 1 P 0 ;0,1=124,2=0.000000
L 0.1268001 1.11916614 0.12733337 1.12166634 1 P 0 ;0,1=124,2=0.000000
L 0.12733337 1.12166634 0.1268001 1.12416654 1 P 0 ;0,1=124,2=0.000000
L 0.1268001 1.12416654 0.12546663 1.12624941 1 P 0 ;0,1=124,2=0.000000
L 0.12546663 1.12624941 0.12306663 1.1275 1 P 0 ;0,1=124,2=0.000000
L 0.12306663 1.1275 0.12066663 1.12708337 1 P 0 ;0,1=124,2=0.000000
L 0.12066663 1.12708337 0.11826663 1.12541634 1 P 0 ;0,1=124,2=0.000000
L 0.31538996 0.8676 0.31538996 0.5576 1 P 0 
L -0.38898002 0.8676 0.31538996 0.8676 1 P 0 
L -0.38898002 0.5576 -0.38898002 0.8676 1 P 0 
L 0.31538996 0.5576 -0.38898002 0.5576 1 P 0 
L 0.33183317 0.57069961 0.3337501 0.56759931 1 P 0 ;0,1=125,2=0.000000
L 0.3337501 0.56759931 0.33604961 0.56553307 1 P 0 ;0,1=125,2=0.000000
L 0.33604961 0.56553307 0.33873307 0.5645 1 P 0 ;0,1=125,2=0.000000
L 0.33873307 0.5645 0.3417998 0.56553307 1 P 0 ;0,1=125,2=0.000000
L 0.3417998 0.56553307 0.3441 0.56759931 1 P 0 ;0,1=125,2=0.000000
L 0.3441 0.56759931 0.3464002 0.57069961 1 P 0 ;0,1=125,2=0.000000
L 0.3464002 0.57069961 0.34716673 0.57483297 1 P 0 ;0,1=125,2=0.000000
L 0.34716673 0.57483297 0.34716673 0.5955 1 P 0 ;0,1=125,2=0.000000
L 0.36321644 0.59033346 0.36551663 0.59343278 1 P 0 ;0,1=125,2=0.000000
L 0.36551663 0.59343278 0.3682001 0.59498337 1 P 0 ;0,1=125,2=0.000000
L 0.3682001 0.59498337 0.37126683 0.5955 1 P 0 ;0,1=125,2=0.000000
L 0.37126683 0.5955 0.3751 0.59446683 1 P 0 ;0,1=125,2=0.000000
L 0.3751 0.59446683 0.37778346 0.59188307 1 P 0 ;0,1=125,2=0.000000
L 0.37778346 0.59188307 0.37855 0.58878376 1 P 0 ;0,1=125,2=0.000000
L 0.37855 0.58878376 0.37816673 0.58568258 1 P 0 ;0,1=125,2=0.000000
L 0.37816673 0.58568258 0.37663307 0.5830998 1 P 0 ;0,1=125,2=0.000000
L 0.37663307 0.5830998 0.36896663 0.57793327 1 P 0 ;0,1=125,2=0.000000
L 0.36896663 0.57793327 0.36551663 0.57431644 1 P 0 ;0,1=125,2=0.000000
L 0.36551663 0.57431644 0.36321644 0.56914892 1 P 0 ;0,1=125,2=0.000000
L 0.36321644 0.56914892 0.3624499 0.5645 1 P 0 ;0,1=125,2=0.000000
L 0.3624499 0.5645 0.37855 0.5645 1 P 0 ;0,1=125,2=0.000000
L 0.2295999 0.88499961 0.23493346 0.88499961 1 P 0 ;0,1=121,2=0.000000
L 0.23493346 0.88499961 0.23493346 0.87749961 1 P 0 ;0,1=121,2=0.000000
L 0.23493346 0.87749961 0.23333337 0.87499941 1 P 0 ;0,1=121,2=0.000000
L 0.23333337 0.87499941 0.23146663 0.87333307 1 P 0 ;0,1=121,2=0.000000
L 0.23146663 0.87333307 0.2288 0.8725 1 P 0 ;0,1=121,2=0.000000
L 0.2288 0.8725 0.22613346 0.87333307 1 P 0 ;0,1=121,2=0.000000
L 0.22613346 0.87333307 0.22426663 0.87499941 1 P 0 ;0,1=121,2=0.000000
L 0.22426663 0.87499941 0.22266654 0.87749961 1 P 0 ;0,1=121,2=0.000000
L 0.22266654 0.87749961 0.22159961 0.88041644 1 P 0 ;0,1=121,2=0.000000
L 0.22159961 0.88041644 0.22106644 0.8837498 1 P 0 ;0,1=121,2=0.000000
L 0.22106644 0.8837498 0.22106644 0.88666663 1 P 0 ;0,1=121,2=0.000000
L 0.22106644 0.88666663 0.22159961 0.88916614 1 P 0 ;0,1=121,2=0.000000
L 0.22159961 0.88916614 0.22266654 0.89208366 1 P 0 ;0,1=121,2=0.000000
L 0.22266654 0.89208366 0.22426663 0.89458317 1 P 0 ;0,1=121,2=0.000000
L 0.22426663 0.89458317 0.22586634 0.89624941 1 P 0 ;0,1=121,2=0.000000
L 0.22586634 0.89624941 0.2279997 0.8975 1 P 0 ;0,1=121,2=0.000000
L 0.2279997 0.8975 0.22986644 0.8975 1 P 0 ;0,1=121,2=0.000000
L 0.22986644 0.8975 0.2319998 0.89666683 1 P 0 ;0,1=121,2=0.000000
L 0.2319998 0.89666683 0.2336 0.8949997 1 P 0 ;0,1=121,2=0.000000
L 0.2443999 0.8725 0.2443999 0.8975 1 P 0 ;0,1=121,2=0.000000
L 0.2556 0.8975 0.2556 0.8725 1 P 0 ;0,1=121,2=0.000000
L 0.2556 0.88499961 0.2443999 0.88499961 1 P 0 ;0,1=121,2=0.000000
L 0.26693317 0.89333337 0.26853327 0.89583287 1 P 0 ;0,1=121,2=0.000000
L 0.26853327 0.89583287 0.2704 0.89708337 1 P 0 ;0,1=121,2=0.000000
L 0.2704 0.89708337 0.27253337 0.8975 1 P 0 ;0,1=121,2=0.000000
L 0.27253337 0.8975 0.2752 0.89666683 1 P 0 ;0,1=121,2=0.000000
L 0.2752 0.89666683 0.27706673 0.89458317 1 P 0 ;0,1=121,2=0.000000
L 0.27706673 0.89458317 0.2776 0.89208366 1 P 0 ;0,1=121,2=0.000000
L 0.2776 0.89208366 0.27733337 0.88958268 1 P 0 ;0,1=121,2=0.000000
L 0.27733337 0.88958268 0.27626644 0.8874998 1 P 0 ;0,1=121,2=0.000000
L 0.27626644 0.8874998 0.27093327 0.88333327 1 P 0 ;0,1=121,2=0.000000
L 0.27093327 0.88333327 0.26853327 0.88041644 1 P 0 ;0,1=121,2=0.000000
L 0.26853327 0.88041644 0.26693317 0.87624911 1 P 0 ;0,1=121,2=0.000000
L 0.26693317 0.87624911 0.2663999 0.8725 1 P 0 ;0,1=121,2=0.000000
L 0.2663999 0.8725 0.2776 0.8725 1 P 0 ;0,1=121,2=0.000000
L 0.33688957 0.7126 0.33688957 0.7436 1 P 0 ;0,1=2,2=0.000000
L 0.33688957 0.7436 0.33228986 0.7374003 1 P 0 ;0,1=2,2=0.000000
L 0.33228986 0.7126 0.34148927 0.7126 1 P 0 ;0,1=2,2=0.000000
L 0.2412998 0.52999951 0.24896693 0.52999951 1 P 0 ;0,1=122,2=0.000000
L 0.24896693 0.52999951 0.24896693 0.52069961 1 P 0 ;0,1=122,2=0.000000
L 0.24896693 0.52069961 0.24666673 0.51759931 1 P 0 ;0,1=122,2=0.000000
L 0.24666673 0.51759931 0.24398327 0.51553307 1 P 0 ;0,1=122,2=0.000000
L 0.24398327 0.51553307 0.2401501 0.5145 1 P 0 ;0,1=122,2=0.000000
L 0.2401501 0.5145 0.23631683 0.51553307 1 P 0 ;0,1=122,2=0.000000
L 0.23631683 0.51553307 0.23363337 0.51759931 1 P 0 ;0,1=122,2=0.000000
L 0.23363337 0.51759931 0.23133317 0.52069961 1 P 0 ;0,1=122,2=0.000000
L 0.23133317 0.52069961 0.22979951 0.52431644 1 P 0 ;0,1=122,2=0.000000
L 0.22979951 0.52431644 0.22903297 0.5284498 1 P 0 ;0,1=122,2=0.000000
L 0.22903297 0.5284498 0.22903297 0.53206663 1 P 0 ;0,1=122,2=0.000000
L 0.22903297 0.53206663 0.22979951 0.53516594 1 P 0 ;0,1=122,2=0.000000
L 0.22979951 0.53516594 0.23133317 0.53878376 1 P 0 ;0,1=122,2=0.000000
L 0.23133317 0.53878376 0.23363337 0.54188307 1 P 0 ;0,1=122,2=0.000000
L 0.23363337 0.54188307 0.23593287 0.54394931 1 P 0 ;0,1=122,2=0.000000
L 0.23593287 0.54394931 0.23899961 0.5455 1 P 0 ;0,1=122,2=0.000000
L 0.23899961 0.5455 0.24168307 0.5455 1 P 0 ;0,1=122,2=0.000000
L 0.24168307 0.5455 0.2447498 0.54446683 1 P 0 ;0,1=122,2=0.000000
L 0.2447498 0.54446683 0.24705 0.5423997 1 P 0 ;0,1=122,2=0.000000
L 0.2619499 0.5145 0.2619499 0.5455 1 P 0 ;0,1=122,2=0.000000
L 0.27805 0.5455 0.27805 0.5145 1 P 0 ;0,1=122,2=0.000000
L 0.27805 0.52999951 0.2619499 0.52999951 1 P 0 ;0,1=122,2=0.000000
L 0.3056 0.5145 0.3056 0.5455 1 P 0 ;0,1=122,2=0.000000
L 0.3056 0.5455 0.29141624 0.52328327 1 P 0 ;0,1=122,2=0.000000
L 0.29141624 0.52328327 0.31058366 0.52328327 1 P 0 ;0,1=122,2=0.000000
L 0.1295999 0.88499961 0.13493346 0.88499961 1 P 0 ;0,1=123,2=0.000000
L 0.13493346 0.88499961 0.13493346 0.87749961 1 P 0 ;0,1=123,2=0.000000
L 0.13493346 0.87749961 0.13333337 0.87499941 1 P 0 ;0,1=123,2=0.000000
L 0.13333337 0.87499941 0.13146663 0.87333307 1 P 0 ;0,1=123,2=0.000000
L 0.13146663 0.87333307 0.1288 0.8725 1 P 0 ;0,1=123,2=0.000000
L 0.1288 0.8725 0.12613346 0.87333307 1 P 0 ;0,1=123,2=0.000000
L 0.12613346 0.87333307 0.12426663 0.87499941 1 P 0 ;0,1=123,2=0.000000
L 0.12426663 0.87499941 0.12266654 0.87749961 1 P 0 ;0,1=123,2=0.000000
L 0.12266654 0.87749961 0.12159961 0.88041644 1 P 0 ;0,1=123,2=0.000000
L 0.12159961 0.88041644 0.12106644 0.8837498 1 P 0 ;0,1=123,2=0.000000
L 0.12106644 0.8837498 0.12106644 0.88666663 1 P 0 ;0,1=123,2=0.000000
L 0.12106644 0.88666663 0.12159961 0.88916614 1 P 0 ;0,1=123,2=0.000000
L 0.12159961 0.88916614 0.12266654 0.89208366 1 P 0 ;0,1=123,2=0.000000
L 0.12266654 0.89208366 0.12426663 0.89458317 1 P 0 ;0,1=123,2=0.000000
L 0.12426663 0.89458317 0.12586634 0.89624941 1 P 0 ;0,1=123,2=0.000000
L 0.12586634 0.89624941 0.1279997 0.8975 1 P 0 ;0,1=123,2=0.000000
L 0.1279997 0.8975 0.12986644 0.8975 1 P 0 ;0,1=123,2=0.000000
L 0.12986644 0.8975 0.1319998 0.89666683 1 P 0 ;0,1=123,2=0.000000
L 0.1319998 0.89666683 0.1336 0.8949997 1 P 0 ;0,1=123,2=0.000000
L 0.1443999 0.8725 0.1443999 0.8975 1 P 0 ;0,1=123,2=0.000000
L 0.1556 0.8975 0.1556 0.8725 1 P 0 ;0,1=123,2=0.000000
L 0.1556 0.88499961 0.1443999 0.88499961 1 P 0 ;0,1=123,2=0.000000
L 0.1719997 0.8725 0.1719997 0.8975 1 P 0 ;0,1=123,2=0.000000
L 0.1719997 0.8975 0.1687999 0.8925003 1 P 0 ;0,1=123,2=0.000000
L 0.1687999 0.8725 0.17519951 0.8725 1 P 0 ;0,1=123,2=0.000000
L 0.0662998 0.53499951 0.07396693 0.53499951 1 P 0 ;0,1=124,2=0.000000
L 0.07396693 0.53499951 0.07396693 0.52569961 1 P 0 ;0,1=124,2=0.000000
L 0.07396693 0.52569961 0.07166673 0.52259931 1 P 0 ;0,1=124,2=0.000000
L 0.07166673 0.52259931 0.06898327 0.52053307 1 P 0 ;0,1=124,2=0.000000
L 0.06898327 0.52053307 0.0651501 0.5195 1 P 0 ;0,1=124,2=0.000000
L 0.0651501 0.5195 0.06131683 0.52053307 1 P 0 ;0,1=124,2=0.000000
L 0.06131683 0.52053307 0.05863337 0.52259931 1 P 0 ;0,1=124,2=0.000000
L 0.05863337 0.52259931 0.05633317 0.52569961 1 P 0 ;0,1=124,2=0.000000
L 0.05633317 0.52569961 0.05479951 0.52931644 1 P 0 ;0,1=124,2=0.000000
L 0.05479951 0.52931644 0.05403297 0.5334498 1 P 0 ;0,1=124,2=0.000000
L 0.05403297 0.5334498 0.05403297 0.53706663 1 P 0 ;0,1=124,2=0.000000
L 0.05403297 0.53706663 0.05479951 0.54016594 1 P 0 ;0,1=124,2=0.000000
L 0.05479951 0.54016594 0.05633317 0.54378376 1 P 0 ;0,1=124,2=0.000000
L 0.05633317 0.54378376 0.05863337 0.54688307 1 P 0 ;0,1=124,2=0.000000
L 0.05863337 0.54688307 0.06093287 0.54894931 1 P 0 ;0,1=124,2=0.000000
L 0.06093287 0.54894931 0.06399961 0.5505 1 P 0 ;0,1=124,2=0.000000
L 0.06399961 0.5505 0.06668307 0.5505 1 P 0 ;0,1=124,2=0.000000
L 0.06668307 0.5505 0.0697498 0.54946683 1 P 0 ;0,1=124,2=0.000000
L 0.0697498 0.54946683 0.07205 0.5473997 1 P 0 ;0,1=124,2=0.000000
L 0.0869499 0.5195 0.0869499 0.5505 1 P 0 ;0,1=124,2=0.000000
L 0.10305 0.5505 0.10305 0.5195 1 P 0 ;0,1=124,2=0.000000
L 0.10305 0.53499951 0.0869499 0.53499951 1 P 0 ;0,1=124,2=0.000000
L 0.11756663 0.52569961 0.11986614 0.52208278 1 P 0 ;0,1=124,2=0.000000
L 0.11986614 0.52208278 0.12293287 0.52001654 1 P 0 ;0,1=124,2=0.000000
L 0.12293287 0.52001654 0.12638356 0.5195 1 P 0 ;0,1=124,2=0.000000
L 0.12638356 0.5195 0.1294503 0.52001654 1 P 0 ;0,1=124,2=0.000000
L 0.1294503 0.52001654 0.13251703 0.52259931 1 P 0 ;0,1=124,2=0.000000
L 0.13251703 0.52259931 0.13443327 0.52569961 1 P 0 ;0,1=124,2=0.000000
L 0.13443327 0.52569961 0.13481654 0.5287999 1 P 0 ;0,1=124,2=0.000000
L 0.13481654 0.5287999 0.13405 0.53241575 1 P 0 ;0,1=124,2=0.000000
L 0.13405 0.53241575 0.13136654 0.53499951 1 P 0 ;0,1=124,2=0.000000
L 0.13136654 0.53499951 0.12868307 0.53603356 1 P 0 ;0,1=124,2=0.000000
L 0.12868307 0.53603356 0.12523307 0.53603356 1 P 0 ;0,1=124,2=0.000000
L 0.12868307 0.53603356 0.13098327 0.53758317 1 P 0 ;0,1=124,2=0.000000
L 0.13098327 0.53758317 0.1329002 0.54016594 1 P 0 ;0,1=124,2=0.000000
L 0.1329002 0.54016594 0.13366673 0.54326624 1 P 0 ;0,1=124,2=0.000000
L 0.13366673 0.54326624 0.1329002 0.54636654 1 P 0 ;0,1=124,2=0.000000
L 0.1329002 0.54636654 0.13098327 0.54894931 1 P 0 ;0,1=124,2=0.000000
L 0.13098327 0.54894931 0.12753327 0.5505 1 P 0 ;0,1=124,2=0.000000
L 0.12753327 0.5505 0.12408337 0.54998337 1 P 0 ;0,1=124,2=0.000000
L 0.12408337 0.54998337 0.12063337 0.54791624 1 P 0 ;0,1=124,2=0.000000
L 0.31538996 2.5802 0.31538996 2.2702 1 P 0 
L -0.38898002 2.5802 0.31538996 2.5802 1 P 0 
L 0.31538996 2.2702 -0.38898002 2.2702 1 P 0 
L -0.38898002 2.2702 -0.38898002 2.5802 1 P 0 
L 0.33183317 2.50569961 0.3337501 2.50259931 1 P 0 ;0,1=126,2=0.000000
L 0.3337501 2.50259931 0.33604961 2.50053307 1 P 0 ;0,1=126,2=0.000000
L 0.33604961 2.50053307 0.33873307 2.4995 1 P 0 ;0,1=126,2=0.000000
L 0.33873307 2.4995 0.3417998 2.50053307 1 P 0 ;0,1=126,2=0.000000
L 0.3417998 2.50053307 0.3441 2.50259931 1 P 0 ;0,1=126,2=0.000000
L 0.3441 2.50259931 0.3464002 2.50569961 1 P 0 ;0,1=126,2=0.000000
L 0.3464002 2.50569961 0.34716673 2.50983297 1 P 0 ;0,1=126,2=0.000000
L 0.34716673 2.50983297 0.34716673 2.5305 1 P 0 ;0,1=126,2=0.000000
L 0.36206663 2.50569961 0.36436614 2.50208278 1 P 0 ;0,1=126,2=0.000000
L 0.36436614 2.50208278 0.36743287 2.50001654 1 P 0 ;0,1=126,2=0.000000
L 0.36743287 2.50001654 0.37088356 2.4995 1 P 0 ;0,1=126,2=0.000000
L 0.37088356 2.4995 0.3739503 2.50001654 1 P 0 ;0,1=126,2=0.000000
L 0.3739503 2.50001654 0.37701703 2.50259931 1 P 0 ;0,1=126,2=0.000000
L 0.37701703 2.50259931 0.37893327 2.50569961 1 P 0 ;0,1=126,2=0.000000
L 0.37893327 2.50569961 0.37931654 2.5087999 1 P 0 ;0,1=126,2=0.000000
L 0.37931654 2.5087999 0.37855 2.51241575 1 P 0 ;0,1=126,2=0.000000
L 0.37855 2.51241575 0.37586654 2.51499951 1 P 0 ;0,1=126,2=0.000000
L 0.37586654 2.51499951 0.37318307 2.51603356 1 P 0 ;0,1=126,2=0.000000
L 0.37318307 2.51603356 0.36973307 2.51603356 1 P 0 ;0,1=126,2=0.000000
L 0.37318307 2.51603356 0.37548327 2.51758317 1 P 0 ;0,1=126,2=0.000000
L 0.37548327 2.51758317 0.3774002 2.52016594 1 P 0 ;0,1=126,2=0.000000
L 0.3774002 2.52016594 0.37816673 2.52326624 1 P 0 ;0,1=126,2=0.000000
L 0.37816673 2.52326624 0.3774002 2.52636654 1 P 0 ;0,1=126,2=0.000000
L 0.3774002 2.52636654 0.37548327 2.52894931 1 P 0 ;0,1=126,2=0.000000
L 0.37548327 2.52894931 0.37203327 2.5305 1 P 0 ;0,1=126,2=0.000000
L 0.37203327 2.5305 0.36858337 2.52998337 1 P 0 ;0,1=126,2=0.000000
L 0.36858337 2.52998337 0.36513337 2.52791624 1 P 0 ;0,1=126,2=0.000000
L 0.2395999 2.59499961 0.24493346 2.59499961 1 P 0 ;0,1=121,2=0.000000
L 0.24493346 2.59499961 0.24493346 2.58749961 1 P 0 ;0,1=121,2=0.000000
L 0.24493346 2.58749961 0.24333337 2.58499941 1 P 0 ;0,1=121,2=0.000000
L 0.24333337 2.58499941 0.24146663 2.58333307 1 P 0 ;0,1=121,2=0.000000
L 0.24146663 2.58333307 0.2388 2.5825 1 P 0 ;0,1=121,2=0.000000
L 0.2388 2.5825 0.23613346 2.58333307 1 P 0 ;0,1=121,2=0.000000
L 0.23613346 2.58333307 0.23426663 2.58499941 1 P 0 ;0,1=121,2=0.000000
L 0.23426663 2.58499941 0.23266654 2.58749961 1 P 0 ;0,1=121,2=0.000000
L 0.23266654 2.58749961 0.23159961 2.59041644 1 P 0 ;0,1=121,2=0.000000
L 0.23159961 2.59041644 0.23106644 2.5937498 1 P 0 ;0,1=121,2=0.000000
L 0.23106644 2.5937498 0.23106644 2.59666663 1 P 0 ;0,1=121,2=0.000000
L 0.23106644 2.59666663 0.23159961 2.59916614 1 P 0 ;0,1=121,2=0.000000
L 0.23159961 2.59916614 0.23266654 2.60208366 1 P 0 ;0,1=121,2=0.000000
L 0.23266654 2.60208366 0.23426663 2.60458317 1 P 0 ;0,1=121,2=0.000000
L 0.23426663 2.60458317 0.23586634 2.60624941 1 P 0 ;0,1=121,2=0.000000
L 0.23586634 2.60624941 0.2379997 2.6075 1 P 0 ;0,1=121,2=0.000000
L 0.2379997 2.6075 0.23986644 2.6075 1 P 0 ;0,1=121,2=0.000000
L 0.23986644 2.6075 0.2419998 2.60666683 1 P 0 ;0,1=121,2=0.000000
L 0.2419998 2.60666683 0.2436 2.6049997 1 P 0 ;0,1=121,2=0.000000
L 0.2543999 2.5825 0.2543999 2.6075 1 P 0 ;0,1=121,2=0.000000
L 0.2656 2.6075 0.2656 2.5825 1 P 0 ;0,1=121,2=0.000000
L 0.2656 2.59499961 0.2543999 2.59499961 1 P 0 ;0,1=121,2=0.000000
L 0.27693317 2.60333337 0.27853327 2.60583287 1 P 0 ;0,1=121,2=0.000000
L 0.27853327 2.60583287 0.2804 2.60708337 1 P 0 ;0,1=121,2=0.000000
L 0.2804 2.60708337 0.28253337 2.6075 1 P 0 ;0,1=121,2=0.000000
L 0.28253337 2.6075 0.2852 2.60666683 1 P 0 ;0,1=121,2=0.000000
L 0.2852 2.60666683 0.28706673 2.60458317 1 P 0 ;0,1=121,2=0.000000
L 0.28706673 2.60458317 0.2876 2.60208366 1 P 0 ;0,1=121,2=0.000000
L 0.2876 2.60208366 0.28733337 2.59958268 1 P 0 ;0,1=121,2=0.000000
L 0.28733337 2.59958268 0.28626644 2.5974998 1 P 0 ;0,1=121,2=0.000000
L 0.28626644 2.5974998 0.28093327 2.59333327 1 P 0 ;0,1=121,2=0.000000
L 0.28093327 2.59333327 0.27853327 2.59041644 1 P 0 ;0,1=121,2=0.000000
L 0.27853327 2.59041644 0.27693317 2.58624911 1 P 0 ;0,1=121,2=0.000000
L 0.27693317 2.58624911 0.2763999 2.5825 1 P 0 ;0,1=121,2=0.000000
L 0.2763999 2.5825 0.2876 2.5825 1 P 0 ;0,1=121,2=0.000000
L 0.33688957 2.4252 0.33688957 2.4562 1 P 0 ;0,1=2,2=0.000000
L 0.33688957 2.4562 0.33228986 2.4500003 1 P 0 ;0,1=2,2=0.000000
L 0.33228986 2.4252 0.34148927 2.4252 1 P 0 ;0,1=2,2=0.000000
L 0.2595999 2.24199961 0.26493346 2.24199961 1 P 0 ;0,1=122,2=0.000000
L 0.26493346 2.24199961 0.26493346 2.23449961 1 P 0 ;0,1=122,2=0.000000
L 0.26493346 2.23449961 0.26333337 2.23199941 1 P 0 ;0,1=122,2=0.000000
L 0.26333337 2.23199941 0.26146663 2.23033307 1 P 0 ;0,1=122,2=0.000000
L 0.26146663 2.23033307 0.2588 2.2295 1 P 0 ;0,1=122,2=0.000000
L 0.2588 2.2295 0.25613346 2.23033307 1 P 0 ;0,1=122,2=0.000000
L 0.25613346 2.23033307 0.25426663 2.23199941 1 P 0 ;0,1=122,2=0.000000
L 0.25426663 2.23199941 0.25266654 2.23449961 1 P 0 ;0,1=122,2=0.000000
L 0.25266654 2.23449961 0.25159961 2.23741644 1 P 0 ;0,1=122,2=0.000000
L 0.25159961 2.23741644 0.25106644 2.2407498 1 P 0 ;0,1=122,2=0.000000
L 0.25106644 2.2407498 0.25106644 2.24366663 1 P 0 ;0,1=122,2=0.000000
L 0.25106644 2.24366663 0.25159961 2.24616614 1 P 0 ;0,1=122,2=0.000000
L 0.25159961 2.24616614 0.25266654 2.24908366 1 P 0 ;0,1=122,2=0.000000
L 0.25266654 2.24908366 0.25426663 2.25158317 1 P 0 ;0,1=122,2=0.000000
L 0.25426663 2.25158317 0.25586634 2.25324941 1 P 0 ;0,1=122,2=0.000000
L 0.25586634 2.25324941 0.2579997 2.2545 1 P 0 ;0,1=122,2=0.000000
L 0.2579997 2.2545 0.25986644 2.2545 1 P 0 ;0,1=122,2=0.000000
L 0.25986644 2.2545 0.2619998 2.25366683 1 P 0 ;0,1=122,2=0.000000
L 0.2619998 2.25366683 0.2636 2.2519997 1 P 0 ;0,1=122,2=0.000000
L 0.2743999 2.2295 0.2743999 2.2545 1 P 0 ;0,1=122,2=0.000000
L 0.2856 2.2545 0.2856 2.2295 1 P 0 ;0,1=122,2=0.000000
L 0.2856 2.24199961 0.2743999 2.24199961 1 P 0 ;0,1=122,2=0.000000
L 0.3052 2.2295 0.3052 2.2545 1 P 0 ;0,1=122,2=0.000000
L 0.3052 2.2545 0.29533297 2.23658327 1 P 0 ;0,1=122,2=0.000000
L 0.29533297 2.23658327 0.30866693 2.23658327 1 P 0 ;0,1=122,2=0.000000
L 0.1445999 2.59499961 0.14993346 2.59499961 1 P 0 ;0,1=123,2=0.000000
L 0.14993346 2.59499961 0.14993346 2.58749961 1 P 0 ;0,1=123,2=0.000000
L 0.14993346 2.58749961 0.14833337 2.58499941 1 P 0 ;0,1=123,2=0.000000
L 0.14833337 2.58499941 0.14646663 2.58333307 1 P 0 ;0,1=123,2=0.000000
L 0.14646663 2.58333307 0.1438 2.5825 1 P 0 ;0,1=123,2=0.000000
L 0.1438 2.5825 0.14113346 2.58333307 1 P 0 ;0,1=123,2=0.000000
L 0.14113346 2.58333307 0.13926663 2.58499941 1 P 0 ;0,1=123,2=0.000000
L 0.13926663 2.58499941 0.13766654 2.58749961 1 P 0 ;0,1=123,2=0.000000
L 0.13766654 2.58749961 0.13659961 2.59041644 1 P 0 ;0,1=123,2=0.000000
L 0.13659961 2.59041644 0.13606644 2.5937498 1 P 0 ;0,1=123,2=0.000000
L 0.13606644 2.5937498 0.13606644 2.59666663 1 P 0 ;0,1=123,2=0.000000
L 0.13606644 2.59666663 0.13659961 2.59916614 1 P 0 ;0,1=123,2=0.000000
L 0.13659961 2.59916614 0.13766654 2.60208366 1 P 0 ;0,1=123,2=0.000000
L 0.13766654 2.60208366 0.13926663 2.60458317 1 P 0 ;0,1=123,2=0.000000
L 0.13926663 2.60458317 0.14086634 2.60624941 1 P 0 ;0,1=123,2=0.000000
L 0.14086634 2.60624941 0.1429997 2.6075 1 P 0 ;0,1=123,2=0.000000
L 0.1429997 2.6075 0.14486644 2.6075 1 P 0 ;0,1=123,2=0.000000
L 0.14486644 2.6075 0.1469998 2.60666683 1 P 0 ;0,1=123,2=0.000000
L 0.1469998 2.60666683 0.1486 2.6049997 1 P 0 ;0,1=123,2=0.000000
L 0.1593999 2.5825 0.1593999 2.6075 1 P 0 ;0,1=123,2=0.000000
L 0.1706 2.6075 0.1706 2.5825 1 P 0 ;0,1=123,2=0.000000
L 0.1706 2.59499961 0.1593999 2.59499961 1 P 0 ;0,1=123,2=0.000000
L 0.1869997 2.5825 0.1869997 2.6075 1 P 0 ;0,1=123,2=0.000000
L 0.1869997 2.6075 0.1837999 2.6025003 1 P 0 ;0,1=123,2=0.000000
L 0.1837999 2.5825 0.19019951 2.5825 1 P 0 ;0,1=123,2=0.000000
L 0.1695999 2.24199961 0.17493346 2.24199961 1 P 0 ;0,1=124,2=0.000000
L 0.17493346 2.24199961 0.17493346 2.23449961 1 P 0 ;0,1=124,2=0.000000
L 0.17493346 2.23449961 0.17333337 2.23199941 1 P 0 ;0,1=124,2=0.000000
L 0.17333337 2.23199941 0.17146663 2.23033307 1 P 0 ;0,1=124,2=0.000000
L 0.17146663 2.23033307 0.1688 2.2295 1 P 0 ;0,1=124,2=0.000000
L 0.1688 2.2295 0.16613346 2.23033307 1 P 0 ;0,1=124,2=0.000000
L 0.16613346 2.23033307 0.16426663 2.23199941 1 P 0 ;0,1=124,2=0.000000
L 0.16426663 2.23199941 0.16266654 2.23449961 1 P 0 ;0,1=124,2=0.000000
L 0.16266654 2.23449961 0.16159961 2.23741644 1 P 0 ;0,1=124,2=0.000000
L 0.16159961 2.23741644 0.16106644 2.2407498 1 P 0 ;0,1=124,2=0.000000
L 0.16106644 2.2407498 0.16106644 2.24366663 1 P 0 ;0,1=124,2=0.000000
L 0.16106644 2.24366663 0.16159961 2.24616614 1 P 0 ;0,1=124,2=0.000000
L 0.16159961 2.24616614 0.16266654 2.24908366 1 P 0 ;0,1=124,2=0.000000
L 0.16266654 2.24908366 0.16426663 2.25158317 1 P 0 ;0,1=124,2=0.000000
L 0.16426663 2.25158317 0.16586634 2.25324941 1 P 0 ;0,1=124,2=0.000000
L 0.16586634 2.25324941 0.1679997 2.2545 1 P 0 ;0,1=124,2=0.000000
L 0.1679997 2.2545 0.16986644 2.2545 1 P 0 ;0,1=124,2=0.000000
L 0.16986644 2.2545 0.1719998 2.25366683 1 P 0 ;0,1=124,2=0.000000
L 0.1719998 2.25366683 0.1736 2.2519997 1 P 0 ;0,1=124,2=0.000000
L 0.1843999 2.2295 0.1843999 2.2545 1 P 0 ;0,1=124,2=0.000000
L 0.1956 2.2545 0.1956 2.2295 1 P 0 ;0,1=124,2=0.000000
L 0.1956 2.24199961 0.1843999 2.24199961 1 P 0 ;0,1=124,2=0.000000
L 0.20613327 2.23449961 0.20773297 2.23158287 1 P 0 ;0,1=124,2=0.000000
L 0.20773297 2.23158287 0.20986634 2.22991654 1 P 0 ;0,1=124,2=0.000000
L 0.20986634 2.22991654 0.21226683 2.2295 1 P 0 ;0,1=124,2=0.000000
L 0.21226683 2.2295 0.2144002 2.22991654 1 P 0 ;0,1=124,2=0.000000
L 0.2144002 2.22991654 0.21653356 2.23199941 1 P 0 ;0,1=124,2=0.000000
L 0.21653356 2.23199941 0.21786663 2.23449961 1 P 0 ;0,1=124,2=0.000000
L 0.21786663 2.23449961 0.21813317 2.2369999 1 P 0 ;0,1=124,2=0.000000
L 0.21813317 2.2369999 0.2176 2.23991594 1 P 0 ;0,1=124,2=0.000000
L 0.2176 2.23991594 0.21573327 2.24199961 1 P 0 ;0,1=124,2=0.000000
L 0.21573327 2.24199961 0.21386644 2.24283346 1 P 0 ;0,1=124,2=0.000000
L 0.21386644 2.24283346 0.21146654 2.24283346 1 P 0 ;0,1=124,2=0.000000
L 0.21386644 2.24283346 0.21546663 2.24408327 1 P 0 ;0,1=124,2=0.000000
L 0.21546663 2.24408327 0.2168001 2.24616614 1 P 0 ;0,1=124,2=0.000000
L 0.2168001 2.24616614 0.21733337 2.24866634 1 P 0 ;0,1=124,2=0.000000
L 0.21733337 2.24866634 0.2168001 2.25116654 1 P 0 ;0,1=124,2=0.000000
L 0.2168001 2.25116654 0.21546663 2.25324941 1 P 0 ;0,1=124,2=0.000000
L 0.21546663 2.25324941 0.21306663 2.2545 1 P 0 ;0,1=124,2=0.000000
L 0.21306663 2.2545 0.21066663 2.25408337 1 P 0 ;0,1=124,2=0.000000
L 0.21066663 2.25408337 0.20826663 2.25241634 1 P 0 ;0,1=124,2=0.000000
L 0.31538996 2.00933002 0.31538996 1.69933002 1 P 0 
L -0.38898002 2.00933002 0.31538996 2.00933002 1 P 0 
L 0.31538996 1.69933002 -0.38898002 1.69933002 1 P 0 
L -0.38898002 1.69933002 -0.38898002 2.00933002 1 P 0 
L 0.2545999 2.02699961 0.25993346 2.02699961 1 P 0 ;0,1=121,2=0.000000
L 0.25993346 2.02699961 0.25993346 2.01949961 1 P 0 ;0,1=121,2=0.000000
L 0.25993346 2.01949961 0.25833337 2.01699941 1 P 0 ;0,1=121,2=0.000000
L 0.25833337 2.01699941 0.25646663 2.01533307 1 P 0 ;0,1=121,2=0.000000
L 0.25646663 2.01533307 0.2538 2.0145 1 P 0 ;0,1=121,2=0.000000
L 0.2538 2.0145 0.25113346 2.01533307 1 P 0 ;0,1=121,2=0.000000
L 0.25113346 2.01533307 0.24926663 2.01699941 1 P 0 ;0,1=121,2=0.000000
L 0.24926663 2.01699941 0.24766654 2.01949961 1 P 0 ;0,1=121,2=0.000000
L 0.24766654 2.01949961 0.24659961 2.02241644 1 P 0 ;0,1=121,2=0.000000
L 0.24659961 2.02241644 0.24606644 2.0257498 1 P 0 ;0,1=121,2=0.000000
L 0.24606644 2.0257498 0.24606644 2.02866663 1 P 0 ;0,1=121,2=0.000000
L 0.24606644 2.02866663 0.24659961 2.03116614 1 P 0 ;0,1=121,2=0.000000
L 0.24659961 2.03116614 0.24766654 2.03408366 1 P 0 ;0,1=121,2=0.000000
L 0.24766654 2.03408366 0.24926663 2.03658317 1 P 0 ;0,1=121,2=0.000000
L 0.24926663 2.03658317 0.25086634 2.03824941 1 P 0 ;0,1=121,2=0.000000
L 0.25086634 2.03824941 0.2529997 2.0395 1 P 0 ;0,1=121,2=0.000000
L 0.2529997 2.0395 0.25486644 2.0395 1 P 0 ;0,1=121,2=0.000000
L 0.25486644 2.0395 0.2569998 2.03866683 1 P 0 ;0,1=121,2=0.000000
L 0.2569998 2.03866683 0.2586 2.0369997 1 P 0 ;0,1=121,2=0.000000
L 0.2693999 2.0145 0.2693999 2.0395 1 P 0 ;0,1=121,2=0.000000
L 0.2806 2.0395 0.2806 2.0145 1 P 0 ;0,1=121,2=0.000000
L 0.2806 2.02699961 0.2693999 2.02699961 1 P 0 ;0,1=121,2=0.000000
L 0.29193317 2.03533337 0.29353327 2.03783287 1 P 0 ;0,1=121,2=0.000000
L 0.29353327 2.03783287 0.2954 2.03908337 1 P 0 ;0,1=121,2=0.000000
L 0.2954 2.03908337 0.29753337 2.0395 1 P 0 ;0,1=121,2=0.000000
L 0.29753337 2.0395 0.3002 2.03866683 1 P 0 ;0,1=121,2=0.000000
L 0.3002 2.03866683 0.30206673 2.03658317 1 P 0 ;0,1=121,2=0.000000
L 0.30206673 2.03658317 0.3026 2.03408366 1 P 0 ;0,1=121,2=0.000000
L 0.3026 2.03408366 0.30233337 2.03158268 1 P 0 ;0,1=121,2=0.000000
L 0.30233337 2.03158268 0.30126644 2.0294998 1 P 0 ;0,1=121,2=0.000000
L 0.30126644 2.0294998 0.29593327 2.02533327 1 P 0 ;0,1=121,2=0.000000
L 0.29593327 2.02533327 0.29353327 2.02241644 1 P 0 ;0,1=121,2=0.000000
L 0.29353327 2.02241644 0.29193317 2.01824911 1 P 0 ;0,1=121,2=0.000000
L 0.29193317 2.01824911 0.2913999 2.0145 1 P 0 ;0,1=121,2=0.000000
L 0.2913999 2.0145 0.3026 2.0145 1 P 0 ;0,1=121,2=0.000000
L 0.32683317 1.94069961 0.3287501 1.93759931 1 P 0 ;0,1=127,2=0.000000
L 0.3287501 1.93759931 0.33104961 1.93553307 1 P 0 ;0,1=127,2=0.000000
L 0.33104961 1.93553307 0.33373307 1.9345 1 P 0 ;0,1=127,2=0.000000
L 0.33373307 1.9345 0.3367998 1.93553307 1 P 0 ;0,1=127,2=0.000000
L 0.3367998 1.93553307 0.3391 1.93759931 1 P 0 ;0,1=127,2=0.000000
L 0.3391 1.93759931 0.3414002 1.94069961 1 P 0 ;0,1=127,2=0.000000
L 0.3414002 1.94069961 0.34216673 1.94483297 1 P 0 ;0,1=127,2=0.000000
L 0.34216673 1.94483297 0.34216673 1.9655 1 P 0 ;0,1=127,2=0.000000
L 0.3701 1.9345 0.3701 1.9655 1 P 0 ;0,1=127,2=0.000000
L 0.3701 1.9655 0.35591624 1.94328327 1 P 0 ;0,1=127,2=0.000000
L 0.35591624 1.94328327 0.37508366 1.94328327 1 P 0 ;0,1=127,2=0.000000
L 0.32999961 1.8445 0.32999961 1.8755 1 P 0 ;0,1=2,2=0.000000
L 0.32999961 1.8755 0.3253999 1.8693003 1 P 0 ;0,1=2,2=0.000000
L 0.3253999 1.8445 0.33459931 1.8445 1 P 0 ;0,1=2,2=0.000000
L 0.33500039 1.7045999 0.33500039 1.70993346 1 P 0 ;0,1=122,2=270.000000
L 0.33500039 1.70993346 0.34250039 1.70993346 1 P 0 ;0,1=122,2=270.000000
L 0.34250039 1.70993346 0.34500059 1.70833337 1 P 0 ;0,1=122,2=270.000000
L 0.34500059 1.70833337 0.34666693 1.70646663 1 P 0 ;0,1=122,2=270.000000
L 0.34666693 1.70646663 0.3475 1.7038 1 P 0 ;0,1=122,2=270.000000
L 0.3475 1.7038 0.34666693 1.70113346 1 P 0 ;0,1=122,2=270.000000
L 0.34666693 1.70113346 0.34500059 1.69926663 1 P 0 ;0,1=122,2=270.000000
L 0.34500059 1.69926663 0.34250039 1.69766654 1 P 0 ;0,1=122,2=270.000000
L 0.34250039 1.69766654 0.33958356 1.69659961 1 P 0 ;0,1=122,2=270.000000
L 0.33958356 1.69659961 0.3362502 1.69606644 1 P 0 ;0,1=122,2=270.000000
L 0.3362502 1.69606644 0.33333337 1.69606644 1 P 0 ;0,1=122,2=270.000000
L 0.33333337 1.69606644 0.33083386 1.69659961 1 P 0 ;0,1=122,2=270.000000
L 0.33083386 1.69659961 0.32791634 1.69766654 1 P 0 ;0,1=122,2=270.000000
L 0.32791634 1.69766654 0.32541683 1.69926663 1 P 0 ;0,1=122,2=270.000000
L 0.32541683 1.69926663 0.32375059 1.70086634 1 P 0 ;0,1=122,2=270.000000
L 0.32375059 1.70086634 0.3225 1.7029997 1 P 0 ;0,1=122,2=270.000000
L 0.3225 1.7029997 0.3225 1.70486644 1 P 0 ;0,1=122,2=270.000000
L 0.3225 1.70486644 0.32333317 1.7069998 1 P 0 ;0,1=122,2=270.000000
L 0.32333317 1.7069998 0.3250003 1.7086 1 P 0 ;0,1=122,2=270.000000
L 0.3475 1.7193999 0.3225 1.7193999 1 P 0 ;0,1=122,2=270.000000
L 0.3225 1.7306 0.3475 1.7306 1 P 0 ;0,1=122,2=270.000000
L 0.33500039 1.7306 0.33500039 1.7193999 1 P 0 ;0,1=122,2=270.000000
L 0.3475 1.7502 0.3225 1.7502 1 P 0 ;0,1=122,2=270.000000
L 0.3225 1.7502 0.34041673 1.74033297 1 P 0 ;0,1=122,2=270.000000
L 0.34041673 1.74033297 0.34041673 1.75366693 1 P 0 ;0,1=122,2=270.000000
L 0.1295999 2.02199961 0.13493346 2.02199961 1 P 0 ;0,1=123,2=0.000000
L 0.13493346 2.02199961 0.13493346 2.01449961 1 P 0 ;0,1=123,2=0.000000
L 0.13493346 2.01449961 0.13333337 2.01199941 1 P 0 ;0,1=123,2=0.000000
L 0.13333337 2.01199941 0.13146663 2.01033307 1 P 0 ;0,1=123,2=0.000000
L 0.13146663 2.01033307 0.1288 2.0095 1 P 0 ;0,1=123,2=0.000000
L 0.1288 2.0095 0.12613346 2.01033307 1 P 0 ;0,1=123,2=0.000000
L 0.12613346 2.01033307 0.12426663 2.01199941 1 P 0 ;0,1=123,2=0.000000
L 0.12426663 2.01199941 0.12266654 2.01449961 1 P 0 ;0,1=123,2=0.000000
L 0.12266654 2.01449961 0.12159961 2.01741644 1 P 0 ;0,1=123,2=0.000000
L 0.12159961 2.01741644 0.12106644 2.0207498 1 P 0 ;0,1=123,2=0.000000
L 0.12106644 2.0207498 0.12106644 2.02366663 1 P 0 ;0,1=123,2=0.000000
L 0.12106644 2.02366663 0.12159961 2.02616614 1 P 0 ;0,1=123,2=0.000000
L 0.12159961 2.02616614 0.12266654 2.02908366 1 P 0 ;0,1=123,2=0.000000
L 0.12266654 2.02908366 0.12426663 2.03158317 1 P 0 ;0,1=123,2=0.000000
L 0.12426663 2.03158317 0.12586634 2.03324941 1 P 0 ;0,1=123,2=0.000000
L 0.12586634 2.03324941 0.1279997 2.0345 1 P 0 ;0,1=123,2=0.000000
L 0.1279997 2.0345 0.12986644 2.0345 1 P 0 ;0,1=123,2=0.000000
L 0.12986644 2.0345 0.1319998 2.03366683 1 P 0 ;0,1=123,2=0.000000
L 0.1319998 2.03366683 0.1336 2.0319997 1 P 0 ;0,1=123,2=0.000000
L 0.1443999 2.0095 0.1443999 2.0345 1 P 0 ;0,1=123,2=0.000000
L 0.1556 2.0345 0.1556 2.0095 1 P 0 ;0,1=123,2=0.000000
L 0.1556 2.02199961 0.1443999 2.02199961 1 P 0 ;0,1=123,2=0.000000
L 0.1719997 2.0095 0.1719997 2.0345 1 P 0 ;0,1=123,2=0.000000
L 0.1719997 2.0345 0.1687999 2.0295003 1 P 0 ;0,1=123,2=0.000000
L 0.1687999 2.0095 0.17519951 2.0095 1 P 0 ;0,1=123,2=0.000000
L 0.0745999 1.68499961 0.07993346 1.68499961 1 P 0 ;0,1=124,2=0.000000
L 0.07993346 1.68499961 0.07993346 1.67749961 1 P 0 ;0,1=124,2=0.000000
L 0.07993346 1.67749961 0.07833337 1.67499941 1 P 0 ;0,1=124,2=0.000000
L 0.07833337 1.67499941 0.07646663 1.67333307 1 P 0 ;0,1=124,2=0.000000
L 0.07646663 1.67333307 0.0738 1.6725 1 P 0 ;0,1=124,2=0.000000
L 0.0738 1.6725 0.07113346 1.67333307 1 P 0 ;0,1=124,2=0.000000
L 0.07113346 1.67333307 0.06926663 1.67499941 1 P 0 ;0,1=124,2=0.000000
L 0.06926663 1.67499941 0.06766654 1.67749961 1 P 0 ;0,1=124,2=0.000000
L 0.06766654 1.67749961 0.06659961 1.68041644 1 P 0 ;0,1=124,2=0.000000
L 0.06659961 1.68041644 0.06606644 1.6837498 1 P 0 ;0,1=124,2=0.000000
L 0.06606644 1.6837498 0.06606644 1.68666663 1 P 0 ;0,1=124,2=0.000000
L 0.06606644 1.68666663 0.06659961 1.68916614 1 P 0 ;0,1=124,2=0.000000
L 0.06659961 1.68916614 0.06766654 1.69208366 1 P 0 ;0,1=124,2=0.000000
L 0.06766654 1.69208366 0.06926663 1.69458317 1 P 0 ;0,1=124,2=0.000000
L 0.06926663 1.69458317 0.07086634 1.69624941 1 P 0 ;0,1=124,2=0.000000
L 0.07086634 1.69624941 0.0729997 1.6975 1 P 0 ;0,1=124,2=0.000000
L 0.0729997 1.6975 0.07486644 1.6975 1 P 0 ;0,1=124,2=0.000000
L 0.07486644 1.6975 0.0769998 1.69666683 1 P 0 ;0,1=124,2=0.000000
L 0.0769998 1.69666683 0.0786 1.6949997 1 P 0 ;0,1=124,2=0.000000
L 0.0893999 1.6725 0.0893999 1.6975 1 P 0 ;0,1=124,2=0.000000
L 0.1006 1.6975 0.1006 1.6725 1 P 0 ;0,1=124,2=0.000000
L 0.1006 1.68499961 0.0893999 1.68499961 1 P 0 ;0,1=124,2=0.000000
L 0.11113327 1.67749961 0.11273297 1.67458287 1 P 0 ;0,1=124,2=0.000000
L 0.11273297 1.67458287 0.11486634 1.67291654 1 P 0 ;0,1=124,2=0.000000
L 0.11486634 1.67291654 0.11726683 1.6725 1 P 0 ;0,1=124,2=0.000000
L 0.11726683 1.6725 0.1194002 1.67291654 1 P 0 ;0,1=124,2=0.000000
L 0.1194002 1.67291654 0.12153356 1.67499941 1 P 0 ;0,1=124,2=0.000000
L 0.12153356 1.67499941 0.12286663 1.67749961 1 P 0 ;0,1=124,2=0.000000
L 0.12286663 1.67749961 0.12313317 1.6799999 1 P 0 ;0,1=124,2=0.000000
L 0.12313317 1.6799999 0.1226 1.68291594 1 P 0 ;0,1=124,2=0.000000
L 0.1226 1.68291594 0.12073327 1.68499961 1 P 0 ;0,1=124,2=0.000000
L 0.12073327 1.68499961 0.11886644 1.68583346 1 P 0 ;0,1=124,2=0.000000
L 0.11886644 1.68583346 0.11646654 1.68583346 1 P 0 ;0,1=124,2=0.000000
L 0.11886644 1.68583346 0.12046663 1.68708327 1 P 0 ;0,1=124,2=0.000000
L 0.12046663 1.68708327 0.1218001 1.68916614 1 P 0 ;0,1=124,2=0.000000
L 0.1218001 1.68916614 0.12233337 1.69166634 1 P 0 ;0,1=124,2=0.000000
L 0.12233337 1.69166634 0.1218001 1.69416654 1 P 0 ;0,1=124,2=0.000000
L 0.1218001 1.69416654 0.12046663 1.69624941 1 P 0 ;0,1=124,2=0.000000
L 0.12046663 1.69624941 0.11806663 1.6975 1 P 0 ;0,1=124,2=0.000000
L 0.11806663 1.6975 0.11566663 1.69708337 1 P 0 ;0,1=124,2=0.000000
L 0.11566663 1.69708337 0.11326663 1.69541634 1 P 0 ;0,1=124,2=0.000000
L 0.02641998 1.48508002 0.04123996 1.48508002 1 P 0 
L 0.04123996 1.48508002 0.04123996 1.4607 1 P 0 
L 0.04123996 1.4607 0.10251998 1.4607 1 P 0 
L 0.10251998 1.4607 0.10251998 1.61803996 1 P 0 
L 0.10251998 1.61803996 0.04123996 1.61803996 1 P 0 
L 0.04123996 1.61803996 0.04123996 1.59366004 1 P 0 
L 0.04123996 1.59366004 0.02641998 1.59366004 1 P 0 
L 0.02641998 1.59366004 0.02641998 1.48508002 1 P 0 
S P 0
OB -0.006980019685 1.510469980315 I
OS 0.00203996063 1.522469980315
OS 0.00203996063 1.513469980315
OS 0.01103996063 1.513469980315
OS 0.01103996063 1.507469980315
OS 0.00203996063 1.507469980315
OS 0.00203996063 1.498469980315
OS -0.006980019685 1.510469980315
OE
SE
S P 0
OB -0.00781003937 1.575530019685 I
OS 0.00121003937 1.587530019685
OS 0.00121003937 1.578530019685
OS 0.01021003937 1.578530019685
OS 0.01021003937 1.572530019685
OS 0.00121003937 1.572530019685
OS 0.00121003937 1.563530019685
OS -0.00781003937 1.575530019685
OE
SE
L 0.0382 1.6375 0.0382 1.6625 1 P 0 ;0,1=11,2=0.000000
L 0.0382 1.6625 0.02833297 1.64458327 1 P 0 ;0,1=11,2=0.000000
L 0.02833297 1.64458327 0.04166693 1.64458327 1 P 0 ;0,1=11,2=0.000000
L 0.11413327 1.58449961 0.11573297 1.58158287 1 P 0 ;0,1=10,2=0.000000
L 0.11573297 1.58158287 0.11786634 1.57991654 1 P 0 ;0,1=10,2=0.000000
L 0.11786634 1.57991654 0.12026683 1.5795 1 P 0 ;0,1=10,2=0.000000
L 0.12026683 1.5795 0.1224002 1.57991654 1 P 0 ;0,1=10,2=0.000000
L 0.1224002 1.57991654 0.12453356 1.58199941 1 P 0 ;0,1=10,2=0.000000
L 0.12453356 1.58199941 0.12586663 1.58449961 1 P 0 ;0,1=10,2=0.000000
L 0.12586663 1.58449961 0.12613317 1.5869999 1 P 0 ;0,1=10,2=0.000000
L 0.12613317 1.5869999 0.1256 1.58991594 1 P 0 ;0,1=10,2=0.000000
L 0.1256 1.58991594 0.12373327 1.59199961 1 P 0 ;0,1=10,2=0.000000
L 0.12373327 1.59199961 0.12186644 1.59283346 1 P 0 ;0,1=10,2=0.000000
L 0.12186644 1.59283346 0.11946654 1.59283346 1 P 0 ;0,1=10,2=0.000000
L 0.12186644 1.59283346 0.12346663 1.59408327 1 P 0 ;0,1=10,2=0.000000
L 0.12346663 1.59408327 0.1248001 1.59616614 1 P 0 ;0,1=10,2=0.000000
L 0.1248001 1.59616614 0.12533337 1.59866634 1 P 0 ;0,1=10,2=0.000000
L 0.12533337 1.59866634 0.1248001 1.60116654 1 P 0 ;0,1=10,2=0.000000
L 0.1248001 1.60116654 0.12346663 1.60324941 1 P 0 ;0,1=10,2=0.000000
L 0.12346663 1.60324941 0.12106663 1.6045 1 P 0 ;0,1=10,2=0.000000
L 0.12106663 1.6045 0.11866663 1.60408337 1 P 0 ;0,1=10,2=0.000000
L 0.11866663 1.60408337 0.11626663 1.60241634 1 P 0 ;0,1=10,2=0.000000
L 0.10993317 1.50333337 0.11153327 1.50583287 1 P 0 ;0,1=4,2=0.000000
L 0.11153327 1.50583287 0.1134 1.50708337 1 P 0 ;0,1=4,2=0.000000
L 0.1134 1.50708337 0.11553337 1.5075 1 P 0 ;0,1=4,2=0.000000
L 0.11553337 1.5075 0.1182 1.50666683 1 P 0 ;0,1=4,2=0.000000
L 0.1182 1.50666683 0.12006673 1.50458317 1 P 0 ;0,1=4,2=0.000000
L 0.12006673 1.50458317 0.1206 1.50208366 1 P 0 ;0,1=4,2=0.000000
L 0.1206 1.50208366 0.12033337 1.49958268 1 P 0 ;0,1=4,2=0.000000
L 0.12033337 1.49958268 0.11926644 1.4974998 1 P 0 ;0,1=4,2=0.000000
L 0.11926644 1.4974998 0.11393327 1.49333327 1 P 0 ;0,1=4,2=0.000000
L 0.11393327 1.49333327 0.11153327 1.49041644 1 P 0 ;0,1=4,2=0.000000
L 0.11153327 1.49041644 0.10993317 1.48624911 1 P 0 ;0,1=4,2=0.000000
L 0.10993317 1.48624911 0.1093999 1.4825 1 P 0 ;0,1=4,2=0.000000
L 0.1093999 1.4825 0.1206 1.4825 1 P 0 ;0,1=4,2=0.000000
L 0.05506663 1.6345 0.05506663 1.6655 1 P 0 ;0,1=128,2=0.000000
L 0.05506663 1.6655 0.06273307 1.6655 1 P 0 ;0,1=128,2=0.000000
L 0.06273307 1.6655 0.0657998 1.66394931 1 P 0 ;0,1=128,2=0.000000
L 0.0657998 1.66394931 0.0681 1.66188307 1 P 0 ;0,1=128,2=0.000000
L 0.0681 1.66188307 0.07001703 1.65878376 1 P 0 ;0,1=128,2=0.000000
L 0.07001703 1.65878376 0.07155 1.65516594 1 P 0 ;0,1=128,2=0.000000
L 0.07155 1.65516594 0.07193327 1.64999951 1 P 0 ;0,1=128,2=0.000000
L 0.07193327 1.64999951 0.07155 1.64483297 1 P 0 ;0,1=128,2=0.000000
L 0.07155 1.64483297 0.07001703 1.64121614 1 P 0 ;0,1=128,2=0.000000
L 0.07001703 1.64121614 0.0681 1.63811585 1 P 0 ;0,1=128,2=0.000000
L 0.0681 1.63811585 0.0657998 1.63604961 1 P 0 ;0,1=128,2=0.000000
L 0.0657998 1.63604961 0.06273307 1.6345 1 P 0 ;0,1=128,2=0.000000
L 0.06273307 1.6345 0.05506663 1.6345 1 P 0 ;0,1=128,2=0.000000
L 0.0864499 1.63863238 0.08951663 1.63604961 1 P 0 ;0,1=128,2=0.000000
L 0.08951663 1.63604961 0.09296663 1.6345 1 P 0 ;0,1=128,2=0.000000
L 0.09296663 1.6345 0.09603327 1.6345 1 P 0 ;0,1=128,2=0.000000
L 0.09603327 1.6345 0.0991 1.63604961 1 P 0 ;0,1=128,2=0.000000
L 0.0991 1.63604961 0.1014002 1.63863238 1 P 0 ;0,1=128,2=0.000000
L 0.1014002 1.63863238 0.10255 1.6422502 1 P 0 ;0,1=128,2=0.000000
L 0.10255 1.6422502 0.10178346 1.64586604 1 P 0 ;0,1=128,2=0.000000
L 0.10178346 1.64586604 0.09986654 1.64896634 1 P 0 ;0,1=128,2=0.000000
L 0.09986654 1.64896634 0.09641654 1.65103356 1 P 0 ;0,1=128,2=0.000000
L 0.09641654 1.65103356 0.09181683 1.65206663 1 P 0 ;0,1=128,2=0.000000
L 0.09181683 1.65206663 0.08913337 1.65413287 1 P 0 ;0,1=128,2=0.000000
L 0.08913337 1.65413287 0.08798287 1.6577497 1 P 0 ;0,1=128,2=0.000000
L 0.08798287 1.6577497 0.0887501 1.66136654 1 P 0 ;0,1=128,2=0.000000
L 0.0887501 1.66136654 0.09066634 1.66394931 1 P 0 ;0,1=128,2=0.000000
L 0.09066634 1.66394931 0.0933498 1.6655 1 P 0 ;0,1=128,2=0.000000
L 0.0933498 1.6655 0.09603327 1.6655 1 P 0 ;0,1=128,2=0.000000
L 0.09603327 1.6655 0.09871673 1.66446683 1 P 0 ;0,1=128,2=0.000000
L 0.09871673 1.66446683 0.10101703 1.66188307 1 P 0 ;0,1=128,2=0.000000
L 0.12549961 1.6345 0.12549961 1.6655 1 P 0 ;0,1=128,2=0.000000
L 0.12549961 1.6655 0.1208999 1.6593003 1 P 0 ;0,1=128,2=0.000000
L 0.1208999 1.6345 0.13009931 1.6345 1 P 0 ;0,1=128,2=0.000000
L 0.1611 1.6345 0.1611 1.6655 1 P 0 ;0,1=128,2=0.000000
L 0.1611 1.6655 0.14691624 1.64328327 1 P 0 ;0,1=128,2=0.000000
L 0.14691624 1.64328327 0.16608366 1.64328327 1 P 0 ;0,1=128,2=0.000000
L 0.08785 1.44581959 0.05685 1.44581959 1 P 0 ;0,1=2,2=270.000000
L 0.05685 1.44581959 0.0630497 1.44121988 1 P 0 ;0,1=2,2=270.000000
L 0.08785 1.44121988 0.08785 1.45041929 1 P 0 ;0,1=2,2=270.000000
L 0.10251998 2.18891004 0.04123996 2.18891004 1 P 0 
L 0.04123996 2.18891004 0.04123996 2.16453002 1 P 0 
L 0.04123996 2.16453002 0.02641998 2.16453002 1 P 0 
L 0.02641998 2.05595 0.04123996 2.05595 1 P 0 
L 0.04123996 2.05595 0.04123996 2.03156998 1 P 0 
L 0.04123996 2.03156998 0.10251998 2.03156998 1 P 0 
L 0.10251998 2.03156998 0.10251998 2.18891004 1 P 0 
L 0.02641998 2.16453002 0.02641998 2.05595 1 P 0 
S P 0
OB -0.006980019685 2.08133996063 I
OS 0.00203996063 2.09333996063
OS 0.00203996063 2.08433996063
OS 0.01103996063 2.08433996063
OS 0.01103996063 2.07833996063
OS 0.00203996063 2.07833996063
OS 0.00203996063 2.06933996063
OS -0.006980019685 2.08133996063
OE
SE
S P 0
OB -0.00781003937 2.1464 I
OS 0.00121003937 2.1584
OS 0.00121003937 2.1494
OS 0.01021003937 2.1494
OS 0.01021003937 2.1434
OS 0.00121003937 2.1434
OS 0.00121003937 2.1344
OS -0.00781003937 2.1464
OE
SE
L 0.03506663 2.2095 0.03506663 2.2405 1 P 0 ;0,1=129,2=0.000000
L 0.03506663 2.2405 0.04273307 2.2405 1 P 0 ;0,1=129,2=0.000000
L 0.04273307 2.2405 0.0457998 2.23894931 1 P 0 ;0,1=129,2=0.000000
L 0.0457998 2.23894931 0.0481 2.23688307 1 P 0 ;0,1=129,2=0.000000
L 0.0481 2.23688307 0.05001703 2.23378376 1 P 0 ;0,1=129,2=0.000000
L 0.05001703 2.23378376 0.05155 2.23016594 1 P 0 ;0,1=129,2=0.000000
L 0.05155 2.23016594 0.05193327 2.22499951 1 P 0 ;0,1=129,2=0.000000
L 0.05193327 2.22499951 0.05155 2.21983297 1 P 0 ;0,1=129,2=0.000000
L 0.05155 2.21983297 0.05001703 2.21621614 1 P 0 ;0,1=129,2=0.000000
L 0.05001703 2.21621614 0.0481 2.21311585 1 P 0 ;0,1=129,2=0.000000
L 0.0481 2.21311585 0.0457998 2.21104961 1 P 0 ;0,1=129,2=0.000000
L 0.0457998 2.21104961 0.04273307 2.2095 1 P 0 ;0,1=129,2=0.000000
L 0.04273307 2.2095 0.03506663 2.2095 1 P 0 ;0,1=129,2=0.000000
L 0.0664499 2.21363238 0.06951663 2.21104961 1 P 0 ;0,1=129,2=0.000000
L 0.06951663 2.21104961 0.07296663 2.2095 1 P 0 ;0,1=129,2=0.000000
L 0.07296663 2.2095 0.07603327 2.2095 1 P 0 ;0,1=129,2=0.000000
L 0.07603327 2.2095 0.0791 2.21104961 1 P 0 ;0,1=129,2=0.000000
L 0.0791 2.21104961 0.0814002 2.21363238 1 P 0 ;0,1=129,2=0.000000
L 0.0814002 2.21363238 0.08255 2.2172502 1 P 0 ;0,1=129,2=0.000000
L 0.08255 2.2172502 0.08178346 2.22086604 1 P 0 ;0,1=129,2=0.000000
L 0.08178346 2.22086604 0.07986654 2.22396634 1 P 0 ;0,1=129,2=0.000000
L 0.07986654 2.22396634 0.07641654 2.22603356 1 P 0 ;0,1=129,2=0.000000
L 0.07641654 2.22603356 0.07181683 2.22706663 1 P 0 ;0,1=129,2=0.000000
L 0.07181683 2.22706663 0.06913337 2.22913287 1 P 0 ;0,1=129,2=0.000000
L 0.06913337 2.22913287 0.06798287 2.2327497 1 P 0 ;0,1=129,2=0.000000
L 0.06798287 2.2327497 0.0687501 2.23636654 1 P 0 ;0,1=129,2=0.000000
L 0.0687501 2.23636654 0.07066634 2.23894931 1 P 0 ;0,1=129,2=0.000000
L 0.07066634 2.23894931 0.0733498 2.2405 1 P 0 ;0,1=129,2=0.000000
L 0.0733498 2.2405 0.07603327 2.2405 1 P 0 ;0,1=129,2=0.000000
L 0.07603327 2.2405 0.07871673 2.23946683 1 P 0 ;0,1=129,2=0.000000
L 0.07871673 2.23946683 0.08101703 2.23688307 1 P 0 ;0,1=129,2=0.000000
L 0.10549961 2.2095 0.10549961 2.2405 1 P 0 ;0,1=129,2=0.000000
L 0.10549961 2.2405 0.1008999 2.2343003 1 P 0 ;0,1=129,2=0.000000
L 0.1008999 2.2095 0.11009931 2.2095 1 P 0 ;0,1=129,2=0.000000
L 0.13573307 2.2095 0.13649961 2.21621614 1 P 0 ;0,1=129,2=0.000000
L 0.13649961 2.21621614 0.1376501 2.22189921 1 P 0 ;0,1=129,2=0.000000
L 0.1376501 2.22189921 0.13918307 2.22706663 1 P 0 ;0,1=129,2=0.000000
L 0.13918307 2.22706663 0.1411 2.2327497 1 P 0 ;0,1=129,2=0.000000
L 0.1411 2.2327497 0.14416673 2.2405 1 P 0 ;0,1=129,2=0.000000
L 0.14416673 2.2405 0.12883317 2.2405 1 P 0 ;0,1=129,2=0.000000
L 0.08785 2.01668957 0.05685 2.01668957 1 P 0 ;0,1=2,2=270.000000
L 0.05685 2.01668957 0.0630497 2.01208986 1 P 0 ;0,1=2,2=270.000000
L 0.08785 2.01208986 0.08785 2.02128927 1 P 0 ;0,1=2,2=270.000000
L 0.11413327 2.16249961 0.11573297 2.15958287 1 P 0 ;0,1=10,2=0.000000
L 0.11573297 2.15958287 0.11786634 2.15791654 1 P 0 ;0,1=10,2=0.000000
L 0.11786634 2.15791654 0.12026683 2.1575 1 P 0 ;0,1=10,2=0.000000
L 0.12026683 2.1575 0.1224002 2.15791654 1 P 0 ;0,1=10,2=0.000000
L 0.1224002 2.15791654 0.12453356 2.15999941 1 P 0 ;0,1=10,2=0.000000
L 0.12453356 2.15999941 0.12586663 2.16249961 1 P 0 ;0,1=10,2=0.000000
L 0.12586663 2.16249961 0.12613317 2.1649999 1 P 0 ;0,1=10,2=0.000000
L 0.12613317 2.1649999 0.1256 2.16791594 1 P 0 ;0,1=10,2=0.000000
L 0.1256 2.16791594 0.12373327 2.16999961 1 P 0 ;0,1=10,2=0.000000
L 0.12373327 2.16999961 0.12186644 2.17083346 1 P 0 ;0,1=10,2=0.000000
L 0.12186644 2.17083346 0.11946654 2.17083346 1 P 0 ;0,1=10,2=0.000000
L 0.12186644 2.17083346 0.12346663 2.17208327 1 P 0 ;0,1=10,2=0.000000
L 0.12346663 2.17208327 0.1248001 2.17416614 1 P 0 ;0,1=10,2=0.000000
L 0.1248001 2.17416614 0.12533337 2.17666634 1 P 0 ;0,1=10,2=0.000000
L 0.12533337 2.17666634 0.1248001 2.17916654 1 P 0 ;0,1=10,2=0.000000
L 0.1248001 2.17916654 0.12346663 2.18124941 1 P 0 ;0,1=10,2=0.000000
L 0.12346663 2.18124941 0.12106663 2.1825 1 P 0 ;0,1=10,2=0.000000
L 0.12106663 2.1825 0.11866663 2.18208337 1 P 0 ;0,1=10,2=0.000000
L 0.11866663 2.18208337 0.11626663 2.18041634 1 P 0 ;0,1=10,2=0.000000
L 0.10993317 2.07833337 0.11153327 2.08083287 1 P 0 ;0,1=4,2=0.000000
L 0.11153327 2.08083287 0.1134 2.08208337 1 P 0 ;0,1=4,2=0.000000
L 0.1134 2.08208337 0.11553337 2.0825 1 P 0 ;0,1=4,2=0.000000
L 0.11553337 2.0825 0.1182 2.08166683 1 P 0 ;0,1=4,2=0.000000
L 0.1182 2.08166683 0.12006673 2.07958317 1 P 0 ;0,1=4,2=0.000000
L 0.12006673 2.07958317 0.1206 2.07708366 1 P 0 ;0,1=4,2=0.000000
L 0.1206 2.07708366 0.12033337 2.07458268 1 P 0 ;0,1=4,2=0.000000
L 0.12033337 2.07458268 0.11926644 2.0724998 1 P 0 ;0,1=4,2=0.000000
L 0.11926644 2.0724998 0.11393327 2.06833327 1 P 0 ;0,1=4,2=0.000000
L 0.11393327 2.06833327 0.11153327 2.06541644 1 P 0 ;0,1=4,2=0.000000
L 0.11153327 2.06541644 0.10993317 2.06124911 1 P 0 ;0,1=4,2=0.000000
L 0.10993317 2.06124911 0.1093999 2.0575 1 P 0 ;0,1=4,2=0.000000
L 0.1093999 2.0575 0.1206 2.0575 1 P 0 ;0,1=4,2=0.000000
L 0.04123996 1.02278996 0.02641998 1.02278996 1 P 0 
L 0.04123996 1.04716998 0.04123996 1.02278996 1 P 0 
L 0.10251998 1.04716998 0.04123996 1.04716998 1 P 0 
L 0.02641998 1.02278996 0.02641998 0.91421004 1 P 0 
L 0.10251998 0.88983002 0.10251998 1.04716998 1 P 0 
L 0.04123996 0.88983002 0.10251998 0.88983002 1 P 0 
L 0.04123996 0.91421004 0.04123996 0.88983002 1 P 0 
L 0.02641998 0.91421004 0.04123996 0.91421004 1 P 0 
S P 0
OB -0.006980019685 0.9396 I
OS 0.00203996063 0.9516
OS 0.00203996063 0.9426
OS 0.01103996063 0.9426
OS 0.01103996063 0.9366
OS 0.00203996063 0.9366
OS 0.00203996063 0.9276
OS -0.006980019685 0.9396
OE
SE
S P 0
OB -0.00781003937 1.00466003937 I
OS 0.00121003937 1.01666003937
OS 0.00121003937 1.00766003937
OS 0.01021003937 1.00766003937
OS 0.01021003937 1.00166003937
OS 0.00121003937 1.00166003937
OS 0.00121003937 0.99266003937
OS -0.00781003937 1.00466003937
OE
SE
L 0.13750039 0.98003327 0.14041713 0.98163297 1 P 0 ;0,1=10,2=270.000000
L 0.14041713 0.98163297 0.14208346 0.98376634 1 P 0 ;0,1=10,2=270.000000
L 0.14208346 0.98376634 0.1425 0.98616683 1 P 0 ;0,1=10,2=270.000000
L 0.1425 0.98616683 0.14208346 0.9883002 1 P 0 ;0,1=10,2=270.000000
L 0.14208346 0.9883002 0.14000059 0.99043356 1 P 0 ;0,1=10,2=270.000000
L 0.14000059 0.99043356 0.13750039 0.99176663 1 P 0 ;0,1=10,2=270.000000
L 0.13750039 0.99176663 0.1350001 0.99203317 1 P 0 ;0,1=10,2=270.000000
L 0.1350001 0.99203317 0.13208406 0.9915 1 P 0 ;0,1=10,2=270.000000
L 0.13208406 0.9915 0.13000039 0.98963327 1 P 0 ;0,1=10,2=270.000000
L 0.13000039 0.98963327 0.12916654 0.98776644 1 P 0 ;0,1=10,2=270.000000
L 0.12916654 0.98776644 0.12916654 0.98536654 1 P 0 ;0,1=10,2=270.000000
L 0.12916654 0.98776644 0.12791673 0.98936663 1 P 0 ;0,1=10,2=270.000000
L 0.12791673 0.98936663 0.12583386 0.9907001 1 P 0 ;0,1=10,2=270.000000
L 0.12583386 0.9907001 0.12333366 0.99123337 1 P 0 ;0,1=10,2=270.000000
L 0.12333366 0.99123337 0.12083346 0.9907001 1 P 0 ;0,1=10,2=270.000000
L 0.12083346 0.9907001 0.11875059 0.98936663 1 P 0 ;0,1=10,2=270.000000
L 0.11875059 0.98936663 0.1175 0.98696663 1 P 0 ;0,1=10,2=270.000000
L 0.1175 0.98696663 0.11791663 0.98456663 1 P 0 ;0,1=10,2=270.000000
L 0.11791663 0.98456663 0.11958366 0.98216663 1 P 0 ;0,1=10,2=270.000000
L 0.03506663 1.0595 0.03506663 1.0905 1 P 0 ;0,1=130,2=0.000000
L 0.03506663 1.0905 0.04273307 1.0905 1 P 0 ;0,1=130,2=0.000000
L 0.04273307 1.0905 0.0457998 1.08894931 1 P 0 ;0,1=130,2=0.000000
L 0.0457998 1.08894931 0.0481 1.08688307 1 P 0 ;0,1=130,2=0.000000
L 0.0481 1.08688307 0.05001703 1.08378376 1 P 0 ;0,1=130,2=0.000000
L 0.05001703 1.08378376 0.05155 1.08016594 1 P 0 ;0,1=130,2=0.000000
L 0.05155 1.08016594 0.05193327 1.07499951 1 P 0 ;0,1=130,2=0.000000
L 0.05193327 1.07499951 0.05155 1.06983297 1 P 0 ;0,1=130,2=0.000000
L 0.05155 1.06983297 0.05001703 1.06621614 1 P 0 ;0,1=130,2=0.000000
L 0.05001703 1.06621614 0.0481 1.06311585 1 P 0 ;0,1=130,2=0.000000
L 0.0481 1.06311585 0.0457998 1.06104961 1 P 0 ;0,1=130,2=0.000000
L 0.0457998 1.06104961 0.04273307 1.0595 1 P 0 ;0,1=130,2=0.000000
L 0.04273307 1.0595 0.03506663 1.0595 1 P 0 ;0,1=130,2=0.000000
L 0.0664499 1.06363238 0.06951663 1.06104961 1 P 0 ;0,1=130,2=0.000000
L 0.06951663 1.06104961 0.07296663 1.0595 1 P 0 ;0,1=130,2=0.000000
L 0.07296663 1.0595 0.07603327 1.0595 1 P 0 ;0,1=130,2=0.000000
L 0.07603327 1.0595 0.0791 1.06104961 1 P 0 ;0,1=130,2=0.000000
L 0.0791 1.06104961 0.0814002 1.06363238 1 P 0 ;0,1=130,2=0.000000
L 0.0814002 1.06363238 0.08255 1.0672502 1 P 0 ;0,1=130,2=0.000000
L 0.08255 1.0672502 0.08178346 1.07086604 1 P 0 ;0,1=130,2=0.000000
L 0.08178346 1.07086604 0.07986654 1.07396634 1 P 0 ;0,1=130,2=0.000000
L 0.07986654 1.07396634 0.07641654 1.07603356 1 P 0 ;0,1=130,2=0.000000
L 0.07641654 1.07603356 0.07181683 1.07706663 1 P 0 ;0,1=130,2=0.000000
L 0.07181683 1.07706663 0.06913337 1.07913287 1 P 0 ;0,1=130,2=0.000000
L 0.06913337 1.07913287 0.06798287 1.0827497 1 P 0 ;0,1=130,2=0.000000
L 0.06798287 1.0827497 0.0687501 1.08636654 1 P 0 ;0,1=130,2=0.000000
L 0.0687501 1.08636654 0.07066634 1.08894931 1 P 0 ;0,1=130,2=0.000000
L 0.07066634 1.08894931 0.0733498 1.0905 1 P 0 ;0,1=130,2=0.000000
L 0.0733498 1.0905 0.07603327 1.0905 1 P 0 ;0,1=130,2=0.000000
L 0.07603327 1.0905 0.07871673 1.08946683 1 P 0 ;0,1=130,2=0.000000
L 0.07871673 1.08946683 0.08101703 1.08688307 1 P 0 ;0,1=130,2=0.000000
L 0.10549961 1.0595 0.10549961 1.0905 1 P 0 ;0,1=130,2=0.000000
L 0.10549961 1.0905 0.1008999 1.0843003 1 P 0 ;0,1=130,2=0.000000
L 0.1008999 1.0595 0.11009931 1.0595 1 P 0 ;0,1=130,2=0.000000
L 0.12806663 1.06414892 0.13036614 1.06156614 1 P 0 ;0,1=130,2=0.000000
L 0.13036614 1.06156614 0.13304961 1.06001654 1 P 0 ;0,1=130,2=0.000000
L 0.13304961 1.06001654 0.13649961 1.0595 1 P 0 ;0,1=130,2=0.000000
L 0.13649961 1.0595 0.1399503 1.06053307 1 P 0 ;0,1=130,2=0.000000
L 0.1399503 1.06053307 0.14263307 1.06259931 1 P 0 ;0,1=130,2=0.000000
L 0.14263307 1.06259931 0.14455 1.06621614 1 P 0 ;0,1=130,2=0.000000
L 0.14455 1.06621614 0.14493327 1.07034951 1 P 0 ;0,1=130,2=0.000000
L 0.14493327 1.07034951 0.14416673 1.07448287 1 P 0 ;0,1=130,2=0.000000
L 0.14416673 1.07448287 0.1422498 1.07706663 1 P 0 ;0,1=130,2=0.000000
L 0.1422498 1.07706663 0.13956634 1.07913287 1 P 0 ;0,1=130,2=0.000000
L 0.13956634 1.07913287 0.13688356 1.07964941 1 P 0 ;0,1=130,2=0.000000
L 0.13688356 1.07964941 0.1342001 1.07913287 1 P 0 ;0,1=130,2=0.000000
L 0.1342001 1.07913287 0.1307501 1.07706663 1 P 0 ;0,1=130,2=0.000000
L 0.1307501 1.07706663 0.1318999 1.0905 1 P 0 ;0,1=130,2=0.000000
L 0.1318999 1.0905 0.1422498 1.0905 1 P 0 ;0,1=130,2=0.000000
L 0.0775 0.8799997 0.0525 0.8799997 1 P 0 ;0,1=2,2=270.000000
L 0.0525 0.8799997 0.0574997 0.8767999 1 P 0 ;0,1=2,2=270.000000
L 0.0775 0.8767999 0.0775 0.88319951 1 P 0 ;0,1=2,2=270.000000
L 0.12166663 0.92993317 0.11916713 0.93153327 1 P 0 ;0,1=4,2=270.000000
L 0.11916713 0.93153327 0.11791663 0.9334 1 P 0 ;0,1=4,2=270.000000
L 0.11791663 0.9334 0.1175 0.93553337 1 P 0 ;0,1=4,2=270.000000
L 0.1175 0.93553337 0.11833317 0.9382 1 P 0 ;0,1=4,2=270.000000
L 0.11833317 0.9382 0.12041683 0.94006673 1 P 0 ;0,1=4,2=270.000000
L 0.12041683 0.94006673 0.12291634 0.9406 1 P 0 ;0,1=4,2=270.000000
L 0.12291634 0.9406 0.12541732 0.94033337 1 P 0 ;0,1=4,2=270.000000
L 0.12541732 0.94033337 0.1275002 0.93926644 1 P 0 ;0,1=4,2=270.000000
L 0.1275002 0.93926644 0.13166673 0.93393327 1 P 0 ;0,1=4,2=270.000000
L 0.13166673 0.93393327 0.13458356 0.93153327 1 P 0 ;0,1=4,2=270.000000
L 0.13458356 0.93153327 0.13875089 0.92993317 1 P 0 ;0,1=4,2=270.000000
L 0.13875089 0.92993317 0.1425 0.9293999 1 P 0 ;0,1=4,2=270.000000
L 0.1425 0.9293999 0.1425 0.9406 1 P 0 ;0,1=4,2=270.000000
L 0.10251998 3.33063996 0.04123996 3.33063996 1 P 0 
L 0.04123996 3.33063996 0.04123996 3.30626004 1 P 0 
L 0.04123996 3.30626004 0.02641998 3.30626004 1 P 0 
L 0.02641998 3.19768002 0.04123996 3.19768002 1 P 0 
L 0.04123996 3.19768002 0.04123996 3.1733 1 P 0 
L 0.04123996 3.1733 0.10251998 3.1733 1 P 0 
L 0.10251998 3.1733 0.10251998 3.33063996 1 P 0 
L 0.02641998 3.30626004 0.02641998 3.19768002 1 P 0 
S P 0
OB -0.006980019685 3.223069980315 I
OS 0.00203996063 3.235069980315
OS 0.00203996063 3.226069980315
OS 0.01103996063 3.226069980315
OS 0.01103996063 3.220069980315
OS 0.00203996063 3.220069980315
OS 0.00203996063 3.211069980315
OS -0.006980019685 3.223069980315
OE
SE
S P 0
OB -0.00781003937 3.288130019685 I
OS 0.00121003937 3.300130019685
OS 0.00121003937 3.291130019685
OS 0.01021003937 3.291130019685
OS 0.01021003937 3.285130019685
OS 0.00121003937 3.285130019685
OS 0.00121003937 3.276130019685
OS -0.00781003937 3.288130019685
OE
SE
L 0.1182 3.2545 0.1182 3.2795 1 P 0 ;0,1=11,2=0.000000
L 0.1182 3.2795 0.10833297 3.26158327 1 P 0 ;0,1=11,2=0.000000
L 0.10833297 3.26158327 0.12166693 3.26158327 1 P 0 ;0,1=11,2=0.000000
L 0.13913327 3.24449961 0.14073297 3.24158287 1 P 0 ;0,1=10,2=0.000000
L 0.14073297 3.24158287 0.14286634 3.23991654 1 P 0 ;0,1=10,2=0.000000
L 0.14286634 3.23991654 0.14526683 3.2395 1 P 0 ;0,1=10,2=0.000000
L 0.14526683 3.2395 0.1474002 3.23991654 1 P 0 ;0,1=10,2=0.000000
L 0.1474002 3.23991654 0.14953356 3.24199941 1 P 0 ;0,1=10,2=0.000000
L 0.14953356 3.24199941 0.15086663 3.24449961 1 P 0 ;0,1=10,2=0.000000
L 0.15086663 3.24449961 0.15113317 3.2469999 1 P 0 ;0,1=10,2=0.000000
L 0.15113317 3.2469999 0.1506 3.24991594 1 P 0 ;0,1=10,2=0.000000
L 0.1506 3.24991594 0.14873327 3.25199961 1 P 0 ;0,1=10,2=0.000000
L 0.14873327 3.25199961 0.14686644 3.25283346 1 P 0 ;0,1=10,2=0.000000
L 0.14686644 3.25283346 0.14446654 3.25283346 1 P 0 ;0,1=10,2=0.000000
L 0.14686644 3.25283346 0.14846663 3.25408327 1 P 0 ;0,1=10,2=0.000000
L 0.14846663 3.25408327 0.1498001 3.25616614 1 P 0 ;0,1=10,2=0.000000
L 0.1498001 3.25616614 0.15033337 3.25866634 1 P 0 ;0,1=10,2=0.000000
L 0.15033337 3.25866634 0.1498001 3.26116654 1 P 0 ;0,1=10,2=0.000000
L 0.1498001 3.26116654 0.14846663 3.26324941 1 P 0 ;0,1=10,2=0.000000
L 0.14846663 3.26324941 0.14606663 3.2645 1 P 0 ;0,1=10,2=0.000000
L 0.14606663 3.2645 0.14366663 3.26408337 1 P 0 ;0,1=10,2=0.000000
L 0.14366663 3.26408337 0.14126663 3.26241634 1 P 0 ;0,1=10,2=0.000000
L 0.08785 3.15841969 0.06285 3.15841969 1 P 0 ;0,1=2,2=270.000000
L 0.06285 3.15841969 0.0678497 3.15521988 1 P 0 ;0,1=2,2=270.000000
L 0.08785 3.15521988 0.08785 3.16161949 1 P 0 ;0,1=2,2=270.000000
L 0.10993317 3.19533337 0.11153327 3.19783287 1 P 0 ;0,1=4,2=0.000000
L 0.11153327 3.19783287 0.1134 3.19908337 1 P 0 ;0,1=4,2=0.000000
L 0.1134 3.19908337 0.11553337 3.1995 1 P 0 ;0,1=4,2=0.000000
L 0.11553337 3.1995 0.1182 3.19866683 1 P 0 ;0,1=4,2=0.000000
L 0.1182 3.19866683 0.12006673 3.19658317 1 P 0 ;0,1=4,2=0.000000
L 0.12006673 3.19658317 0.1206 3.19408366 1 P 0 ;0,1=4,2=0.000000
L 0.1206 3.19408366 0.12033337 3.19158268 1 P 0 ;0,1=4,2=0.000000
L 0.12033337 3.19158268 0.11926644 3.1894998 1 P 0 ;0,1=4,2=0.000000
L 0.11926644 3.1894998 0.11393327 3.18533327 1 P 0 ;0,1=4,2=0.000000
L 0.11393327 3.18533327 0.11153327 3.18241644 1 P 0 ;0,1=4,2=0.000000
L 0.11153327 3.18241644 0.10993317 3.17824911 1 P 0 ;0,1=4,2=0.000000
L 0.10993317 3.17824911 0.1093999 3.1745 1 P 0 ;0,1=4,2=0.000000
L 0.1093999 3.1745 0.1206 3.1745 1 P 0 ;0,1=4,2=0.000000
L 0.1005 3.03006663 0.0695 3.03006663 1 P 0 ;0,1=131,2=270.000000
L 0.0695 3.03006663 0.0695 3.03773307 1 P 0 ;0,1=131,2=270.000000
L 0.0695 3.03773307 0.07105069 3.0407998 1 P 0 ;0,1=131,2=270.000000
L 0.07105069 3.0407998 0.07311693 3.0431 1 P 0 ;0,1=131,2=270.000000
L 0.07311693 3.0431 0.07621624 3.04501703 1 P 0 ;0,1=131,2=270.000000
L 0.07621624 3.04501703 0.07983406 3.04655 1 P 0 ;0,1=131,2=270.000000
L 0.07983406 3.04655 0.08500049 3.04693327 1 P 0 ;0,1=131,2=270.000000
L 0.08500049 3.04693327 0.09016703 3.04655 1 P 0 ;0,1=131,2=270.000000
L 0.09016703 3.04655 0.09378386 3.04501703 1 P 0 ;0,1=131,2=270.000000
L 0.09378386 3.04501703 0.09688415 3.0431 1 P 0 ;0,1=131,2=270.000000
L 0.09688415 3.0431 0.09895039 3.0407998 1 P 0 ;0,1=131,2=270.000000
L 0.09895039 3.0407998 0.1005 3.03773307 1 P 0 ;0,1=131,2=270.000000
L 0.1005 3.03773307 0.1005 3.03006663 1 P 0 ;0,1=131,2=270.000000
L 0.09636762 3.0614499 0.09895039 3.06451663 1 P 0 ;0,1=131,2=270.000000
L 0.09895039 3.06451663 0.1005 3.06796663 1 P 0 ;0,1=131,2=270.000000
L 0.1005 3.06796663 0.1005 3.07103327 1 P 0 ;0,1=131,2=270.000000
L 0.1005 3.07103327 0.09895039 3.0741 1 P 0 ;0,1=131,2=270.000000
L 0.09895039 3.0741 0.09636762 3.0764002 1 P 0 ;0,1=131,2=270.000000
L 0.09636762 3.0764002 0.0927498 3.07755 1 P 0 ;0,1=131,2=270.000000
L 0.0927498 3.07755 0.08913396 3.07678346 1 P 0 ;0,1=131,2=270.000000
L 0.08913396 3.07678346 0.08603366 3.07486654 1 P 0 ;0,1=131,2=270.000000
L 0.08603366 3.07486654 0.08396644 3.07141654 1 P 0 ;0,1=131,2=270.000000
L 0.08396644 3.07141654 0.08293337 3.06681683 1 P 0 ;0,1=131,2=270.000000
L 0.08293337 3.06681683 0.08086713 3.06413337 1 P 0 ;0,1=131,2=270.000000
L 0.08086713 3.06413337 0.0772503 3.06298287 1 P 0 ;0,1=131,2=270.000000
L 0.0772503 3.06298287 0.07363346 3.0637501 1 P 0 ;0,1=131,2=270.000000
L 0.07363346 3.0637501 0.07105069 3.06566634 1 P 0 ;0,1=131,2=270.000000
L 0.07105069 3.06566634 0.0695 3.0683498 1 P 0 ;0,1=131,2=270.000000
L 0.0695 3.0683498 0.0695 3.07103327 1 P 0 ;0,1=131,2=270.000000
L 0.0695 3.07103327 0.07053317 3.07371673 1 P 0 ;0,1=131,2=270.000000
L 0.07053317 3.07371673 0.07311693 3.07601703 1 P 0 ;0,1=131,2=270.000000
L 0.1005 3.10049961 0.0695 3.10049961 1 P 0 ;0,1=131,2=270.000000
L 0.0695 3.10049961 0.0756997 3.0958999 1 P 0 ;0,1=131,2=270.000000
L 0.1005 3.0958999 0.1005 3.10509931 1 P 0 ;0,1=131,2=270.000000
L 0.1005 3.13149961 0.09998346 3.13418307 1 P 0 ;0,1=131,2=270.000000
L 0.09998346 3.13418307 0.09843386 3.1372498 1 P 0 ;0,1=131,2=270.000000
L 0.09843386 3.1372498 0.09585108 3.13916673 1 P 0 ;0,1=131,2=270.000000
L 0.09585108 3.13916673 0.09223327 3.13993327 1 P 0 ;0,1=131,2=270.000000
L 0.09223327 3.13993327 0.08861732 3.13916673 1 P 0 ;0,1=131,2=270.000000
L 0.08861732 3.13916673 0.08551713 3.13686654 1 P 0 ;0,1=131,2=270.000000
L 0.08551713 3.13686654 0.08396644 3.13341654 1 P 0 ;0,1=131,2=270.000000
L 0.08396644 3.13341654 0.08396644 3.12958337 1 P 0 ;0,1=131,2=270.000000
L 0.08396644 3.12958337 0.08293337 3.12728317 1 P 0 ;0,1=131,2=270.000000
L 0.08293337 3.12728317 0.08035059 3.12536614 1 P 0 ;0,1=131,2=270.000000
L 0.08035059 3.12536614 0.07673376 3.1245997 1 P 0 ;0,1=131,2=270.000000
L 0.07673376 3.1245997 0.07311693 3.1257501 1 P 0 ;0,1=131,2=270.000000
L 0.07311693 3.1257501 0.07053317 3.12843287 1 P 0 ;0,1=131,2=270.000000
L 0.07053317 3.12843287 0.0695 3.13149961 1 P 0 ;0,1=131,2=270.000000
L 0.0695 3.13149961 0.07053317 3.13456634 1 P 0 ;0,1=131,2=270.000000
L 0.07053317 3.13456634 0.07311693 3.1372498 1 P 0 ;0,1=131,2=270.000000
L 0.07311693 3.1372498 0.07673376 3.1384002 1 P 0 ;0,1=131,2=270.000000
L 0.07673376 3.1384002 0.08035059 3.13763307 1 P 0 ;0,1=131,2=270.000000
L 0.08035059 3.13763307 0.08293337 3.13571673 1 P 0 ;0,1=131,2=270.000000
L 0.08293337 3.13571673 0.08396644 3.13341654 1 P 0 ;0,1=131,2=270.000000
L 0.08396644 3.13341654 0.08396644 3.12958337 1 P 0 ;0,1=131,2=270.000000
L 0.08396644 3.12958337 0.08551713 3.12613337 1 P 0 ;0,1=131,2=270.000000
L 0.08551713 3.12613337 0.08861732 3.12383317 1 P 0 ;0,1=131,2=270.000000
L 0.08861732 3.12383317 0.09223327 3.12306663 1 P 0 ;0,1=131,2=270.000000
L 0.09223327 3.12306663 0.09585108 3.12383317 1 P 0 ;0,1=131,2=270.000000
L 0.09585108 3.12383317 0.09843386 3.1257501 1 P 0 ;0,1=131,2=270.000000
L 0.09843386 3.1257501 0.09998346 3.12881683 1 P 0 ;0,1=131,2=270.000000
L 0.09998346 3.12881683 0.1005 3.13149961 1 P 0 ;0,1=131,2=270.000000
L 0.10251998 2.75976998 0.04123996 2.75976998 1 P 0 
L 0.04123996 2.75976998 0.04123996 2.73538996 1 P 0 
L 0.04123996 2.73538996 0.02641998 2.73538996 1 P 0 
L 0.02641998 2.62681004 0.04123996 2.62681004 1 P 0 
L 0.04123996 2.62681004 0.04123996 2.60243002 1 P 0 
L 0.04123996 2.60243002 0.10251998 2.60243002 1 P 0 
L 0.10251998 2.60243002 0.10251998 2.75976998 1 P 0 
L 0.02641998 2.73538996 0.02641998 2.62681004 1 P 0 
S P 0
OB -0.006980019685 2.6522 I
OS 0.00203996063 2.6642
OS 0.00203996063 2.6552
OS 0.01103996063 2.6552
OS 0.01103996063 2.6492
OS 0.00203996063 2.6492
OS 0.00203996063 2.6402
OS -0.006980019685 2.6522
OE
SE
S P 0
OB -0.00781003937 2.71726003937 I
OS 0.00121003937 2.72926003937
OS 0.00121003937 2.72026003937
OS 0.01021003937 2.72026003937
OS 0.01021003937 2.71426003937
OS 0.00121003937 2.71426003937
OS 0.00121003937 2.70526003937
OS -0.00781003937 2.71726003937
OE
SE
L 0.13156663 2.70069961 0.13386614 2.69708278 1 P 0 ;0,1=10,2=0.000000
L 0.13386614 2.69708278 0.13693287 2.69501654 1 P 0 ;0,1=10,2=0.000000
L 0.13693287 2.69501654 0.14038356 2.6945 1 P 0 ;0,1=10,2=0.000000
L 0.14038356 2.6945 0.1434503 2.69501654 1 P 0 ;0,1=10,2=0.000000
L 0.1434503 2.69501654 0.14651703 2.69759931 1 P 0 ;0,1=10,2=0.000000
L 0.14651703 2.69759931 0.14843327 2.70069961 1 P 0 ;0,1=10,2=0.000000
L 0.14843327 2.70069961 0.14881654 2.7037999 1 P 0 ;0,1=10,2=0.000000
L 0.14881654 2.7037999 0.14805 2.70741575 1 P 0 ;0,1=10,2=0.000000
L 0.14805 2.70741575 0.14536654 2.70999951 1 P 0 ;0,1=10,2=0.000000
L 0.14536654 2.70999951 0.14268307 2.71103356 1 P 0 ;0,1=10,2=0.000000
L 0.14268307 2.71103356 0.13923307 2.71103356 1 P 0 ;0,1=10,2=0.000000
L 0.14268307 2.71103356 0.14498327 2.71258317 1 P 0 ;0,1=10,2=0.000000
L 0.14498327 2.71258317 0.1469002 2.71516594 1 P 0 ;0,1=10,2=0.000000
L 0.1469002 2.71516594 0.14766673 2.71826624 1 P 0 ;0,1=10,2=0.000000
L 0.14766673 2.71826624 0.1469002 2.72136654 1 P 0 ;0,1=10,2=0.000000
L 0.1469002 2.72136654 0.14498327 2.72394931 1 P 0 ;0,1=10,2=0.000000
L 0.14498327 2.72394931 0.14153327 2.7255 1 P 0 ;0,1=10,2=0.000000
L 0.14153327 2.7255 0.13808337 2.72498337 1 P 0 ;0,1=10,2=0.000000
L 0.13808337 2.72498337 0.13463337 2.72291624 1 P 0 ;0,1=10,2=0.000000
L 0.1355 2.79006663 0.1045 2.79006663 1 P 0 ;0,1=132,2=270.000000
L 0.1045 2.79006663 0.1045 2.79773307 1 P 0 ;0,1=132,2=270.000000
L 0.1045 2.79773307 0.10605069 2.8007998 1 P 0 ;0,1=132,2=270.000000
L 0.10605069 2.8007998 0.10811693 2.8031 1 P 0 ;0,1=132,2=270.000000
L 0.10811693 2.8031 0.11121624 2.80501703 1 P 0 ;0,1=132,2=270.000000
L 0.11121624 2.80501703 0.11483406 2.80655 1 P 0 ;0,1=132,2=270.000000
L 0.11483406 2.80655 0.12000049 2.80693327 1 P 0 ;0,1=132,2=270.000000
L 0.12000049 2.80693327 0.12516703 2.80655 1 P 0 ;0,1=132,2=270.000000
L 0.12516703 2.80655 0.12878386 2.80501703 1 P 0 ;0,1=132,2=270.000000
L 0.12878386 2.80501703 0.13188415 2.8031 1 P 0 ;0,1=132,2=270.000000
L 0.13188415 2.8031 0.13395039 2.8007998 1 P 0 ;0,1=132,2=270.000000
L 0.13395039 2.8007998 0.1355 2.79773307 1 P 0 ;0,1=132,2=270.000000
L 0.1355 2.79773307 0.1355 2.79006663 1 P 0 ;0,1=132,2=270.000000
L 0.13136762 2.8214499 0.13395039 2.82451663 1 P 0 ;0,1=132,2=270.000000
L 0.13395039 2.82451663 0.1355 2.82796663 1 P 0 ;0,1=132,2=270.000000
L 0.1355 2.82796663 0.1355 2.83103327 1 P 0 ;0,1=132,2=270.000000
L 0.1355 2.83103327 0.13395039 2.8341 1 P 0 ;0,1=132,2=270.000000
L 0.13395039 2.8341 0.13136762 2.8364002 1 P 0 ;0,1=132,2=270.000000
L 0.13136762 2.8364002 0.1277498 2.83755 1 P 0 ;0,1=132,2=270.000000
L 0.1277498 2.83755 0.12413396 2.83678346 1 P 0 ;0,1=132,2=270.000000
L 0.12413396 2.83678346 0.12103366 2.83486654 1 P 0 ;0,1=132,2=270.000000
L 0.12103366 2.83486654 0.11896644 2.83141654 1 P 0 ;0,1=132,2=270.000000
L 0.11896644 2.83141654 0.11793337 2.82681683 1 P 0 ;0,1=132,2=270.000000
L 0.11793337 2.82681683 0.11586713 2.82413337 1 P 0 ;0,1=132,2=270.000000
L 0.11586713 2.82413337 0.1122503 2.82298287 1 P 0 ;0,1=132,2=270.000000
L 0.1122503 2.82298287 0.10863346 2.8237501 1 P 0 ;0,1=132,2=270.000000
L 0.10863346 2.8237501 0.10605069 2.82566634 1 P 0 ;0,1=132,2=270.000000
L 0.10605069 2.82566634 0.1045 2.8283498 1 P 0 ;0,1=132,2=270.000000
L 0.1045 2.8283498 0.1045 2.83103327 1 P 0 ;0,1=132,2=270.000000
L 0.1045 2.83103327 0.10553317 2.83371673 1 P 0 ;0,1=132,2=270.000000
L 0.10553317 2.83371673 0.10811693 2.83601703 1 P 0 ;0,1=132,2=270.000000
L 0.1355 2.86049961 0.1045 2.86049961 1 P 0 ;0,1=132,2=270.000000
L 0.1045 2.86049961 0.1106997 2.8558999 1 P 0 ;0,1=132,2=270.000000
L 0.1355 2.8558999 0.1355 2.86509931 1 P 0 ;0,1=132,2=270.000000
L 0.12258425 2.88421644 0.11896644 2.8868999 1 P 0 ;0,1=132,2=270.000000
L 0.11896644 2.8868999 0.1169002 2.8892001 1 P 0 ;0,1=132,2=270.000000
L 0.1169002 2.8892001 0.11586713 2.89226683 1 P 0 ;0,1=132,2=270.000000
L 0.11586713 2.89226683 0.1169002 2.8949503 1 P 0 ;0,1=132,2=270.000000
L 0.1169002 2.8949503 0.11896644 2.89686654 1 P 0 ;0,1=132,2=270.000000
L 0.11896644 2.89686654 0.12206673 2.8984002 1 P 0 ;0,1=132,2=270.000000
L 0.12206673 2.8984002 0.12568356 2.89878346 1 P 0 ;0,1=132,2=270.000000
L 0.12568356 2.89878346 0.12878386 2.8984002 1 P 0 ;0,1=132,2=270.000000
L 0.12878386 2.8984002 0.13188415 2.89686654 1 P 0 ;0,1=132,2=270.000000
L 0.13188415 2.89686654 0.13446693 2.89456634 1 P 0 ;0,1=132,2=270.000000
L 0.13446693 2.89456634 0.1355 2.89188356 1 P 0 ;0,1=132,2=270.000000
L 0.1355 2.89188356 0.13446693 2.88881683 1 P 0 ;0,1=132,2=270.000000
L 0.13446693 2.88881683 0.13136762 2.88613337 1 P 0 ;0,1=132,2=270.000000
L 0.13136762 2.88613337 0.12671673 2.8845997 1 P 0 ;0,1=132,2=270.000000
L 0.12671673 2.8845997 0.1215502 2.88421644 1 P 0 ;0,1=132,2=270.000000
L 0.1215502 2.88421644 0.11483406 2.88498287 1 P 0 ;0,1=132,2=270.000000
L 0.11483406 2.88498287 0.11121624 2.88613337 1 P 0 ;0,1=132,2=270.000000
L 0.11121624 2.88613337 0.1076003 2.88804961 1 P 0 ;0,1=132,2=270.000000
L 0.1076003 2.88804961 0.10501663 2.89073307 1 P 0 ;0,1=132,2=270.000000
L 0.10501663 2.89073307 0.1045 2.89341654 1 P 0 ;0,1=132,2=270.000000
L 0.1045 2.89341654 0.10553317 2.8961 1 P 0 ;0,1=132,2=270.000000
L 0.10553317 2.8961 0.10811693 2.89801703 1 P 0 ;0,1=132,2=270.000000
L 0.08785 2.58754961 0.05685 2.58754961 1 P 0 ;0,1=2,2=270.000000
L 0.05685 2.58754961 0.0630497 2.5829499 1 P 0 ;0,1=2,2=270.000000
L 0.08785 2.5829499 0.08785 2.59214931 1 P 0 ;0,1=2,2=270.000000
L 0.13771644 2.67533346 0.14001663 2.67843278 1 P 0 ;0,1=4,2=0.000000
L 0.14001663 2.67843278 0.1427001 2.67998337 1 P 0 ;0,1=4,2=0.000000
L 0.1427001 2.67998337 0.14576683 2.6805 1 P 0 ;0,1=4,2=0.000000
L 0.14576683 2.6805 0.1496 2.67946683 1 P 0 ;0,1=4,2=0.000000
L 0.1496 2.67946683 0.15228346 2.67688307 1 P 0 ;0,1=4,2=0.000000
L 0.15228346 2.67688307 0.15305 2.67378376 1 P 0 ;0,1=4,2=0.000000
L 0.15305 2.67378376 0.15266673 2.67068258 1 P 0 ;0,1=4,2=0.000000
L 0.15266673 2.67068258 0.15113307 2.6680998 1 P 0 ;0,1=4,2=0.000000
L 0.15113307 2.6680998 0.14346663 2.66293327 1 P 0 ;0,1=4,2=0.000000
L 0.14346663 2.66293327 0.14001663 2.65931644 1 P 0 ;0,1=4,2=0.000000
L 0.14001663 2.65931644 0.13771644 2.65414892 1 P 0 ;0,1=4,2=0.000000
L 0.13771644 2.65414892 0.1369499 2.6495 1 P 0 ;0,1=4,2=0.000000
L 0.1369499 2.6495 0.15305 2.6495 1 P 0 ;0,1=4,2=0.000000
L 1.77016998 3.08503996 1.77016998 2.94496004 1 P 0 
L 1.58983002 3.08503996 1.77016998 3.08503996 1 P 0 
L 1.77016998 2.94496004 1.58983002 2.94496004 1 P 0 
L 1.58983002 2.94496004 1.58983002 3.08503996 1 P 0 
S P 0
OB 1.579469980315 3.055280019685 I
OC 1.579469980315 3.055280019685 1.564469980315 3.055280019685 Y
OE
SE
L 1.7975 3.0339997 1.7725 3.0339997 1 P 0 ;0,1=133,2=270.000000
L 1.7725 3.0339997 1.7774997 3.0307999 1 P 0 ;0,1=133,2=270.000000
L 1.7975 3.0307999 1.7975 3.03719951 1 P 0 ;0,1=133,2=270.000000
L 1.7725 3.0559997 1.77333317 3.05386634 1 P 0 ;0,1=133,2=270.000000
L 1.77333317 3.05386634 1.77541683 3.05226663 1 P 0 ;0,1=133,2=270.000000
L 1.77541683 3.05226663 1.77791634 3.0511998 1 P 0 ;0,1=133,2=270.000000
L 1.77791634 3.0511998 1.78125049 3.0503999 1 P 0 ;0,1=133,2=270.000000
L 1.78125049 3.0503999 1.78500039 3.05013327 1 P 0 ;0,1=133,2=270.000000
L 1.78500039 3.05013327 1.78875039 3.0503999 1 P 0 ;0,1=133,2=270.000000
L 1.78875039 3.0503999 1.79208376 3.0511998 1 P 0 ;0,1=133,2=270.000000
L 1.79208376 3.0511998 1.79458396 3.05226663 1 P 0 ;0,1=133,2=270.000000
L 1.79458396 3.05226663 1.79666693 3.05386634 1 P 0 ;0,1=133,2=270.000000
L 1.79666693 3.05386634 1.7975 3.0559997 1 P 0 ;0,1=133,2=270.000000
L 1.7975 3.0559997 1.79666693 3.05813307 1 P 0 ;0,1=133,2=270.000000
L 1.79666693 3.05813307 1.79458396 3.05973327 1 P 0 ;0,1=133,2=270.000000
L 1.79458396 3.05973327 1.79208376 3.0608001 1 P 0 ;0,1=133,2=270.000000
L 1.79208376 3.0608001 1.78875039 3.0616 1 P 0 ;0,1=133,2=270.000000
L 1.78875039 3.0616 1.78500039 3.06186663 1 P 0 ;0,1=133,2=270.000000
L 1.78500039 3.06186663 1.78125049 3.0616 1 P 0 ;0,1=133,2=270.000000
L 1.78125049 3.0616 1.77791634 3.0608001 1 P 0 ;0,1=133,2=270.000000
L 1.77791634 3.0608001 1.77541683 3.05973327 1 P 0 ;0,1=133,2=270.000000
L 1.77541683 3.05973327 1.77333317 3.05813307 1 P 0 ;0,1=133,2=270.000000
L 1.77333317 3.05813307 1.7725 3.0559997 1 P 0 ;0,1=133,2=270.000000
L 1.77993317 2.97291594 1.7817999 2.97583346 1 P 0 ;0,1=8,2=0.000000
L 1.7817999 2.97583346 1.7834 2.9774998 1 P 0 ;0,1=8,2=0.000000
L 1.7834 2.9774998 1.78553337 2.97833297 1 P 0 ;0,1=8,2=0.000000
L 1.78553337 2.97833297 1.7874002 2.9774998 1 P 0 ;0,1=8,2=0.000000
L 1.7874002 2.9774998 1.78873327 2.97583346 1 P 0 ;0,1=8,2=0.000000
L 1.78873327 2.97583346 1.7898001 2.97333327 1 P 0 ;0,1=8,2=0.000000
L 1.7898001 2.97333327 1.79006673 2.97041644 1 P 0 ;0,1=8,2=0.000000
L 1.79006673 2.97041644 1.7898001 2.96791624 1 P 0 ;0,1=8,2=0.000000
L 1.7898001 2.96791624 1.78873327 2.96541604 1 P 0 ;0,1=8,2=0.000000
L 1.78873327 2.96541604 1.78713307 2.96333307 1 P 0 ;0,1=8,2=0.000000
L 1.78713307 2.96333307 1.78526683 2.9625 1 P 0 ;0,1=8,2=0.000000
L 1.78526683 2.9625 1.78313346 2.96333307 1 P 0 ;0,1=8,2=0.000000
L 1.78313346 2.96333307 1.78126663 2.96583258 1 P 0 ;0,1=8,2=0.000000
L 1.78126663 2.96583258 1.7801998 2.96958327 1 P 0 ;0,1=8,2=0.000000
L 1.7801998 2.96958327 1.77993317 2.9737498 1 P 0 ;0,1=8,2=0.000000
L 1.77993317 2.9737498 1.78046634 2.97916614 1 P 0 ;0,1=8,2=0.000000
L 1.78046634 2.97916614 1.78126663 2.98208366 1 P 0 ;0,1=8,2=0.000000
L 1.78126663 2.98208366 1.7825997 2.9849997 1 P 0 ;0,1=8,2=0.000000
L 1.7825997 2.9849997 1.78446654 2.98708337 1 P 0 ;0,1=8,2=0.000000
L 1.78446654 2.98708337 1.78633327 2.9875 1 P 0 ;0,1=8,2=0.000000
L 1.78633327 2.9875 1.7882 2.98666683 1 P 0 ;0,1=8,2=0.000000
L 1.7882 2.98666683 1.78953356 2.98458317 1 P 0 ;0,1=8,2=0.000000
L 1.56289331 2.96086909 1.56449301 2.95878622 1 P 0 ;0,1=20,2=0.000000
L 1.56449301 2.95878622 1.56635974 2.95753652 1 P 0 ;0,1=20,2=0.000000
L 1.56635974 2.95753652 1.56875974 2.95711998 1 P 0 ;0,1=20,2=0.000000
L 1.56875974 2.95711998 1.57116024 2.95795305 1 P 0 ;0,1=20,2=0.000000
L 1.57116024 2.95795305 1.57302648 2.95961939 1 P 0 ;0,1=20,2=0.000000
L 1.57302648 2.95961939 1.57436004 2.96253622 1 P 0 ;0,1=20,2=0.000000
L 1.57436004 2.96253622 1.57462667 2.96586959 1 P 0 ;0,1=20,2=0.000000
L 1.57462667 2.96586959 1.57409341 2.96920295 1 P 0 ;0,1=20,2=0.000000
L 1.57409341 2.96920295 1.57275984 2.97128661 1 P 0 ;0,1=20,2=0.000000
L 1.57275984 2.97128661 1.57089311 2.97295295 1 P 0 ;0,1=20,2=0.000000
L 1.57089311 2.97295295 1.56902687 2.97336949 1 P 0 ;0,1=20,2=0.000000
L 1.56902687 2.97336949 1.56716004 2.97295295 1 P 0 ;0,1=20,2=0.000000
L 1.56716004 2.97295295 1.56476014 2.97128661 1 P 0 ;0,1=20,2=0.000000
L 1.56476014 2.97128661 1.56555994 2.98211998 1 P 0 ;0,1=20,2=0.000000
L 1.56555994 2.98211998 1.57275984 2.98211998 1 P 0 ;0,1=20,2=0.000000
L 1.60556663 2.9205 1.60556663 2.89828327 1 P 0 ;0,1=134,2=0.000000
L 1.60556663 2.89828327 1.6070997 2.89363238 1 P 0 ;0,1=134,2=0.000000
L 1.6070997 2.89363238 1.61016634 2.89053307 1 P 0 ;0,1=134,2=0.000000
L 1.61016634 2.89053307 1.61399961 2.8895 1 P 0 ;0,1=134,2=0.000000
L 1.61399961 2.8895 1.61783356 2.89053307 1 P 0 ;0,1=134,2=0.000000
L 1.61783356 2.89053307 1.6209002 2.89363238 1 P 0 ;0,1=134,2=0.000000
L 1.6209002 2.89363238 1.62243327 2.89828327 1 P 0 ;0,1=134,2=0.000000
L 1.62243327 2.89828327 1.62243327 2.9205 1 P 0 ;0,1=134,2=0.000000
L 1.6496 2.8895 1.6496 2.9205 1 P 0 ;0,1=134,2=0.000000
L 1.6496 2.9205 1.63541624 2.89828327 1 P 0 ;0,1=134,2=0.000000
L 1.63541624 2.89828327 1.65458366 2.89828327 1 P 0 ;0,1=134,2=0.000000
L 1.67599961 2.8895 1.67599961 2.9205 1 P 0 ;0,1=134,2=0.000000
L 1.67599961 2.9205 1.6713999 2.9143003 1 P 0 ;0,1=134,2=0.000000
L 1.6713999 2.8895 1.68059931 2.8895 1 P 0 ;0,1=134,2=0.000000
L 5.19816998 2.77703996 5.19816998 2.63696004 1 P 0 
L 5.01783002 2.77703996 5.19816998 2.77703996 1 P 0 
L 5.01783002 2.63696004 5.01783002 2.77703996 1 P 0 
L 5.19816998 2.63696004 5.01783002 2.63696004 1 P 0 
S P 0
OB 5.238530019685 2.666719980315 I
OC 5.238530019685 2.666719980315 5.223530019685 2.666719980315 Y
OE
SE
L 5.08056663 2.8305 5.08056663 2.80828327 1 P 0 ;0,1=135,2=0.000000
L 5.08056663 2.80828327 5.0820997 2.80363238 1 P 0 ;0,1=135,2=0.000000
L 5.0820997 2.80363238 5.08516634 2.80053307 1 P 0 ;0,1=135,2=0.000000
L 5.08516634 2.80053307 5.08899961 2.7995 1 P 0 ;0,1=135,2=0.000000
L 5.08899961 2.7995 5.09283356 2.80053307 1 P 0 ;0,1=135,2=0.000000
L 5.09283356 2.80053307 5.0959002 2.80363238 1 P 0 ;0,1=135,2=0.000000
L 5.0959002 2.80363238 5.09743327 2.80828327 1 P 0 ;0,1=135,2=0.000000
L 5.09743327 2.80828327 5.09743327 2.8305 1 P 0 ;0,1=135,2=0.000000
L 5.11271644 2.82533346 5.11501663 2.82843278 1 P 0 ;0,1=135,2=0.000000
L 5.11501663 2.82843278 5.1177001 2.82998337 1 P 0 ;0,1=135,2=0.000000
L 5.1177001 2.82998337 5.12076683 2.8305 1 P 0 ;0,1=135,2=0.000000
L 5.12076683 2.8305 5.1246 2.82946683 1 P 0 ;0,1=135,2=0.000000
L 5.1246 2.82946683 5.12728346 2.82688307 1 P 0 ;0,1=135,2=0.000000
L 5.12728346 2.82688307 5.12805 2.82378376 1 P 0 ;0,1=135,2=0.000000
L 5.12805 2.82378376 5.12766673 2.82068258 1 P 0 ;0,1=135,2=0.000000
L 5.12766673 2.82068258 5.12613307 2.8180998 1 P 0 ;0,1=135,2=0.000000
L 5.12613307 2.8180998 5.11846663 2.81293327 1 P 0 ;0,1=135,2=0.000000
L 5.11846663 2.81293327 5.11501663 2.80931644 1 P 0 ;0,1=135,2=0.000000
L 5.11501663 2.80931644 5.11271644 2.80414892 1 P 0 ;0,1=135,2=0.000000
L 5.11271644 2.80414892 5.1119499 2.7995 1 P 0 ;0,1=135,2=0.000000
L 5.1119499 2.7995 5.12805 2.7995 1 P 0 ;0,1=135,2=0.000000
L 5.15099961 2.7995 5.15099961 2.8305 1 P 0 ;0,1=135,2=0.000000
L 5.15099961 2.8305 5.1463999 2.8243003 1 P 0 ;0,1=135,2=0.000000
L 5.1463999 2.7995 5.15559931 2.7995 1 P 0 ;0,1=135,2=0.000000
L 5.21413327 2.72324911 5.21573297 2.72116624 1 P 0 ;0,1=20,2=0.000000
L 5.21573297 2.72116624 5.2175997 2.71991654 1 P 0 ;0,1=20,2=0.000000
L 5.2175997 2.71991654 5.2199997 2.7195 1 P 0 ;0,1=20,2=0.000000
L 5.2199997 2.7195 5.2224002 2.72033307 1 P 0 ;0,1=20,2=0.000000
L 5.2224002 2.72033307 5.22426644 2.72199941 1 P 0 ;0,1=20,2=0.000000
L 5.22426644 2.72199941 5.2256 2.72491624 1 P 0 ;0,1=20,2=0.000000
L 5.2256 2.72491624 5.22586663 2.72824961 1 P 0 ;0,1=20,2=0.000000
L 5.22586663 2.72824961 5.22533337 2.73158297 1 P 0 ;0,1=20,2=0.000000
L 5.22533337 2.73158297 5.2239998 2.73366663 1 P 0 ;0,1=20,2=0.000000
L 5.2239998 2.73366663 5.22213307 2.73533297 1 P 0 ;0,1=20,2=0.000000
L 5.22213307 2.73533297 5.22026683 2.73574951 1 P 0 ;0,1=20,2=0.000000
L 5.22026683 2.73574951 5.2184 2.73533297 1 P 0 ;0,1=20,2=0.000000
L 5.2184 2.73533297 5.2160001 2.73366663 1 P 0 ;0,1=20,2=0.000000
L 5.2160001 2.73366663 5.2167999 2.7445 1 P 0 ;0,1=20,2=0.000000
L 5.2167999 2.7445 5.2239998 2.7445 1 P 0 ;0,1=20,2=0.000000
L 4.99493317 2.74491594 4.9967999 2.74783346 1 P 0 ;0,1=8,2=0.000000
L 4.9967999 2.74783346 4.9984 2.7494998 1 P 0 ;0,1=8,2=0.000000
L 4.9984 2.7494998 5.00053337 2.75033297 1 P 0 ;0,1=8,2=0.000000
L 5.00053337 2.75033297 5.0024002 2.7494998 1 P 0 ;0,1=8,2=0.000000
L 5.0024002 2.7494998 5.00373327 2.74783346 1 P 0 ;0,1=8,2=0.000000
L 5.00373327 2.74783346 5.0048001 2.74533327 1 P 0 ;0,1=8,2=0.000000
L 5.0048001 2.74533327 5.00506673 2.74241644 1 P 0 ;0,1=8,2=0.000000
L 5.00506673 2.74241644 5.0048001 2.73991624 1 P 0 ;0,1=8,2=0.000000
L 5.0048001 2.73991624 5.00373327 2.73741604 1 P 0 ;0,1=8,2=0.000000
L 5.00373327 2.73741604 5.00213307 2.73533307 1 P 0 ;0,1=8,2=0.000000
L 5.00213307 2.73533307 5.00026683 2.7345 1 P 0 ;0,1=8,2=0.000000
L 5.00026683 2.7345 4.99813346 2.73533307 1 P 0 ;0,1=8,2=0.000000
L 4.99813346 2.73533307 4.99626663 2.73783258 1 P 0 ;0,1=8,2=0.000000
L 4.99626663 2.73783258 4.9951998 2.74158327 1 P 0 ;0,1=8,2=0.000000
L 4.9951998 2.74158327 4.99493317 2.7457498 1 P 0 ;0,1=8,2=0.000000
L 4.99493317 2.7457498 4.99546634 2.75116614 1 P 0 ;0,1=8,2=0.000000
L 4.99546634 2.75116614 4.99626663 2.75408366 1 P 0 ;0,1=8,2=0.000000
L 4.99626663 2.75408366 4.9975997 2.7569997 1 P 0 ;0,1=8,2=0.000000
L 4.9975997 2.7569997 4.99946654 2.75908337 1 P 0 ;0,1=8,2=0.000000
L 4.99946654 2.75908337 5.00133327 2.7595 1 P 0 ;0,1=8,2=0.000000
L 5.00133327 2.7595 5.0032 2.75866683 1 P 0 ;0,1=8,2=0.000000
L 5.0032 2.75866683 5.00453356 2.75658317 1 P 0 ;0,1=8,2=0.000000
L 5.0125 2.6589997 4.9875 2.6589997 1 P 0 ;0,1=133,2=270.000000
L 4.9875 2.6589997 4.9924997 2.6557999 1 P 0 ;0,1=133,2=270.000000
L 5.0125 2.6557999 5.0125 2.66219951 1 P 0 ;0,1=133,2=270.000000
L 4.9875 2.6809997 4.98833317 2.67886634 1 P 0 ;0,1=133,2=270.000000
L 4.98833317 2.67886634 4.99041683 2.67726663 1 P 0 ;0,1=133,2=270.000000
L 4.99041683 2.67726663 4.99291634 2.6761998 1 P 0 ;0,1=133,2=270.000000
L 4.99291634 2.6761998 4.99625049 2.6753999 1 P 0 ;0,1=133,2=270.000000
L 4.99625049 2.6753999 5.00000039 2.67513327 1 P 0 ;0,1=133,2=270.000000
L 5.00000039 2.67513327 5.00375039 2.6753999 1 P 0 ;0,1=133,2=270.000000
L 5.00375039 2.6753999 5.00708376 2.6761998 1 P 0 ;0,1=133,2=270.000000
L 5.00708376 2.6761998 5.00958396 2.67726663 1 P 0 ;0,1=133,2=270.000000
L 5.00958396 2.67726663 5.01166693 2.67886634 1 P 0 ;0,1=133,2=270.000000
L 5.01166693 2.67886634 5.0125 2.6809997 1 P 0 ;0,1=133,2=270.000000
L 5.0125 2.6809997 5.01166693 2.68313307 1 P 0 ;0,1=133,2=270.000000
L 5.01166693 2.68313307 5.00958396 2.68473327 1 P 0 ;0,1=133,2=270.000000
L 5.00958396 2.68473327 5.00708376 2.6858001 1 P 0 ;0,1=133,2=270.000000
L 5.00708376 2.6858001 5.00375039 2.6866 1 P 0 ;0,1=133,2=270.000000
L 5.00375039 2.6866 5.00000039 2.68686663 1 P 0 ;0,1=133,2=270.000000
L 5.00000039 2.68686663 4.99625049 2.6866 1 P 0 ;0,1=133,2=270.000000
L 4.99625049 2.6866 4.99291634 2.6858001 1 P 0 ;0,1=133,2=270.000000
L 4.99291634 2.6858001 4.99041683 2.68473327 1 P 0 ;0,1=133,2=270.000000
L 4.99041683 2.68473327 4.98833317 2.68313307 1 P 0 ;0,1=133,2=270.000000
L 4.98833317 2.68313307 4.9875 2.6809997 1 P 0 ;0,1=133,2=270.000000
L 5.71516998 0.74903996 5.71516998 0.60896004 1 P 0 
L 5.53483002 0.60896004 5.53483002 0.74903996 1 P 0 
L 5.53483002 0.74903996 5.71516998 0.74903996 1 P 0 
L 5.71516998 0.60896004 5.53483002 0.60896004 1 P 0 
S P 0
OB 5.524469980315 0.719280019685 I
OC 5.524469980315 0.719280019685 5.509469980315 0.719280019685 Y
OE
SE
L 5.72621644 0.63063573 5.7288999 0.63425354 1 P 0 ;0,1=8,2=0.000000
L 5.7288999 0.63425354 5.7312001 0.63631978 1 P 0 ;0,1=8,2=0.000000
L 5.7312001 0.63631978 5.73426683 0.63735285 1 P 0 ;0,1=8,2=0.000000
L 5.73426683 0.63735285 5.7369503 0.63631978 1 P 0 ;0,1=8,2=0.000000
L 5.7369503 0.63631978 5.73886654 0.63425354 1 P 0 ;0,1=8,2=0.000000
L 5.73886654 0.63425354 5.7404002 0.63115325 1 P 0 ;0,1=8,2=0.000000
L 5.7404002 0.63115325 5.74078346 0.62753642 1 P 0 ;0,1=8,2=0.000000
L 5.74078346 0.62753642 5.7404002 0.62443612 1 P 0 ;0,1=8,2=0.000000
L 5.7404002 0.62443612 5.73886654 0.62133583 1 P 0 ;0,1=8,2=0.000000
L 5.73886654 0.62133583 5.73656634 0.61875305 1 P 0 ;0,1=8,2=0.000000
L 5.73656634 0.61875305 5.73388356 0.61771998 1 P 0 ;0,1=8,2=0.000000
L 5.73388356 0.61771998 5.73081683 0.61875305 1 P 0 ;0,1=8,2=0.000000
L 5.73081683 0.61875305 5.72813337 0.62185236 1 P 0 ;0,1=8,2=0.000000
L 5.72813337 0.62185236 5.7265997 0.62650325 1 P 0 ;0,1=8,2=0.000000
L 5.7265997 0.62650325 5.72621644 0.63166978 1 P 0 ;0,1=8,2=0.000000
L 5.72621644 0.63166978 5.72698287 0.63838593 1 P 0 ;0,1=8,2=0.000000
L 5.72698287 0.63838593 5.72813337 0.64200374 1 P 0 ;0,1=8,2=0.000000
L 5.72813337 0.64200374 5.73004961 0.64561969 1 P 0 ;0,1=8,2=0.000000
L 5.73004961 0.64561969 5.73273307 0.64820335 1 P 0 ;0,1=8,2=0.000000
L 5.73273307 0.64820335 5.73541654 0.64871998 1 P 0 ;0,1=8,2=0.000000
L 5.73541654 0.64871998 5.7381 0.64768681 1 P 0 ;0,1=8,2=0.000000
L 5.7381 0.64768681 5.74001703 0.64510305 1 P 0 ;0,1=8,2=0.000000
L 5.50156663 0.61414892 5.50386614 0.61156614 1 P 0 ;0,1=20,2=0.000000
L 5.50386614 0.61156614 5.50654961 0.61001654 1 P 0 ;0,1=20,2=0.000000
L 5.50654961 0.61001654 5.50999961 0.6095 1 P 0 ;0,1=20,2=0.000000
L 5.50999961 0.6095 5.5134503 0.61053307 1 P 0 ;0,1=20,2=0.000000
L 5.5134503 0.61053307 5.51613307 0.61259931 1 P 0 ;0,1=20,2=0.000000
L 5.51613307 0.61259931 5.51805 0.61621614 1 P 0 ;0,1=20,2=0.000000
L 5.51805 0.61621614 5.51843327 0.62034951 1 P 0 ;0,1=20,2=0.000000
L 5.51843327 0.62034951 5.51766673 0.62448287 1 P 0 ;0,1=20,2=0.000000
L 5.51766673 0.62448287 5.5157498 0.62706663 1 P 0 ;0,1=20,2=0.000000
L 5.5157498 0.62706663 5.51306634 0.62913287 1 P 0 ;0,1=20,2=0.000000
L 5.51306634 0.62913287 5.51038356 0.62964941 1 P 0 ;0,1=20,2=0.000000
L 5.51038356 0.62964941 5.5077001 0.62913287 1 P 0 ;0,1=20,2=0.000000
L 5.5077001 0.62913287 5.5042501 0.62706663 1 P 0 ;0,1=20,2=0.000000
L 5.5042501 0.62706663 5.5053999 0.6405 1 P 0 ;0,1=20,2=0.000000
L 5.5053999 0.6405 5.5157498 0.6405 1 P 0 ;0,1=20,2=0.000000
L 5.57556663 0.5905 5.57556663 0.56828327 1 P 0 ;0,1=136,2=0.000000
L 5.57556663 0.56828327 5.5770997 0.56363238 1 P 0 ;0,1=136,2=0.000000
L 5.5770997 0.56363238 5.58016634 0.56053307 1 P 0 ;0,1=136,2=0.000000
L 5.58016634 0.56053307 5.58399961 0.5595 1 P 0 ;0,1=136,2=0.000000
L 5.58399961 0.5595 5.58783356 0.56053307 1 P 0 ;0,1=136,2=0.000000
L 5.58783356 0.56053307 5.5909002 0.56363238 1 P 0 ;0,1=136,2=0.000000
L 5.5909002 0.56363238 5.59243327 0.56828327 1 P 0 ;0,1=136,2=0.000000
L 5.59243327 0.56828327 5.59243327 0.5905 1 P 0 ;0,1=136,2=0.000000
L 5.60771644 0.58533346 5.61001663 0.58843278 1 P 0 ;0,1=136,2=0.000000
L 5.61001663 0.58843278 5.6127001 0.58998337 1 P 0 ;0,1=136,2=0.000000
L 5.6127001 0.58998337 5.61576683 0.5905 1 P 0 ;0,1=136,2=0.000000
L 5.61576683 0.5905 5.6196 0.58946683 1 P 0 ;0,1=136,2=0.000000
L 5.6196 0.58946683 5.62228346 0.58688307 1 P 0 ;0,1=136,2=0.000000
L 5.62228346 0.58688307 5.62305 0.58378376 1 P 0 ;0,1=136,2=0.000000
L 5.62305 0.58378376 5.62266673 0.58068258 1 P 0 ;0,1=136,2=0.000000
L 5.62266673 0.58068258 5.62113307 0.5780998 1 P 0 ;0,1=136,2=0.000000
L 5.62113307 0.5780998 5.61346663 0.57293327 1 P 0 ;0,1=136,2=0.000000
L 5.61346663 0.57293327 5.61001663 0.56931644 1 P 0 ;0,1=136,2=0.000000
L 5.61001663 0.56931644 5.60771644 0.56414892 1 P 0 ;0,1=136,2=0.000000
L 5.60771644 0.56414892 5.6069499 0.5595 1 P 0 ;0,1=136,2=0.000000
L 5.6069499 0.5595 5.62305 0.5595 1 P 0 ;0,1=136,2=0.000000
L 5.63756663 0.56414892 5.63986614 0.56156614 1 P 0 ;0,1=136,2=0.000000
L 5.63986614 0.56156614 5.64254961 0.56001654 1 P 0 ;0,1=136,2=0.000000
L 5.64254961 0.56001654 5.64599961 0.5595 1 P 0 ;0,1=136,2=0.000000
L 5.64599961 0.5595 5.6494503 0.56053307 1 P 0 ;0,1=136,2=0.000000
L 5.6494503 0.56053307 5.65213307 0.56259931 1 P 0 ;0,1=136,2=0.000000
L 5.65213307 0.56259931 5.65405 0.56621614 1 P 0 ;0,1=136,2=0.000000
L 5.65405 0.56621614 5.65443327 0.57034951 1 P 0 ;0,1=136,2=0.000000
L 5.65443327 0.57034951 5.65366673 0.57448287 1 P 0 ;0,1=136,2=0.000000
L 5.65366673 0.57448287 5.6517498 0.57706663 1 P 0 ;0,1=136,2=0.000000
L 5.6517498 0.57706663 5.64906634 0.57913287 1 P 0 ;0,1=136,2=0.000000
L 5.64906634 0.57913287 5.64638356 0.57964941 1 P 0 ;0,1=136,2=0.000000
L 5.64638356 0.57964941 5.6437001 0.57913287 1 P 0 ;0,1=136,2=0.000000
L 5.6437001 0.57913287 5.6402501 0.57706663 1 P 0 ;0,1=136,2=0.000000
L 5.6402501 0.57706663 5.6413999 0.5905 1 P 0 ;0,1=136,2=0.000000
L 5.6413999 0.5905 5.6517498 0.5905 1 P 0 ;0,1=136,2=0.000000
L 3.84196004 3.03516998 3.98203996 3.03516998 1 P 0 
L 3.98203996 2.85483002 3.84196004 2.85483002 1 P 0 
L 3.84196004 2.85483002 3.84196004 3.03516998 1 P 0 
L 3.98203996 3.03516998 3.98203996 2.85483002 1 P 0 
S P 0
OB 3.886719980315 2.829469980315 I
OC 3.886719980315 2.829469980315 3.871719980315 2.829469980315 Y
OE
SE
L 3.99271644 3.03241575 3.9953999 3.03603356 1 P 0 ;0,1=8,2=0.000000
L 3.9953999 3.03603356 3.9977001 3.0380998 1 P 0 ;0,1=8,2=0.000000
L 3.9977001 3.0380998 4.00076683 3.03913287 1 P 0 ;0,1=8,2=0.000000
L 4.00076683 3.03913287 4.0034503 3.0380998 1 P 0 ;0,1=8,2=0.000000
L 4.0034503 3.0380998 4.00536654 3.03603356 1 P 0 ;0,1=8,2=0.000000
L 4.00536654 3.03603356 4.0069002 3.03293327 1 P 0 ;0,1=8,2=0.000000
L 4.0069002 3.03293327 4.00728346 3.02931644 1 P 0 ;0,1=8,2=0.000000
L 4.00728346 3.02931644 4.0069002 3.02621614 1 P 0 ;0,1=8,2=0.000000
L 4.0069002 3.02621614 4.00536654 3.02311585 1 P 0 ;0,1=8,2=0.000000
L 4.00536654 3.02311585 4.00306634 3.02053307 1 P 0 ;0,1=8,2=0.000000
L 4.00306634 3.02053307 4.00038356 3.0195 1 P 0 ;0,1=8,2=0.000000
L 4.00038356 3.0195 3.99731683 3.02053307 1 P 0 ;0,1=8,2=0.000000
L 3.99731683 3.02053307 3.99463337 3.02363238 1 P 0 ;0,1=8,2=0.000000
L 3.99463337 3.02363238 3.9930997 3.02828327 1 P 0 ;0,1=8,2=0.000000
L 3.9930997 3.02828327 3.99271644 3.0334498 1 P 0 ;0,1=8,2=0.000000
L 3.99271644 3.0334498 3.99348287 3.04016594 1 P 0 ;0,1=8,2=0.000000
L 3.99348287 3.04016594 3.99463337 3.04378376 1 P 0 ;0,1=8,2=0.000000
L 3.99463337 3.04378376 3.99654961 3.0473997 1 P 0 ;0,1=8,2=0.000000
L 3.99654961 3.0473997 3.99923307 3.04998337 1 P 0 ;0,1=8,2=0.000000
L 3.99923307 3.04998337 4.00191654 3.0505 1 P 0 ;0,1=8,2=0.000000
L 4.00191654 3.0505 4.0046 3.04946683 1 P 0 ;0,1=8,2=0.000000
L 4.0046 3.04946683 4.00651703 3.04688307 1 P 0 ;0,1=8,2=0.000000
L 3.9995 2.90556663 4.02171673 2.90556663 1 P 0 ;0,1=137,2=270.000000
L 4.02171673 2.90556663 4.02636762 2.9070997 1 P 0 ;0,1=137,2=270.000000
L 4.02636762 2.9070997 4.02946693 2.91016634 1 P 0 ;0,1=137,2=270.000000
L 4.02946693 2.91016634 4.0305 2.91399961 1 P 0 ;0,1=137,2=270.000000
L 4.0305 2.91399961 4.02946693 2.91783356 1 P 0 ;0,1=137,2=270.000000
L 4.02946693 2.91783356 4.02636762 2.9209002 1 P 0 ;0,1=137,2=270.000000
L 4.02636762 2.9209002 4.02171673 2.92243327 1 P 0 ;0,1=137,2=270.000000
L 4.02171673 2.92243327 3.9995 2.92243327 1 P 0 ;0,1=137,2=270.000000
L 4.00466654 2.93771644 4.00156722 2.94001663 1 P 0 ;0,1=137,2=270.000000
L 4.00156722 2.94001663 4.00001663 2.9427001 1 P 0 ;0,1=137,2=270.000000
L 4.00001663 2.9427001 3.9995 2.94576683 1 P 0 ;0,1=137,2=270.000000
L 3.9995 2.94576683 4.00053317 2.9496 1 P 0 ;0,1=137,2=270.000000
L 4.00053317 2.9496 4.00311693 2.95228346 1 P 0 ;0,1=137,2=270.000000
L 4.00311693 2.95228346 4.00621624 2.95305 1 P 0 ;0,1=137,2=270.000000
L 4.00621624 2.95305 4.00931742 2.95266673 1 P 0 ;0,1=137,2=270.000000
L 4.00931742 2.95266673 4.0119002 2.95113307 1 P 0 ;0,1=137,2=270.000000
L 4.0119002 2.95113307 4.01706673 2.94346663 1 P 0 ;0,1=137,2=270.000000
L 4.01706673 2.94346663 4.02068356 2.94001663 1 P 0 ;0,1=137,2=270.000000
L 4.02068356 2.94001663 4.02585108 2.93771644 1 P 0 ;0,1=137,2=270.000000
L 4.02585108 2.93771644 4.0305 2.9369499 1 P 0 ;0,1=137,2=270.000000
L 4.0305 2.9369499 4.0305 2.95305 1 P 0 ;0,1=137,2=270.000000
L 3.9995 2.97599961 4.00053317 2.97293287 1 P 0 ;0,1=137,2=270.000000
L 4.00053317 2.97293287 4.00311693 2.97063337 1 P 0 ;0,1=137,2=270.000000
L 4.00311693 2.97063337 4.00621624 2.9690997 1 P 0 ;0,1=137,2=270.000000
L 4.00621624 2.9690997 4.01035059 2.9679499 1 P 0 ;0,1=137,2=270.000000
L 4.01035059 2.9679499 4.01500049 2.96756663 1 P 0 ;0,1=137,2=270.000000
L 4.01500049 2.96756663 4.01965049 2.9679499 1 P 0 ;0,1=137,2=270.000000
L 4.01965049 2.9679499 4.02378386 2.9690997 1 P 0 ;0,1=137,2=270.000000
L 4.02378386 2.9690997 4.02688415 2.97063337 1 P 0 ;0,1=137,2=270.000000
L 4.02688415 2.97063337 4.02946693 2.97293287 1 P 0 ;0,1=137,2=270.000000
L 4.02946693 2.97293287 4.0305 2.97599961 1 P 0 ;0,1=137,2=270.000000
L 4.0305 2.97599961 4.02946693 2.97906634 1 P 0 ;0,1=137,2=270.000000
L 4.02946693 2.97906634 4.02688415 2.98136654 1 P 0 ;0,1=137,2=270.000000
L 4.02688415 2.98136654 4.02378386 2.9829002 1 P 0 ;0,1=137,2=270.000000
L 4.02378386 2.9829002 4.01965049 2.98405 1 P 0 ;0,1=137,2=270.000000
L 4.01965049 2.98405 4.01500049 2.98443327 1 P 0 ;0,1=137,2=270.000000
L 4.01500049 2.98443327 4.01035059 2.98405 1 P 0 ;0,1=137,2=270.000000
L 4.01035059 2.98405 4.00621624 2.9829002 1 P 0 ;0,1=137,2=270.000000
L 4.00621624 2.9829002 4.00311693 2.98136654 1 P 0 ;0,1=137,2=270.000000
L 4.00311693 2.98136654 4.00053317 2.97906634 1 P 0 ;0,1=137,2=270.000000
L 4.00053317 2.97906634 3.9995 2.97599961 1 P 0 ;0,1=137,2=270.000000
L 3.9652311 2.82532667 3.96781388 2.82762618 1 P 0 ;0,1=20,2=270.000000
L 3.96781388 2.82762618 3.96936348 2.83030965 1 P 0 ;0,1=20,2=270.000000
L 3.96936348 2.83030965 3.96988002 2.83375965 1 P 0 ;0,1=20,2=270.000000
L 3.96988002 2.83375965 3.96884695 2.83721033 1 P 0 ;0,1=20,2=270.000000
L 3.96884695 2.83721033 3.96678071 2.83989311 1 P 0 ;0,1=20,2=270.000000
L 3.96678071 2.83989311 3.96316388 2.84181004 1 P 0 ;0,1=20,2=270.000000
L 3.96316388 2.84181004 3.95903051 2.84219331 1 P 0 ;0,1=20,2=270.000000
L 3.95903051 2.84219331 3.95489715 2.84142677 1 P 0 ;0,1=20,2=270.000000
L 3.95489715 2.84142677 3.95231339 2.83950984 1 P 0 ;0,1=20,2=270.000000
L 3.95231339 2.83950984 3.95024715 2.83682638 1 P 0 ;0,1=20,2=270.000000
L 3.95024715 2.83682638 3.94973061 2.8341436 1 P 0 ;0,1=20,2=270.000000
L 3.94973061 2.8341436 3.95024715 2.83146014 1 P 0 ;0,1=20,2=270.000000
L 3.95024715 2.83146014 3.95231339 2.82801014 1 P 0 ;0,1=20,2=270.000000
L 3.95231339 2.82801014 3.93888002 2.82915994 1 P 0 ;0,1=20,2=270.000000
L 3.93888002 2.82915994 3.93888002 2.83950984 1 P 0 ;0,1=20,2=270.000000
L 4.44625 2.94506004 4.44625 2.80578996 1 P 0 
L 4.26575 2.94506004 4.44625 2.94506004 1 P 0 
L 4.44625 2.80578996 4.26575 2.80578996 1 P 0 
L 4.26575 2.80578996 4.26575 2.94506004 1 P 0 
S P 0
OB 4.505 2.80001003937 I
OC 4.505 2.80001003937 4.48500511811 2.80000738189 Y
OE
SE
L 4.47493317 2.92291594 4.4767999 2.92583346 1 P 0 ;0,1=8,2=0.000000
L 4.4767999 2.92583346 4.4784 2.9274998 1 P 0 ;0,1=8,2=0.000000
L 4.4784 2.9274998 4.48053337 2.92833297 1 P 0 ;0,1=8,2=0.000000
L 4.48053337 2.92833297 4.4824002 2.9274998 1 P 0 ;0,1=8,2=0.000000
L 4.4824002 2.9274998 4.48373327 2.92583346 1 P 0 ;0,1=8,2=0.000000
L 4.48373327 2.92583346 4.4848001 2.92333327 1 P 0 ;0,1=8,2=0.000000
L 4.4848001 2.92333327 4.48506673 2.92041644 1 P 0 ;0,1=8,2=0.000000
L 4.48506673 2.92041644 4.4848001 2.91791624 1 P 0 ;0,1=8,2=0.000000
L 4.4848001 2.91791624 4.48373327 2.91541604 1 P 0 ;0,1=8,2=0.000000
L 4.48373327 2.91541604 4.48213307 2.91333307 1 P 0 ;0,1=8,2=0.000000
L 4.48213307 2.91333307 4.48026683 2.9125 1 P 0 ;0,1=8,2=0.000000
L 4.48026683 2.9125 4.47813346 2.91333307 1 P 0 ;0,1=8,2=0.000000
L 4.47813346 2.91333307 4.47626663 2.91583258 1 P 0 ;0,1=8,2=0.000000
L 4.47626663 2.91583258 4.4751998 2.91958327 1 P 0 ;0,1=8,2=0.000000
L 4.4751998 2.91958327 4.47493317 2.9237498 1 P 0 ;0,1=8,2=0.000000
L 4.47493317 2.9237498 4.47546634 2.92916614 1 P 0 ;0,1=8,2=0.000000
L 4.47546634 2.92916614 4.47626663 2.93208366 1 P 0 ;0,1=8,2=0.000000
L 4.47626663 2.93208366 4.4775997 2.9349997 1 P 0 ;0,1=8,2=0.000000
L 4.4775997 2.9349997 4.47946654 2.93708337 1 P 0 ;0,1=8,2=0.000000
L 4.47946654 2.93708337 4.48133327 2.9375 1 P 0 ;0,1=8,2=0.000000
L 4.48133327 2.9375 4.4832 2.93666683 1 P 0 ;0,1=8,2=0.000000
L 4.4832 2.93666683 4.48453356 2.93458317 1 P 0 ;0,1=8,2=0.000000
L 4.24446654 2.9445 4.2449997 2.94991624 1 P 0 ;0,1=138,2=0.000000
L 4.2449997 2.94991624 4.2458 2.95449931 1 P 0 ;0,1=138,2=0.000000
L 4.2458 2.95449931 4.24686644 2.95866663 1 P 0 ;0,1=138,2=0.000000
L 4.24686644 2.95866663 4.2482 2.9632498 1 P 0 ;0,1=138,2=0.000000
L 4.2482 2.9632498 4.25033337 2.9695 1 P 0 ;0,1=138,2=0.000000
L 4.25033337 2.9695 4.23966654 2.9695 1 P 0 ;0,1=138,2=0.000000
L 4.30056663 2.9905 4.30056663 2.96828327 1 P 0 ;0,1=139,2=0.000000
L 4.30056663 2.96828327 4.3020997 2.96363238 1 P 0 ;0,1=139,2=0.000000
L 4.3020997 2.96363238 4.30516634 2.96053307 1 P 0 ;0,1=139,2=0.000000
L 4.30516634 2.96053307 4.30899961 2.9595 1 P 0 ;0,1=139,2=0.000000
L 4.30899961 2.9595 4.31283356 2.96053307 1 P 0 ;0,1=139,2=0.000000
L 4.31283356 2.96053307 4.3159002 2.96363238 1 P 0 ;0,1=139,2=0.000000
L 4.3159002 2.96363238 4.31743327 2.96828327 1 P 0 ;0,1=139,2=0.000000
L 4.31743327 2.96828327 4.31743327 2.9905 1 P 0 ;0,1=139,2=0.000000
L 4.33271644 2.98533346 4.33501663 2.98843278 1 P 0 ;0,1=139,2=0.000000
L 4.33501663 2.98843278 4.3377001 2.98998337 1 P 0 ;0,1=139,2=0.000000
L 4.3377001 2.98998337 4.34076683 2.9905 1 P 0 ;0,1=139,2=0.000000
L 4.34076683 2.9905 4.3446 2.98946683 1 P 0 ;0,1=139,2=0.000000
L 4.3446 2.98946683 4.34728346 2.98688307 1 P 0 ;0,1=139,2=0.000000
L 4.34728346 2.98688307 4.34805 2.98378376 1 P 0 ;0,1=139,2=0.000000
L 4.34805 2.98378376 4.34766673 2.98068258 1 P 0 ;0,1=139,2=0.000000
L 4.34766673 2.98068258 4.34613307 2.9780998 1 P 0 ;0,1=139,2=0.000000
L 4.34613307 2.9780998 4.33846663 2.97293327 1 P 0 ;0,1=139,2=0.000000
L 4.33846663 2.97293327 4.33501663 2.96931644 1 P 0 ;0,1=139,2=0.000000
L 4.33501663 2.96931644 4.33271644 2.96414892 1 P 0 ;0,1=139,2=0.000000
L 4.33271644 2.96414892 4.3319499 2.9595 1 P 0 ;0,1=139,2=0.000000
L 4.3319499 2.9595 4.34805 2.9595 1 P 0 ;0,1=139,2=0.000000
L 4.36371644 2.98533346 4.36601663 2.98843278 1 P 0 ;0,1=139,2=0.000000
L 4.36601663 2.98843278 4.3687001 2.98998337 1 P 0 ;0,1=139,2=0.000000
L 4.3687001 2.98998337 4.37176683 2.9905 1 P 0 ;0,1=139,2=0.000000
L 4.37176683 2.9905 4.3756 2.98946683 1 P 0 ;0,1=139,2=0.000000
L 4.3756 2.98946683 4.37828346 2.98688307 1 P 0 ;0,1=139,2=0.000000
L 4.37828346 2.98688307 4.37905 2.98378376 1 P 0 ;0,1=139,2=0.000000
L 4.37905 2.98378376 4.37866673 2.98068258 1 P 0 ;0,1=139,2=0.000000
L 4.37866673 2.98068258 4.37713307 2.9780998 1 P 0 ;0,1=139,2=0.000000
L 4.37713307 2.9780998 4.36946663 2.97293327 1 P 0 ;0,1=139,2=0.000000
L 4.36946663 2.97293327 4.36601663 2.96931644 1 P 0 ;0,1=139,2=0.000000
L 4.36601663 2.96931644 4.36371644 2.96414892 1 P 0 ;0,1=139,2=0.000000
L 4.36371644 2.96414892 4.3629499 2.9595 1 P 0 ;0,1=139,2=0.000000
L 4.3629499 2.9595 4.37905 2.9595 1 P 0 ;0,1=139,2=0.000000
L 4.2539997 2.7725 4.2539997 2.7975 1 P 0 ;0,1=6,2=0.000000
L 4.2539997 2.7975 4.2507999 2.7925003 1 P 0 ;0,1=6,2=0.000000
L 4.2507999 2.7725 4.25719951 2.7725 1 P 0 ;0,1=6,2=0.000000
L 4.27093317 2.79333337 4.27253327 2.79583287 1 P 0 ;0,1=6,2=0.000000
L 4.27253327 2.79583287 4.2744 2.79708337 1 P 0 ;0,1=6,2=0.000000
L 4.2744 2.79708337 4.27653337 2.7975 1 P 0 ;0,1=6,2=0.000000
L 4.27653337 2.7975 4.2792 2.79666683 1 P 0 ;0,1=6,2=0.000000
L 4.2792 2.79666683 4.28106673 2.79458317 1 P 0 ;0,1=6,2=0.000000
L 4.28106673 2.79458317 4.2816 2.79208366 1 P 0 ;0,1=6,2=0.000000
L 4.2816 2.79208366 4.28133337 2.78958268 1 P 0 ;0,1=6,2=0.000000
L 4.28133337 2.78958268 4.28026644 2.7874998 1 P 0 ;0,1=6,2=0.000000
L 4.28026644 2.7874998 4.27493327 2.78333327 1 P 0 ;0,1=6,2=0.000000
L 4.27493327 2.78333327 4.27253327 2.78041644 1 P 0 ;0,1=6,2=0.000000
L 4.27253327 2.78041644 4.27093317 2.77624911 1 P 0 ;0,1=6,2=0.000000
L 4.27093317 2.77624911 4.2703999 2.7725 1 P 0 ;0,1=6,2=0.000000
L 4.2703999 2.7725 4.2816 2.7725 1 P 0 ;0,1=6,2=0.000000
L 4.2736 3.8624 4.2736 4.1216 1 P 0 
L 4.2736 4.1216 4.0144 4.1216 1 P 0 
L 4.0144 4.1216 4.0144 3.8624 1 P 0 
L 4.0144 3.8624 4.2736 3.8624 1 P 0 
S P 0
OB 4.327430019685 3.93293996063 I
OC 4.327430019685 3.93293996063 4.30742519685 3.93294488189 Y
OE
SE
L 4.2049997 4.1375 4.20686644 4.13791654 1 P 0 ;0,1=16,2=0.000000
L 4.20686644 4.13791654 4.2089998 4.13916624 1 P 0 ;0,1=16,2=0.000000
L 4.2089998 4.13916624 4.21033337 4.14124911 1 P 0 ;0,1=16,2=0.000000
L 4.21033337 4.14124911 4.21086663 4.14416673 1 P 0 ;0,1=16,2=0.000000
L 4.21086663 4.14416673 4.21033337 4.14708278 1 P 0 ;0,1=16,2=0.000000
L 4.21033337 4.14708278 4.20873327 4.14958297 1 P 0 ;0,1=16,2=0.000000
L 4.20873327 4.14958297 4.20633327 4.15083346 1 P 0 ;0,1=16,2=0.000000
L 4.20633327 4.15083346 4.20366663 4.15083346 1 P 0 ;0,1=16,2=0.000000
L 4.20366663 4.15083346 4.20206654 4.15166663 1 P 0 ;0,1=16,2=0.000000
L 4.20206654 4.15166663 4.20073297 4.15374951 1 P 0 ;0,1=16,2=0.000000
L 4.20073297 4.15374951 4.2001998 4.15666634 1 P 0 ;0,1=16,2=0.000000
L 4.2001998 4.15666634 4.2010001 4.15958317 1 P 0 ;0,1=16,2=0.000000
L 4.2010001 4.15958317 4.20286634 4.16166683 1 P 0 ;0,1=16,2=0.000000
L 4.20286634 4.16166683 4.2049997 4.1625 1 P 0 ;0,1=16,2=0.000000
L 4.2049997 4.1625 4.20713307 4.16166683 1 P 0 ;0,1=16,2=0.000000
L 4.20713307 4.16166683 4.2089998 4.15958317 1 P 0 ;0,1=16,2=0.000000
L 4.2089998 4.15958317 4.2098001 4.15666634 1 P 0 ;0,1=16,2=0.000000
L 4.2098001 4.15666634 4.20926644 4.15374951 1 P 0 ;0,1=16,2=0.000000
L 4.20926644 4.15374951 4.20793337 4.15166663 1 P 0 ;0,1=16,2=0.000000
L 4.20793337 4.15166663 4.20633327 4.15083346 1 P 0 ;0,1=16,2=0.000000
L 4.20633327 4.15083346 4.20366663 4.15083346 1 P 0 ;0,1=16,2=0.000000
L 4.20366663 4.15083346 4.20126663 4.14958297 1 P 0 ;0,1=16,2=0.000000
L 4.20126663 4.14958297 4.19966654 4.14708278 1 P 0 ;0,1=16,2=0.000000
L 4.19966654 4.14708278 4.19913327 4.14416673 1 P 0 ;0,1=16,2=0.000000
L 4.19913327 4.14416673 4.19966654 4.14124911 1 P 0 ;0,1=16,2=0.000000
L 4.19966654 4.14124911 4.2010001 4.13916624 1 P 0 ;0,1=16,2=0.000000
L 4.2010001 4.13916624 4.20313346 4.13791654 1 P 0 ;0,1=16,2=0.000000
L 4.20313346 4.13791654 4.2049997 4.1375 1 P 0 ;0,1=16,2=0.000000
L 4.29446654 4.0645 4.2949997 4.06991624 1 P 0 ;0,1=138,2=0.000000
L 4.2949997 4.06991624 4.2958 4.07449931 1 P 0 ;0,1=138,2=0.000000
L 4.2958 4.07449931 4.29686644 4.07866663 1 P 0 ;0,1=138,2=0.000000
L 4.29686644 4.07866663 4.2982 4.0832498 1 P 0 ;0,1=138,2=0.000000
L 4.2982 4.0832498 4.30033337 4.0895 1 P 0 ;0,1=138,2=0.000000
L 4.30033337 4.0895 4.28966654 4.0895 1 P 0 ;0,1=138,2=0.000000
L 4.20893317 3.84833337 4.21053327 3.85083287 1 P 0 ;0,1=140,2=0.000000
L 4.21053327 3.85083287 4.2124 3.85208337 1 P 0 ;0,1=140,2=0.000000
L 4.2124 3.85208337 4.21453337 3.8525 1 P 0 ;0,1=140,2=0.000000
L 4.21453337 3.8525 4.2172 3.85166683 1 P 0 ;0,1=140,2=0.000000
L 4.2172 3.85166683 4.21906673 3.84958317 1 P 0 ;0,1=140,2=0.000000
L 4.21906673 3.84958317 4.2196 3.84708366 1 P 0 ;0,1=140,2=0.000000
L 4.2196 3.84708366 4.21933337 3.84458268 1 P 0 ;0,1=140,2=0.000000
L 4.21933337 3.84458268 4.21826644 3.8424998 1 P 0 ;0,1=140,2=0.000000
L 4.21826644 3.8424998 4.21293327 3.83833327 1 P 0 ;0,1=140,2=0.000000
L 4.21293327 3.83833327 4.21053327 3.83541644 1 P 0 ;0,1=140,2=0.000000
L 4.21053327 3.83541644 4.20893317 3.83124911 1 P 0 ;0,1=140,2=0.000000
L 4.20893317 3.83124911 4.2083999 3.8275 1 P 0 ;0,1=140,2=0.000000
L 4.2083999 3.8275 4.2196 3.8275 1 P 0 ;0,1=140,2=0.000000
L 4.2359997 3.8275 4.23786644 3.82791654 1 P 0 ;0,1=140,2=0.000000
L 4.23786644 3.82791654 4.2399998 3.82916624 1 P 0 ;0,1=140,2=0.000000
L 4.2399998 3.82916624 4.24133337 3.83124911 1 P 0 ;0,1=140,2=0.000000
L 4.24133337 3.83124911 4.24186663 3.83416673 1 P 0 ;0,1=140,2=0.000000
L 4.24186663 3.83416673 4.24133337 3.83708278 1 P 0 ;0,1=140,2=0.000000
L 4.24133337 3.83708278 4.23973327 3.83958297 1 P 0 ;0,1=140,2=0.000000
L 4.23973327 3.83958297 4.23733327 3.84083346 1 P 0 ;0,1=140,2=0.000000
L 4.23733327 3.84083346 4.23466663 3.84083346 1 P 0 ;0,1=140,2=0.000000
L 4.23466663 3.84083346 4.23306654 3.84166663 1 P 0 ;0,1=140,2=0.000000
L 4.23306654 3.84166663 4.23173297 3.84374951 1 P 0 ;0,1=140,2=0.000000
L 4.23173297 3.84374951 4.2311998 3.84666634 1 P 0 ;0,1=140,2=0.000000
L 4.2311998 3.84666634 4.2320001 3.84958317 1 P 0 ;0,1=140,2=0.000000
L 4.2320001 3.84958317 4.23386634 3.85166683 1 P 0 ;0,1=140,2=0.000000
L 4.23386634 3.85166683 4.2359997 3.8525 1 P 0 ;0,1=140,2=0.000000
L 4.2359997 3.8525 4.23813307 3.85166683 1 P 0 ;0,1=140,2=0.000000
L 4.23813307 3.85166683 4.2399998 3.84958317 1 P 0 ;0,1=140,2=0.000000
L 4.2399998 3.84958317 4.2408001 3.84666634 1 P 0 ;0,1=140,2=0.000000
L 4.2408001 3.84666634 4.24026644 3.84374951 1 P 0 ;0,1=140,2=0.000000
L 4.24026644 3.84374951 4.23893337 3.84166663 1 P 0 ;0,1=140,2=0.000000
L 4.23893337 3.84166663 4.23733327 3.84083346 1 P 0 ;0,1=140,2=0.000000
L 4.23733327 3.84083346 4.23466663 3.84083346 1 P 0 ;0,1=140,2=0.000000
L 4.23466663 3.84083346 4.23226663 3.83958297 1 P 0 ;0,1=140,2=0.000000
L 4.23226663 3.83958297 4.23066654 3.83708278 1 P 0 ;0,1=140,2=0.000000
L 4.23066654 3.83708278 4.23013327 3.83416673 1 P 0 ;0,1=140,2=0.000000
L 4.23013327 3.83416673 4.23066654 3.83124911 1 P 0 ;0,1=140,2=0.000000
L 4.23066654 3.83124911 4.2320001 3.82916624 1 P 0 ;0,1=140,2=0.000000
L 4.2320001 3.82916624 4.23413346 3.82791654 1 P 0 ;0,1=140,2=0.000000
L 4.23413346 3.82791654 4.2359997 3.8275 1 P 0 ;0,1=140,2=0.000000
L 4.0539997 4.1425 4.0539997 4.1675 1 P 0 ;0,1=141,2=0.000000
L 4.0539997 4.1675 4.0507999 4.1625003 1 P 0 ;0,1=141,2=0.000000
L 4.0507999 4.1425 4.05719951 4.1425 1 P 0 ;0,1=141,2=0.000000
L 4.0792 4.1425 4.0792 4.1675 1 P 0 ;0,1=141,2=0.000000
L 4.0792 4.1675 4.06933297 4.14958327 1 P 0 ;0,1=141,2=0.000000
L 4.06933297 4.14958327 4.08266693 4.14958327 1 P 0 ;0,1=141,2=0.000000
L 4.16556663 4.2105 4.16556663 4.18828327 1 P 0 ;0,1=142,2=0.000000
L 4.16556663 4.18828327 4.1670997 4.18363238 1 P 0 ;0,1=142,2=0.000000
L 4.1670997 4.18363238 4.17016634 4.18053307 1 P 0 ;0,1=142,2=0.000000
L 4.17016634 4.18053307 4.17399961 4.1795 1 P 0 ;0,1=142,2=0.000000
L 4.17399961 4.1795 4.17783356 4.18053307 1 P 0 ;0,1=142,2=0.000000
L 4.17783356 4.18053307 4.1809002 4.18363238 1 P 0 ;0,1=142,2=0.000000
L 4.1809002 4.18363238 4.18243327 4.18828327 1 P 0 ;0,1=142,2=0.000000
L 4.18243327 4.18828327 4.18243327 4.2105 1 P 0 ;0,1=142,2=0.000000
L 4.19656663 4.18569961 4.19886614 4.18208278 1 P 0 ;0,1=142,2=0.000000
L 4.19886614 4.18208278 4.20193287 4.18001654 1 P 0 ;0,1=142,2=0.000000
L 4.20193287 4.18001654 4.20538356 4.1795 1 P 0 ;0,1=142,2=0.000000
L 4.20538356 4.1795 4.2084503 4.18001654 1 P 0 ;0,1=142,2=0.000000
L 4.2084503 4.18001654 4.21151703 4.18259931 1 P 0 ;0,1=142,2=0.000000
L 4.21151703 4.18259931 4.21343327 4.18569961 1 P 0 ;0,1=142,2=0.000000
L 4.21343327 4.18569961 4.21381654 4.1887999 1 P 0 ;0,1=142,2=0.000000
L 4.21381654 4.1887999 4.21305 4.19241575 1 P 0 ;0,1=142,2=0.000000
L 4.21305 4.19241575 4.21036654 4.19499951 1 P 0 ;0,1=142,2=0.000000
L 4.21036654 4.19499951 4.20768307 4.19603356 1 P 0 ;0,1=142,2=0.000000
L 4.20768307 4.19603356 4.20423307 4.19603356 1 P 0 ;0,1=142,2=0.000000
L 4.20768307 4.19603356 4.20998327 4.19758317 1 P 0 ;0,1=142,2=0.000000
L 4.20998327 4.19758317 4.2119002 4.20016594 1 P 0 ;0,1=142,2=0.000000
L 4.2119002 4.20016594 4.21266673 4.20326624 1 P 0 ;0,1=142,2=0.000000
L 4.21266673 4.20326624 4.2119002 4.20636654 1 P 0 ;0,1=142,2=0.000000
L 4.2119002 4.20636654 4.20998327 4.20894931 1 P 0 ;0,1=142,2=0.000000
L 4.20998327 4.20894931 4.20653327 4.2105 1 P 0 ;0,1=142,2=0.000000
L 4.20653327 4.2105 4.20308337 4.20998337 1 P 0 ;0,1=142,2=0.000000
L 4.20308337 4.20998337 4.19963337 4.20791624 1 P 0 ;0,1=142,2=0.000000
L 4.22756663 4.18569961 4.22986614 4.18208278 1 P 0 ;0,1=142,2=0.000000
L 4.22986614 4.18208278 4.23293287 4.18001654 1 P 0 ;0,1=142,2=0.000000
L 4.23293287 4.18001654 4.23638356 4.1795 1 P 0 ;0,1=142,2=0.000000
L 4.23638356 4.1795 4.2394503 4.18001654 1 P 0 ;0,1=142,2=0.000000
L 4.2394503 4.18001654 4.24251703 4.18259931 1 P 0 ;0,1=142,2=0.000000
L 4.24251703 4.18259931 4.24443327 4.18569961 1 P 0 ;0,1=142,2=0.000000
L 4.24443327 4.18569961 4.24481654 4.1887999 1 P 0 ;0,1=142,2=0.000000
L 4.24481654 4.1887999 4.24405 4.19241575 1 P 0 ;0,1=142,2=0.000000
L 4.24405 4.19241575 4.24136654 4.19499951 1 P 0 ;0,1=142,2=0.000000
L 4.24136654 4.19499951 4.23868307 4.19603356 1 P 0 ;0,1=142,2=0.000000
L 4.23868307 4.19603356 4.23523307 4.19603356 1 P 0 ;0,1=142,2=0.000000
L 4.23868307 4.19603356 4.24098327 4.19758317 1 P 0 ;0,1=142,2=0.000000
L 4.24098327 4.19758317 4.2429002 4.20016594 1 P 0 ;0,1=142,2=0.000000
L 4.2429002 4.20016594 4.24366673 4.20326624 1 P 0 ;0,1=142,2=0.000000
L 4.24366673 4.20326624 4.2429002 4.20636654 1 P 0 ;0,1=142,2=0.000000
L 4.2429002 4.20636654 4.24098327 4.20894931 1 P 0 ;0,1=142,2=0.000000
L 4.24098327 4.20894931 4.23753327 4.2105 1 P 0 ;0,1=142,2=0.000000
L 4.23753327 4.2105 4.23408337 4.20998337 1 P 0 ;0,1=142,2=0.000000
L 4.23408337 4.20998337 4.23063337 4.20791624 1 P 0 ;0,1=142,2=0.000000
L 4.06393317 3.85333337 4.06553327 3.85583287 1 P 0 ;0,1=143,2=0.000000
L 4.06553327 3.85583287 4.0674 3.85708337 1 P 0 ;0,1=143,2=0.000000
L 4.0674 3.85708337 4.06953337 3.8575 1 P 0 ;0,1=143,2=0.000000
L 4.06953337 3.8575 4.0722 3.85666683 1 P 0 ;0,1=143,2=0.000000
L 4.0722 3.85666683 4.07406673 3.85458317 1 P 0 ;0,1=143,2=0.000000
L 4.07406673 3.85458317 4.0746 3.85208366 1 P 0 ;0,1=143,2=0.000000
L 4.0746 3.85208366 4.07433337 3.84958268 1 P 0 ;0,1=143,2=0.000000
L 4.07433337 3.84958268 4.07326644 3.8474998 1 P 0 ;0,1=143,2=0.000000
L 4.07326644 3.8474998 4.06793327 3.84333327 1 P 0 ;0,1=143,2=0.000000
L 4.06793327 3.84333327 4.06553327 3.84041644 1 P 0 ;0,1=143,2=0.000000
L 4.06553327 3.84041644 4.06393317 3.83624911 1 P 0 ;0,1=143,2=0.000000
L 4.06393317 3.83624911 4.0633999 3.8325 1 P 0 ;0,1=143,2=0.000000
L 4.0633999 3.8325 4.0746 3.8325 1 P 0 ;0,1=143,2=0.000000
L 4.08593317 3.85333337 4.08753327 3.85583287 1 P 0 ;0,1=143,2=0.000000
L 4.08753327 3.85583287 4.0894 3.85708337 1 P 0 ;0,1=143,2=0.000000
L 4.0894 3.85708337 4.09153337 3.8575 1 P 0 ;0,1=143,2=0.000000
L 4.09153337 3.8575 4.0942 3.85666683 1 P 0 ;0,1=143,2=0.000000
L 4.0942 3.85666683 4.09606673 3.85458317 1 P 0 ;0,1=143,2=0.000000
L 4.09606673 3.85458317 4.0966 3.85208366 1 P 0 ;0,1=143,2=0.000000
L 4.0966 3.85208366 4.09633337 3.84958268 1 P 0 ;0,1=143,2=0.000000
L 4.09633337 3.84958268 4.09526644 3.8474998 1 P 0 ;0,1=143,2=0.000000
L 4.09526644 3.8474998 4.08993327 3.84333327 1 P 0 ;0,1=143,2=0.000000
L 4.08993327 3.84333327 4.08753327 3.84041644 1 P 0 ;0,1=143,2=0.000000
L 4.08753327 3.84041644 4.08593317 3.83624911 1 P 0 ;0,1=143,2=0.000000
L 4.08593317 3.83624911 4.0853999 3.8325 1 P 0 ;0,1=143,2=0.000000
L 4.0853999 3.8325 4.0966 3.8325 1 P 0 ;0,1=143,2=0.000000
L 3.9689997 4.0375 3.9689997 4.0625 1 P 0 ;0,1=144,2=0.000000
L 3.9689997 4.0625 3.9657999 4.0575003 1 P 0 ;0,1=144,2=0.000000
L 3.9657999 4.0375 3.97219951 4.0375 1 P 0 ;0,1=144,2=0.000000
L 3.98513327 4.04124911 3.98673297 4.03916624 1 P 0 ;0,1=144,2=0.000000
L 3.98673297 4.03916624 3.9885997 4.03791654 1 P 0 ;0,1=144,2=0.000000
L 3.9885997 4.03791654 3.9909997 4.0375 1 P 0 ;0,1=144,2=0.000000
L 3.9909997 4.0375 3.9934002 4.03833307 1 P 0 ;0,1=144,2=0.000000
L 3.9934002 4.03833307 3.99526644 4.03999941 1 P 0 ;0,1=144,2=0.000000
L 3.99526644 4.03999941 3.9966 4.04291624 1 P 0 ;0,1=144,2=0.000000
L 3.9966 4.04291624 3.99686663 4.04624961 1 P 0 ;0,1=144,2=0.000000
L 3.99686663 4.04624961 3.99633337 4.04958297 1 P 0 ;0,1=144,2=0.000000
L 3.99633337 4.04958297 3.9949998 4.05166663 1 P 0 ;0,1=144,2=0.000000
L 3.9949998 4.05166663 3.99313307 4.05333297 1 P 0 ;0,1=144,2=0.000000
L 3.99313307 4.05333297 3.99126683 4.05374951 1 P 0 ;0,1=144,2=0.000000
L 3.99126683 4.05374951 3.9894 4.05333297 1 P 0 ;0,1=144,2=0.000000
L 3.9894 4.05333297 3.9870001 4.05166663 1 P 0 ;0,1=144,2=0.000000
L 3.9870001 4.05166663 3.9877999 4.0625 1 P 0 ;0,1=144,2=0.000000
L 3.9877999 4.0625 3.9949998 4.0625 1 P 0 ;0,1=144,2=0.000000
L 3.96893317 3.94833337 3.97053327 3.95083287 1 P 0 ;0,1=145,2=0.000000
L 3.97053327 3.95083287 3.9724 3.95208337 1 P 0 ;0,1=145,2=0.000000
L 3.9724 3.95208337 3.97453337 3.9525 1 P 0 ;0,1=145,2=0.000000
L 3.97453337 3.9525 3.9772 3.95166683 1 P 0 ;0,1=145,2=0.000000
L 3.9772 3.95166683 3.97906673 3.94958317 1 P 0 ;0,1=145,2=0.000000
L 3.97906673 3.94958317 3.9796 3.94708366 1 P 0 ;0,1=145,2=0.000000
L 3.9796 3.94708366 3.97933337 3.94458268 1 P 0 ;0,1=145,2=0.000000
L 3.97933337 3.94458268 3.97826644 3.9424998 1 P 0 ;0,1=145,2=0.000000
L 3.97826644 3.9424998 3.97293327 3.93833327 1 P 0 ;0,1=145,2=0.000000
L 3.97293327 3.93833327 3.97053327 3.93541644 1 P 0 ;0,1=145,2=0.000000
L 3.97053327 3.93541644 3.96893317 3.93124911 1 P 0 ;0,1=145,2=0.000000
L 3.96893317 3.93124911 3.9683999 3.9275 1 P 0 ;0,1=145,2=0.000000
L 3.9683999 3.9275 3.9796 3.9275 1 P 0 ;0,1=145,2=0.000000
L 3.9959997 3.9275 3.9959997 3.9525 1 P 0 ;0,1=145,2=0.000000
L 3.9959997 3.9525 3.9927999 3.9475003 1 P 0 ;0,1=145,2=0.000000
L 3.9927999 3.9275 3.99919951 3.9275 1 P 0 ;0,1=145,2=0.000000
L 2.76903297 1.2495 2.76903297 1.2805 1 P 0 ;0,1=146,2=0.000000
L 2.76903297 1.2805 2.77899961 1.25466644 1 P 0 ;0,1=146,2=0.000000
L 2.77899961 1.25466644 2.78896693 1.2805 1 P 0 ;0,1=146,2=0.000000
L 2.78896693 1.2805 2.78896693 1.2495 1 P 0 ;0,1=146,2=0.000000
L 2.81766673 1.2495 2.80233317 1.2495 1 P 0 ;0,1=146,2=0.000000
L 2.80233317 1.2495 2.80233317 1.2805 1 P 0 ;0,1=146,2=0.000000
L 2.80233317 1.2805 2.81766673 1.2805 1 P 0 ;0,1=146,2=0.000000
L 2.81153327 1.26551703 2.80233317 1.26551703 1 P 0 ;0,1=146,2=0.000000
L 2.84099961 1.2495 2.84368307 1.25001654 1 P 0 ;0,1=146,2=0.000000
L 2.84368307 1.25001654 2.8467498 1.25156614 1 P 0 ;0,1=146,2=0.000000
L 2.8467498 1.25156614 2.84866673 1.25414892 1 P 0 ;0,1=146,2=0.000000
L 2.84866673 1.25414892 2.84943327 1.25776673 1 P 0 ;0,1=146,2=0.000000
L 2.84943327 1.25776673 2.84866673 1.26138268 1 P 0 ;0,1=146,2=0.000000
L 2.84866673 1.26138268 2.84636654 1.26448287 1 P 0 ;0,1=146,2=0.000000
L 2.84636654 1.26448287 2.84291654 1.26603356 1 P 0 ;0,1=146,2=0.000000
L 2.84291654 1.26603356 2.83908337 1.26603356 1 P 0 ;0,1=146,2=0.000000
L 2.83908337 1.26603356 2.83678317 1.26706663 1 P 0 ;0,1=146,2=0.000000
L 2.83678317 1.26706663 2.83486614 1.26964941 1 P 0 ;0,1=146,2=0.000000
L 2.83486614 1.26964941 2.8340997 1.27326624 1 P 0 ;0,1=146,2=0.000000
L 2.8340997 1.27326624 2.8352501 1.27688307 1 P 0 ;0,1=146,2=0.000000
L 2.8352501 1.27688307 2.83793287 1.27946683 1 P 0 ;0,1=146,2=0.000000
L 2.83793287 1.27946683 2.84099961 1.2805 1 P 0 ;0,1=146,2=0.000000
L 2.84099961 1.2805 2.84406634 1.27946683 1 P 0 ;0,1=146,2=0.000000
L 2.84406634 1.27946683 2.8467498 1.27688307 1 P 0 ;0,1=146,2=0.000000
L 2.8467498 1.27688307 2.8479002 1.27326624 1 P 0 ;0,1=146,2=0.000000
L 2.8479002 1.27326624 2.84713307 1.26964941 1 P 0 ;0,1=146,2=0.000000
L 2.84713307 1.26964941 2.84521673 1.26706663 1 P 0 ;0,1=146,2=0.000000
L 2.84521673 1.26706663 2.84291654 1.26603356 1 P 0 ;0,1=146,2=0.000000
L 2.84291654 1.26603356 2.83908337 1.26603356 1 P 0 ;0,1=146,2=0.000000
L 2.83908337 1.26603356 2.83563337 1.26448287 1 P 0 ;0,1=146,2=0.000000
L 2.83563337 1.26448287 2.83333317 1.26138268 1 P 0 ;0,1=146,2=0.000000
L 2.83333317 1.26138268 2.83256663 1.25776673 1 P 0 ;0,1=146,2=0.000000
L 2.83256663 1.25776673 2.83333317 1.25414892 1 P 0 ;0,1=146,2=0.000000
L 2.83333317 1.25414892 2.8352501 1.25156614 1 P 0 ;0,1=146,2=0.000000
L 2.8352501 1.25156614 2.83831683 1.25001654 1 P 0 ;0,1=146,2=0.000000
L 2.83831683 1.25001654 2.84099961 1.2495 1 P 0 ;0,1=146,2=0.000000
L 2.46973297 2.4639 2.46973297 2.4949 1 P 0 ;0,1=147,2=0.000000
L 2.46973297 2.4949 2.47969961 2.46906644 1 P 0 ;0,1=147,2=0.000000
L 2.47969961 2.46906644 2.48966693 2.4949 1 P 0 ;0,1=147,2=0.000000
L 2.48966693 2.4949 2.48966693 2.4639 1 P 0 ;0,1=147,2=0.000000
L 2.51836673 2.4639 2.50303317 2.4639 1 P 0 ;0,1=147,2=0.000000
L 2.50303317 2.4639 2.50303317 2.4949 1 P 0 ;0,1=147,2=0.000000
L 2.50303317 2.4949 2.51836673 2.4949 1 P 0 ;0,1=147,2=0.000000
L 2.51223327 2.47991703 2.50303317 2.47991703 1 P 0 ;0,1=147,2=0.000000
L 2.53441644 2.47681575 2.5370999 2.48043356 1 P 0 ;0,1=147,2=0.000000
L 2.5370999 2.48043356 2.5394001 2.4824998 1 P 0 ;0,1=147,2=0.000000
L 2.5394001 2.4824998 2.54246683 2.48353287 1 P 0 ;0,1=147,2=0.000000
L 2.54246683 2.48353287 2.5451503 2.4824998 1 P 0 ;0,1=147,2=0.000000
L 2.5451503 2.4824998 2.54706654 2.48043356 1 P 0 ;0,1=147,2=0.000000
L 2.54706654 2.48043356 2.5486002 2.47733327 1 P 0 ;0,1=147,2=0.000000
L 2.5486002 2.47733327 2.54898346 2.47371644 1 P 0 ;0,1=147,2=0.000000
L 2.54898346 2.47371644 2.5486002 2.47061614 1 P 0 ;0,1=147,2=0.000000
L 2.5486002 2.47061614 2.54706654 2.46751585 1 P 0 ;0,1=147,2=0.000000
L 2.54706654 2.46751585 2.54476634 2.46493307 1 P 0 ;0,1=147,2=0.000000
L 2.54476634 2.46493307 2.54208356 2.4639 1 P 0 ;0,1=147,2=0.000000
L 2.54208356 2.4639 2.53901683 2.46493307 1 P 0 ;0,1=147,2=0.000000
L 2.53901683 2.46493307 2.53633337 2.46803238 1 P 0 ;0,1=147,2=0.000000
L 2.53633337 2.46803238 2.5347997 2.47268327 1 P 0 ;0,1=147,2=0.000000
L 2.5347997 2.47268327 2.53441644 2.4778498 1 P 0 ;0,1=147,2=0.000000
L 2.53441644 2.4778498 2.53518287 2.48456594 1 P 0 ;0,1=147,2=0.000000
L 2.53518287 2.48456594 2.53633337 2.48818376 1 P 0 ;0,1=147,2=0.000000
L 2.53633337 2.48818376 2.53824961 2.4917997 1 P 0 ;0,1=147,2=0.000000
L 2.53824961 2.4917997 2.54093307 2.49438337 1 P 0 ;0,1=147,2=0.000000
L 2.54093307 2.49438337 2.54361654 2.4949 1 P 0 ;0,1=147,2=0.000000
L 2.54361654 2.4949 2.5463 2.49386683 1 P 0 ;0,1=147,2=0.000000
L 2.5463 2.49386683 2.54821703 2.49128307 1 P 0 ;0,1=147,2=0.000000
L 1.34903297 2.8295 1.34903297 2.8605 1 P 0 ;0,1=148,2=0.000000
L 1.34903297 2.8605 1.35899961 2.83466644 1 P 0 ;0,1=148,2=0.000000
L 1.35899961 2.83466644 1.36896693 2.8605 1 P 0 ;0,1=148,2=0.000000
L 1.36896693 2.8605 1.36896693 2.8295 1 P 0 ;0,1=148,2=0.000000
L 1.39766673 2.8295 1.38233317 2.8295 1 P 0 ;0,1=148,2=0.000000
L 1.38233317 2.8295 1.38233317 2.8605 1 P 0 ;0,1=148,2=0.000000
L 1.38233317 2.8605 1.39766673 2.8605 1 P 0 ;0,1=148,2=0.000000
L 1.39153327 2.84551703 1.38233317 2.84551703 1 P 0 ;0,1=148,2=0.000000
L 1.41256663 2.83414892 1.41486614 2.83156614 1 P 0 ;0,1=148,2=0.000000
L 1.41486614 2.83156614 1.41754961 2.83001654 1 P 0 ;0,1=148,2=0.000000
L 1.41754961 2.83001654 1.42099961 2.8295 1 P 0 ;0,1=148,2=0.000000
L 1.42099961 2.8295 1.4244503 2.83053307 1 P 0 ;0,1=148,2=0.000000
L 1.4244503 2.83053307 1.42713307 2.83259931 1 P 0 ;0,1=148,2=0.000000
L 1.42713307 2.83259931 1.42905 2.83621614 1 P 0 ;0,1=148,2=0.000000
L 1.42905 2.83621614 1.42943327 2.84034951 1 P 0 ;0,1=148,2=0.000000
L 1.42943327 2.84034951 1.42866673 2.84448287 1 P 0 ;0,1=148,2=0.000000
L 1.42866673 2.84448287 1.4267498 2.84706663 1 P 0 ;0,1=148,2=0.000000
L 1.4267498 2.84706663 1.42406634 2.84913287 1 P 0 ;0,1=148,2=0.000000
L 1.42406634 2.84913287 1.42138356 2.84964941 1 P 0 ;0,1=148,2=0.000000
L 1.42138356 2.84964941 1.4187001 2.84913287 1 P 0 ;0,1=148,2=0.000000
L 1.4187001 2.84913287 1.4152501 2.84706663 1 P 0 ;0,1=148,2=0.000000
L 1.4152501 2.84706663 1.4163999 2.8605 1 P 0 ;0,1=148,2=0.000000
L 1.4163999 2.8605 1.4267498 2.8605 1 P 0 ;0,1=148,2=0.000000
L 1.37903297 1.2205 1.37903297 1.2515 1 P 0 ;0,1=149,2=0.000000
L 1.37903297 1.2515 1.38899961 1.22566644 1 P 0 ;0,1=149,2=0.000000
L 1.38899961 1.22566644 1.39896693 1.2515 1 P 0 ;0,1=149,2=0.000000
L 1.39896693 1.2515 1.39896693 1.2205 1 P 0 ;0,1=149,2=0.000000
L 1.42766673 1.2205 1.41233317 1.2205 1 P 0 ;0,1=149,2=0.000000
L 1.41233317 1.2205 1.41233317 1.2515 1 P 0 ;0,1=149,2=0.000000
L 1.41233317 1.2515 1.42766673 1.2515 1 P 0 ;0,1=149,2=0.000000
L 1.42153327 1.23651703 1.41233317 1.23651703 1 P 0 ;0,1=149,2=0.000000
L 1.45023307 1.2205 1.45099961 1.22721614 1 P 0 ;0,1=149,2=0.000000
L 1.45099961 1.22721614 1.4521501 1.23289921 1 P 0 ;0,1=149,2=0.000000
L 1.4521501 1.23289921 1.45368307 1.23806663 1 P 0 ;0,1=149,2=0.000000
L 1.45368307 1.23806663 1.4556 1.2437497 1 P 0 ;0,1=149,2=0.000000
L 1.4556 1.2437497 1.45866673 1.2515 1 P 0 ;0,1=149,2=0.000000
L 1.45866673 1.2515 1.44333317 1.2515 1 P 0 ;0,1=149,2=0.000000
L 0.59858002 2.52073996 0.59858002 2.32966004 1 P 0 
L 0.4959 2.52073996 0.59858002 2.52073996 1 P 0 
L 0.59858002 2.32966004 0.4959 2.32966004 1 P 0 
L 0.4959 2.32966004 0.4959 2.52073996 1 P 0 
S P 0
OB 0.604930019685 2.55175 I
OC 0.604930019685 2.55175 0.589930019685 2.55175 Y
OE
SE
L 0.6099997 2.3075 0.61186644 2.30791654 1 P 0 ;0,1=16,2=0.000000
L 0.61186644 2.30791654 0.6139998 2.30916624 1 P 0 ;0,1=16,2=0.000000
L 0.6139998 2.30916624 0.61533337 2.31124911 1 P 0 ;0,1=16,2=0.000000
L 0.61533337 2.31124911 0.61586663 2.31416673 1 P 0 ;0,1=16,2=0.000000
L 0.61586663 2.31416673 0.61533337 2.31708278 1 P 0 ;0,1=16,2=0.000000
L 0.61533337 2.31708278 0.61373327 2.31958297 1 P 0 ;0,1=16,2=0.000000
L 0.61373327 2.31958297 0.61133327 2.32083346 1 P 0 ;0,1=16,2=0.000000
L 0.61133327 2.32083346 0.60866663 2.32083346 1 P 0 ;0,1=16,2=0.000000
L 0.60866663 2.32083346 0.60706654 2.32166663 1 P 0 ;0,1=16,2=0.000000
L 0.60706654 2.32166663 0.60573297 2.32374951 1 P 0 ;0,1=16,2=0.000000
L 0.60573297 2.32374951 0.6051998 2.32666634 1 P 0 ;0,1=16,2=0.000000
L 0.6051998 2.32666634 0.6060001 2.32958317 1 P 0 ;0,1=16,2=0.000000
L 0.6060001 2.32958317 0.60786634 2.33166683 1 P 0 ;0,1=16,2=0.000000
L 0.60786634 2.33166683 0.6099997 2.3325 1 P 0 ;0,1=16,2=0.000000
L 0.6099997 2.3325 0.61213307 2.33166683 1 P 0 ;0,1=16,2=0.000000
L 0.61213307 2.33166683 0.6139998 2.32958317 1 P 0 ;0,1=16,2=0.000000
L 0.6139998 2.32958317 0.6148001 2.32666634 1 P 0 ;0,1=16,2=0.000000
L 0.6148001 2.32666634 0.61426644 2.32374951 1 P 0 ;0,1=16,2=0.000000
L 0.61426644 2.32374951 0.61293337 2.32166663 1 P 0 ;0,1=16,2=0.000000
L 0.61293337 2.32166663 0.61133327 2.32083346 1 P 0 ;0,1=16,2=0.000000
L 0.61133327 2.32083346 0.60866663 2.32083346 1 P 0 ;0,1=16,2=0.000000
L 0.60866663 2.32083346 0.60626663 2.31958297 1 P 0 ;0,1=16,2=0.000000
L 0.60626663 2.31958297 0.60466654 2.31708278 1 P 0 ;0,1=16,2=0.000000
L 0.60466654 2.31708278 0.60413327 2.31416673 1 P 0 ;0,1=16,2=0.000000
L 0.60413327 2.31416673 0.60466654 2.31124911 1 P 0 ;0,1=16,2=0.000000
L 0.60466654 2.31124911 0.6060001 2.30916624 1 P 0 ;0,1=16,2=0.000000
L 0.6060001 2.30916624 0.60813346 2.30791654 1 P 0 ;0,1=16,2=0.000000
L 0.60813346 2.30791654 0.6099997 2.3075 1 P 0 ;0,1=16,2=0.000000
L 0.4345 2.42056663 0.45671673 2.42056663 1 P 0 ;0,1=150,2=270.000000
L 0.45671673 2.42056663 0.46136762 2.4220997 1 P 0 ;0,1=150,2=270.000000
L 0.46136762 2.4220997 0.46446693 2.42516634 1 P 0 ;0,1=150,2=270.000000
L 0.46446693 2.42516634 0.4655 2.42899961 1 P 0 ;0,1=150,2=270.000000
L 0.4655 2.42899961 0.46446693 2.43283356 1 P 0 ;0,1=150,2=270.000000
L 0.46446693 2.43283356 0.46136762 2.4359002 1 P 0 ;0,1=150,2=270.000000
L 0.46136762 2.4359002 0.45671673 2.43743327 1 P 0 ;0,1=150,2=270.000000
L 0.45671673 2.43743327 0.4345 2.43743327 1 P 0 ;0,1=150,2=270.000000
L 0.4655 2.45999961 0.4345 2.45999961 1 P 0 ;0,1=150,2=270.000000
L 0.4345 2.45999961 0.4406997 2.4553999 1 P 0 ;0,1=150,2=270.000000
L 0.4655 2.4553999 0.4655 2.46459931 1 P 0 ;0,1=150,2=270.000000
L 0.46085108 2.48256663 0.46343386 2.48486614 1 P 0 ;0,1=150,2=270.000000
L 0.46343386 2.48486614 0.46498346 2.48754961 1 P 0 ;0,1=150,2=270.000000
L 0.46498346 2.48754961 0.4655 2.49099961 1 P 0 ;0,1=150,2=270.000000
L 0.4655 2.49099961 0.46446693 2.4944503 1 P 0 ;0,1=150,2=270.000000
L 0.46446693 2.4944503 0.46240069 2.49713307 1 P 0 ;0,1=150,2=270.000000
L 0.46240069 2.49713307 0.45878386 2.49905 1 P 0 ;0,1=150,2=270.000000
L 0.45878386 2.49905 0.45465049 2.49943327 1 P 0 ;0,1=150,2=270.000000
L 0.45465049 2.49943327 0.45051713 2.49866673 1 P 0 ;0,1=150,2=270.000000
L 0.45051713 2.49866673 0.44793337 2.4967498 1 P 0 ;0,1=150,2=270.000000
L 0.44793337 2.4967498 0.44586713 2.49406634 1 P 0 ;0,1=150,2=270.000000
L 0.44586713 2.49406634 0.44535059 2.49138356 1 P 0 ;0,1=150,2=270.000000
L 0.44535059 2.49138356 0.44586713 2.4887001 1 P 0 ;0,1=150,2=270.000000
L 0.44586713 2.4887001 0.44793337 2.4852501 1 P 0 ;0,1=150,2=270.000000
L 0.44793337 2.4852501 0.4345 2.4863999 1 P 0 ;0,1=150,2=270.000000
L 0.4345 2.4863999 0.4345 2.4967498 1 P 0 ;0,1=150,2=270.000000
L 0.4832 2.4745 0.4832 2.4995 1 P 0 ;0,1=11,2=0.000000
L 0.4832 2.4995 0.47333297 2.48158327 1 P 0 ;0,1=11,2=0.000000
L 0.47333297 2.48158327 0.48666693 2.48158327 1 P 0 ;0,1=11,2=0.000000
L 0.47913327 2.30824911 0.48073297 2.30616624 1 P 0 ;0,1=20,2=0.000000
L 0.48073297 2.30616624 0.4825997 2.30491654 1 P 0 ;0,1=20,2=0.000000
L 0.4825997 2.30491654 0.4849997 2.3045 1 P 0 ;0,1=20,2=0.000000
L 0.4849997 2.3045 0.4874002 2.30533307 1 P 0 ;0,1=20,2=0.000000
L 0.4874002 2.30533307 0.48926644 2.30699941 1 P 0 ;0,1=20,2=0.000000
L 0.48926644 2.30699941 0.4906 2.30991624 1 P 0 ;0,1=20,2=0.000000
L 0.4906 2.30991624 0.49086663 2.31324961 1 P 0 ;0,1=20,2=0.000000
L 0.49086663 2.31324961 0.49033337 2.31658297 1 P 0 ;0,1=20,2=0.000000
L 0.49033337 2.31658297 0.4889998 2.31866663 1 P 0 ;0,1=20,2=0.000000
L 0.4889998 2.31866663 0.48713307 2.32033297 1 P 0 ;0,1=20,2=0.000000
L 0.48713307 2.32033297 0.48526683 2.32074951 1 P 0 ;0,1=20,2=0.000000
L 0.48526683 2.32074951 0.4834 2.32033297 1 P 0 ;0,1=20,2=0.000000
L 0.4834 2.32033297 0.4810001 2.31866663 1 P 0 ;0,1=20,2=0.000000
L 0.4810001 2.31866663 0.4817999 2.3295 1 P 0 ;0,1=20,2=0.000000
L 0.4817999 2.3295 0.4889998 2.3295 1 P 0 ;0,1=20,2=0.000000
L 0.59858002 1.94986998 0.59858002 1.75878996 1 P 0 
L 0.4959 1.94986998 0.59858002 1.94986998 1 P 0 
L 0.59858002 1.75878996 0.4959 1.75878996 1 P 0 
L 0.4959 1.75878996 0.4959 1.94986998 1 P 0 
S P 0
OB 0.604930019685 1.980880019685 I
OC 0.604930019685 1.980880019685 0.589930019685 1.980880019685 Y
OE
SE
L 0.6149997 1.7675 0.61686644 1.76791654 1 P 0 ;0,1=16,2=0.000000
L 0.61686644 1.76791654 0.6189998 1.76916624 1 P 0 ;0,1=16,2=0.000000
L 0.6189998 1.76916624 0.62033337 1.77124911 1 P 0 ;0,1=16,2=0.000000
L 0.62033337 1.77124911 0.62086663 1.77416673 1 P 0 ;0,1=16,2=0.000000
L 0.62086663 1.77416673 0.62033337 1.77708278 1 P 0 ;0,1=16,2=0.000000
L 0.62033337 1.77708278 0.61873327 1.77958297 1 P 0 ;0,1=16,2=0.000000
L 0.61873327 1.77958297 0.61633327 1.78083346 1 P 0 ;0,1=16,2=0.000000
L 0.61633327 1.78083346 0.61366663 1.78083346 1 P 0 ;0,1=16,2=0.000000
L 0.61366663 1.78083346 0.61206654 1.78166663 1 P 0 ;0,1=16,2=0.000000
L 0.61206654 1.78166663 0.61073297 1.78374951 1 P 0 ;0,1=16,2=0.000000
L 0.61073297 1.78374951 0.6101998 1.78666634 1 P 0 ;0,1=16,2=0.000000
L 0.6101998 1.78666634 0.6110001 1.78958317 1 P 0 ;0,1=16,2=0.000000
L 0.6110001 1.78958317 0.61286634 1.79166683 1 P 0 ;0,1=16,2=0.000000
L 0.61286634 1.79166683 0.6149997 1.7925 1 P 0 ;0,1=16,2=0.000000
L 0.6149997 1.7925 0.61713307 1.79166683 1 P 0 ;0,1=16,2=0.000000
L 0.61713307 1.79166683 0.6189998 1.78958317 1 P 0 ;0,1=16,2=0.000000
L 0.6189998 1.78958317 0.6198001 1.78666634 1 P 0 ;0,1=16,2=0.000000
L 0.6198001 1.78666634 0.61926644 1.78374951 1 P 0 ;0,1=16,2=0.000000
L 0.61926644 1.78374951 0.61793337 1.78166663 1 P 0 ;0,1=16,2=0.000000
L 0.61793337 1.78166663 0.61633327 1.78083346 1 P 0 ;0,1=16,2=0.000000
L 0.61633327 1.78083346 0.61366663 1.78083346 1 P 0 ;0,1=16,2=0.000000
L 0.61366663 1.78083346 0.61126663 1.77958297 1 P 0 ;0,1=16,2=0.000000
L 0.61126663 1.77958297 0.60966654 1.77708278 1 P 0 ;0,1=16,2=0.000000
L 0.60966654 1.77708278 0.60913327 1.77416673 1 P 0 ;0,1=16,2=0.000000
L 0.60913327 1.77416673 0.60966654 1.77124911 1 P 0 ;0,1=16,2=0.000000
L 0.60966654 1.77124911 0.6110001 1.76916624 1 P 0 ;0,1=16,2=0.000000
L 0.6110001 1.76916624 0.61313346 1.76791654 1 P 0 ;0,1=16,2=0.000000
L 0.61313346 1.76791654 0.6149997 1.7675 1 P 0 ;0,1=16,2=0.000000
L 0.4982 1.9595 0.4982 1.9845 1 P 0 ;0,1=11,2=0.000000
L 0.4982 1.9845 0.48833297 1.96658327 1 P 0 ;0,1=11,2=0.000000
L 0.48833297 1.96658327 0.50166693 1.96658327 1 P 0 ;0,1=11,2=0.000000
L 0.4495 1.85056663 0.47171673 1.85056663 1 P 0 ;0,1=151,2=270.000000
L 0.47171673 1.85056663 0.47636762 1.8520997 1 P 0 ;0,1=151,2=270.000000
L 0.47636762 1.8520997 0.47946693 1.85516634 1 P 0 ;0,1=151,2=270.000000
L 0.47946693 1.85516634 0.4805 1.85899961 1 P 0 ;0,1=151,2=270.000000
L 0.4805 1.85899961 0.47946693 1.86283356 1 P 0 ;0,1=151,2=270.000000
L 0.47946693 1.86283356 0.47636762 1.8659002 1 P 0 ;0,1=151,2=270.000000
L 0.47636762 1.8659002 0.47171673 1.86743327 1 P 0 ;0,1=151,2=270.000000
L 0.47171673 1.86743327 0.4495 1.86743327 1 P 0 ;0,1=151,2=270.000000
L 0.4805 1.88999961 0.4495 1.88999961 1 P 0 ;0,1=151,2=270.000000
L 0.4495 1.88999961 0.4556997 1.8853999 1 P 0 ;0,1=151,2=270.000000
L 0.4805 1.8853999 0.4805 1.89459931 1 P 0 ;0,1=151,2=270.000000
L 0.46758425 1.91371644 0.46396644 1.9163999 1 P 0 ;0,1=151,2=270.000000
L 0.46396644 1.9163999 0.4619002 1.9187001 1 P 0 ;0,1=151,2=270.000000
L 0.4619002 1.9187001 0.46086713 1.92176683 1 P 0 ;0,1=151,2=270.000000
L 0.46086713 1.92176683 0.4619002 1.9244503 1 P 0 ;0,1=151,2=270.000000
L 0.4619002 1.9244503 0.46396644 1.92636654 1 P 0 ;0,1=151,2=270.000000
L 0.46396644 1.92636654 0.46706673 1.9279002 1 P 0 ;0,1=151,2=270.000000
L 0.46706673 1.9279002 0.47068356 1.92828346 1 P 0 ;0,1=151,2=270.000000
L 0.47068356 1.92828346 0.47378386 1.9279002 1 P 0 ;0,1=151,2=270.000000
L 0.47378386 1.9279002 0.47688415 1.92636654 1 P 0 ;0,1=151,2=270.000000
L 0.47688415 1.92636654 0.47946693 1.92406634 1 P 0 ;0,1=151,2=270.000000
L 0.47946693 1.92406634 0.4805 1.92138356 1 P 0 ;0,1=151,2=270.000000
L 0.4805 1.92138356 0.47946693 1.91831683 1 P 0 ;0,1=151,2=270.000000
L 0.47946693 1.91831683 0.47636762 1.91563337 1 P 0 ;0,1=151,2=270.000000
L 0.47636762 1.91563337 0.47171673 1.9140997 1 P 0 ;0,1=151,2=270.000000
L 0.47171673 1.9140997 0.4665502 1.91371644 1 P 0 ;0,1=151,2=270.000000
L 0.4665502 1.91371644 0.45983406 1.91448287 1 P 0 ;0,1=151,2=270.000000
L 0.45983406 1.91448287 0.45621624 1.91563337 1 P 0 ;0,1=151,2=270.000000
L 0.45621624 1.91563337 0.4526003 1.91754961 1 P 0 ;0,1=151,2=270.000000
L 0.4526003 1.91754961 0.45001663 1.92023307 1 P 0 ;0,1=151,2=270.000000
L 0.45001663 1.92023307 0.4495 1.92291654 1 P 0 ;0,1=151,2=270.000000
L 0.4495 1.92291654 0.45053317 1.9256 1 P 0 ;0,1=151,2=270.000000
L 0.45053317 1.9256 0.45311693 1.92751703 1 P 0 ;0,1=151,2=270.000000
L 0.47913327 1.73324911 0.48073297 1.73116624 1 P 0 ;0,1=20,2=0.000000
L 0.48073297 1.73116624 0.4825997 1.72991654 1 P 0 ;0,1=20,2=0.000000
L 0.4825997 1.72991654 0.4849997 1.7295 1 P 0 ;0,1=20,2=0.000000
L 0.4849997 1.7295 0.4874002 1.73033307 1 P 0 ;0,1=20,2=0.000000
L 0.4874002 1.73033307 0.48926644 1.73199941 1 P 0 ;0,1=20,2=0.000000
L 0.48926644 1.73199941 0.4906 1.73491624 1 P 0 ;0,1=20,2=0.000000
L 0.4906 1.73491624 0.49086663 1.73824961 1 P 0 ;0,1=20,2=0.000000
L 0.49086663 1.73824961 0.49033337 1.74158297 1 P 0 ;0,1=20,2=0.000000
L 0.49033337 1.74158297 0.4889998 1.74366663 1 P 0 ;0,1=20,2=0.000000
L 0.4889998 1.74366663 0.48713307 1.74533297 1 P 0 ;0,1=20,2=0.000000
L 0.48713307 1.74533297 0.48526683 1.74574951 1 P 0 ;0,1=20,2=0.000000
L 0.48526683 1.74574951 0.4834 1.74533297 1 P 0 ;0,1=20,2=0.000000
L 0.4834 1.74533297 0.4810001 1.74366663 1 P 0 ;0,1=20,2=0.000000
L 0.4810001 1.74366663 0.4817999 1.7545 1 P 0 ;0,1=20,2=0.000000
L 0.4817999 1.7545 0.4889998 1.7545 1 P 0 ;0,1=20,2=0.000000
L 0.59858002 1.379 0.59858002 1.18791998 1 P 0 
L 0.4959 1.379 0.59858002 1.379 1 P 0 
L 0.59858002 1.18791998 0.4959 1.18791998 1 P 0 
L 0.4959 1.18791998 0.4959 1.379 1 P 0 
S P 0
OB 0.604930019685 1.41001003937 I
OC 0.604930019685 1.41001003937 0.589930019685 1.41001003937 Y
OE
SE
L 0.5999997 1.1575 0.60186644 1.15791654 1 P 0 ;0,1=16,2=0.000000
L 0.60186644 1.15791654 0.6039998 1.15916624 1 P 0 ;0,1=16,2=0.000000
L 0.6039998 1.15916624 0.60533337 1.16124911 1 P 0 ;0,1=16,2=0.000000
L 0.60533337 1.16124911 0.60586663 1.16416673 1 P 0 ;0,1=16,2=0.000000
L 0.60586663 1.16416673 0.60533337 1.16708278 1 P 0 ;0,1=16,2=0.000000
L 0.60533337 1.16708278 0.60373327 1.16958297 1 P 0 ;0,1=16,2=0.000000
L 0.60373327 1.16958297 0.60133327 1.17083346 1 P 0 ;0,1=16,2=0.000000
L 0.60133327 1.17083346 0.59866663 1.17083346 1 P 0 ;0,1=16,2=0.000000
L 0.59866663 1.17083346 0.59706654 1.17166663 1 P 0 ;0,1=16,2=0.000000
L 0.59706654 1.17166663 0.59573297 1.17374951 1 P 0 ;0,1=16,2=0.000000
L 0.59573297 1.17374951 0.5951998 1.17666634 1 P 0 ;0,1=16,2=0.000000
L 0.5951998 1.17666634 0.5960001 1.17958317 1 P 0 ;0,1=16,2=0.000000
L 0.5960001 1.17958317 0.59786634 1.18166683 1 P 0 ;0,1=16,2=0.000000
L 0.59786634 1.18166683 0.5999997 1.1825 1 P 0 ;0,1=16,2=0.000000
L 0.5999997 1.1825 0.60213307 1.18166683 1 P 0 ;0,1=16,2=0.000000
L 0.60213307 1.18166683 0.6039998 1.17958317 1 P 0 ;0,1=16,2=0.000000
L 0.6039998 1.17958317 0.6048001 1.17666634 1 P 0 ;0,1=16,2=0.000000
L 0.6048001 1.17666634 0.60426644 1.17374951 1 P 0 ;0,1=16,2=0.000000
L 0.60426644 1.17374951 0.60293337 1.17166663 1 P 0 ;0,1=16,2=0.000000
L 0.60293337 1.17166663 0.60133327 1.17083346 1 P 0 ;0,1=16,2=0.000000
L 0.60133327 1.17083346 0.59866663 1.17083346 1 P 0 ;0,1=16,2=0.000000
L 0.59866663 1.17083346 0.59626663 1.16958297 1 P 0 ;0,1=16,2=0.000000
L 0.59626663 1.16958297 0.59466654 1.16708278 1 P 0 ;0,1=16,2=0.000000
L 0.59466654 1.16708278 0.59413327 1.16416673 1 P 0 ;0,1=16,2=0.000000
L 0.59413327 1.16416673 0.59466654 1.16124911 1 P 0 ;0,1=16,2=0.000000
L 0.59466654 1.16124911 0.5960001 1.15916624 1 P 0 ;0,1=16,2=0.000000
L 0.5960001 1.15916624 0.59813346 1.15791654 1 P 0 ;0,1=16,2=0.000000
L 0.59813346 1.15791654 0.5999997 1.1575 1 P 0 ;0,1=16,2=0.000000
L 0.6345 1.17556663 0.65671673 1.17556663 1 P 0 ;0,1=152,2=270.000000
L 0.65671673 1.17556663 0.66136762 1.1770997 1 P 0 ;0,1=152,2=270.000000
L 0.66136762 1.1770997 0.66446693 1.18016634 1 P 0 ;0,1=152,2=270.000000
L 0.66446693 1.18016634 0.6655 1.18399961 1 P 0 ;0,1=152,2=270.000000
L 0.6655 1.18399961 0.66446693 1.18783356 1 P 0 ;0,1=152,2=270.000000
L 0.66446693 1.18783356 0.66136762 1.1909002 1 P 0 ;0,1=152,2=270.000000
L 0.66136762 1.1909002 0.65671673 1.19243327 1 P 0 ;0,1=152,2=270.000000
L 0.65671673 1.19243327 0.6345 1.19243327 1 P 0 ;0,1=152,2=270.000000
L 0.6655 1.21499961 0.6345 1.21499961 1 P 0 ;0,1=152,2=270.000000
L 0.6345 1.21499961 0.6406997 1.2103999 1 P 0 ;0,1=152,2=270.000000
L 0.6655 1.2103999 0.6655 1.21959931 1 P 0 ;0,1=152,2=270.000000
L 0.65930039 1.23756663 0.66291722 1.23986614 1 P 0 ;0,1=152,2=270.000000
L 0.66291722 1.23986614 0.66498346 1.24293287 1 P 0 ;0,1=152,2=270.000000
L 0.66498346 1.24293287 0.6655 1.24638356 1 P 0 ;0,1=152,2=270.000000
L 0.6655 1.24638356 0.66498346 1.2494503 1 P 0 ;0,1=152,2=270.000000
L 0.66498346 1.2494503 0.66240069 1.25251703 1 P 0 ;0,1=152,2=270.000000
L 0.66240069 1.25251703 0.65930039 1.25443327 1 P 0 ;0,1=152,2=270.000000
L 0.65930039 1.25443327 0.6562001 1.25481654 1 P 0 ;0,1=152,2=270.000000
L 0.6562001 1.25481654 0.65258425 1.25405 1 P 0 ;0,1=152,2=270.000000
L 0.65258425 1.25405 0.65000049 1.25136654 1 P 0 ;0,1=152,2=270.000000
L 0.65000049 1.25136654 0.64896644 1.24868307 1 P 0 ;0,1=152,2=270.000000
L 0.64896644 1.24868307 0.64896644 1.24523307 1 P 0 ;0,1=152,2=270.000000
L 0.64896644 1.24868307 0.64741683 1.25098327 1 P 0 ;0,1=152,2=270.000000
L 0.64741683 1.25098327 0.64483406 1.2529002 1 P 0 ;0,1=152,2=270.000000
L 0.64483406 1.2529002 0.64173376 1.25366673 1 P 0 ;0,1=152,2=270.000000
L 0.64173376 1.25366673 0.63863346 1.2529002 1 P 0 ;0,1=152,2=270.000000
L 0.63863346 1.2529002 0.63605069 1.25098327 1 P 0 ;0,1=152,2=270.000000
L 0.63605069 1.25098327 0.6345 1.24753327 1 P 0 ;0,1=152,2=270.000000
L 0.6345 1.24753327 0.63501663 1.24408337 1 P 0 ;0,1=152,2=270.000000
L 0.63501663 1.24408337 0.63708376 1.24063337 1 P 0 ;0,1=152,2=270.000000
L 0.4782 1.34358996 0.4782 1.36858996 1 P 0 ;0,1=11,2=0.000000
L 0.4782 1.36858996 0.46833297 1.35067323 1 P 0 ;0,1=11,2=0.000000
L 0.46833297 1.35067323 0.48166693 1.35067323 1 P 0 ;0,1=11,2=0.000000
L 0.48413327 1.16124911 0.48573297 1.15916624 1 P 0 ;0,1=20,2=0.000000
L 0.48573297 1.15916624 0.4875997 1.15791654 1 P 0 ;0,1=20,2=0.000000
L 0.4875997 1.15791654 0.4899997 1.1575 1 P 0 ;0,1=20,2=0.000000
L 0.4899997 1.1575 0.4924002 1.15833307 1 P 0 ;0,1=20,2=0.000000
L 0.4924002 1.15833307 0.49426644 1.15999941 1 P 0 ;0,1=20,2=0.000000
L 0.49426644 1.15999941 0.4956 1.16291624 1 P 0 ;0,1=20,2=0.000000
L 0.4956 1.16291624 0.49586663 1.16624961 1 P 0 ;0,1=20,2=0.000000
L 0.49586663 1.16624961 0.49533337 1.16958297 1 P 0 ;0,1=20,2=0.000000
L 0.49533337 1.16958297 0.4939998 1.17166663 1 P 0 ;0,1=20,2=0.000000
L 0.4939998 1.17166663 0.49213307 1.17333297 1 P 0 ;0,1=20,2=0.000000
L 0.49213307 1.17333297 0.49026683 1.17374951 1 P 0 ;0,1=20,2=0.000000
L 0.49026683 1.17374951 0.4884 1.17333297 1 P 0 ;0,1=20,2=0.000000
L 0.4884 1.17333297 0.4860001 1.17166663 1 P 0 ;0,1=20,2=0.000000
L 0.4860001 1.17166663 0.4867999 1.1825 1 P 0 ;0,1=20,2=0.000000
L 0.4867999 1.1825 0.4939998 1.1825 1 P 0 ;0,1=20,2=0.000000
L 0.59858002 0.80813996 0.59858002 0.61706004 1 P 0 
L 0.4959 0.80813996 0.59858002 0.80813996 1 P 0 
L 0.59858002 0.61706004 0.4959 0.61706004 1 P 0 
L 0.4959 0.61706004 0.4959 0.80813996 1 P 0 
S P 0
OB 0.61 0.83 I
OC 0.61 0.83 0.595 0.83 Y
OE
SE
L 0.6249997 0.57828002 0.62686644 0.57869656 1 P 0 ;0,1=16,2=0.000000
L 0.62686644 0.57869656 0.6289998 0.57994626 1 P 0 ;0,1=16,2=0.000000
L 0.6289998 0.57994626 0.63033337 0.58202913 1 P 0 ;0,1=16,2=0.000000
L 0.63033337 0.58202913 0.63086663 0.58494675 1 P 0 ;0,1=16,2=0.000000
L 0.63086663 0.58494675 0.63033337 0.5878628 1 P 0 ;0,1=16,2=0.000000
L 0.63033337 0.5878628 0.62873327 0.59036299 1 P 0 ;0,1=16,2=0.000000
L 0.62873327 0.59036299 0.62633327 0.59161348 1 P 0 ;0,1=16,2=0.000000
L 0.62633327 0.59161348 0.62366663 0.59161348 1 P 0 ;0,1=16,2=0.000000
L 0.62366663 0.59161348 0.62206654 0.59244665 1 P 0 ;0,1=16,2=0.000000
L 0.62206654 0.59244665 0.62073297 0.59452953 1 P 0 ;0,1=16,2=0.000000
L 0.62073297 0.59452953 0.6201998 0.59744636 1 P 0 ;0,1=16,2=0.000000
L 0.6201998 0.59744636 0.6210001 0.60036319 1 P 0 ;0,1=16,2=0.000000
L 0.6210001 0.60036319 0.62286634 0.60244685 1 P 0 ;0,1=16,2=0.000000
L 0.62286634 0.60244685 0.6249997 0.60328002 1 P 0 ;0,1=16,2=0.000000
L 0.6249997 0.60328002 0.62713307 0.60244685 1 P 0 ;0,1=16,2=0.000000
L 0.62713307 0.60244685 0.6289998 0.60036319 1 P 0 ;0,1=16,2=0.000000
L 0.6289998 0.60036319 0.6298001 0.59744636 1 P 0 ;0,1=16,2=0.000000
L 0.6298001 0.59744636 0.62926644 0.59452953 1 P 0 ;0,1=16,2=0.000000
L 0.62926644 0.59452953 0.62793337 0.59244665 1 P 0 ;0,1=16,2=0.000000
L 0.62793337 0.59244665 0.62633327 0.59161348 1 P 0 ;0,1=16,2=0.000000
L 0.62633327 0.59161348 0.62366663 0.59161348 1 P 0 ;0,1=16,2=0.000000
L 0.62366663 0.59161348 0.62126663 0.59036299 1 P 0 ;0,1=16,2=0.000000
L 0.62126663 0.59036299 0.61966654 0.5878628 1 P 0 ;0,1=16,2=0.000000
L 0.61966654 0.5878628 0.61913327 0.58494675 1 P 0 ;0,1=16,2=0.000000
L 0.61913327 0.58494675 0.61966654 0.58202913 1 P 0 ;0,1=16,2=0.000000
L 0.61966654 0.58202913 0.6210001 0.57994626 1 P 0 ;0,1=16,2=0.000000
L 0.6210001 0.57994626 0.62313346 0.57869656 1 P 0 ;0,1=16,2=0.000000
L 0.62313346 0.57869656 0.6249997 0.57828002 1 P 0 ;0,1=16,2=0.000000
L 0.4782 0.78828002 0.4782 0.81328002 1 P 0 ;0,1=11,2=0.000000
L 0.4782 0.81328002 0.46833297 0.79536329 1 P 0 ;0,1=11,2=0.000000
L 0.46833297 0.79536329 0.48166693 0.79536329 1 P 0 ;0,1=11,2=0.000000
L 0.46913327 0.59824911 0.47073297 0.59616624 1 P 0 ;0,1=20,2=0.000000
L 0.47073297 0.59616624 0.4725997 0.59491654 1 P 0 ;0,1=20,2=0.000000
L 0.4725997 0.59491654 0.4749997 0.5945 1 P 0 ;0,1=20,2=0.000000
L 0.4749997 0.5945 0.4774002 0.59533307 1 P 0 ;0,1=20,2=0.000000
L 0.4774002 0.59533307 0.47926644 0.59699941 1 P 0 ;0,1=20,2=0.000000
L 0.47926644 0.59699941 0.4806 0.59991624 1 P 0 ;0,1=20,2=0.000000
L 0.4806 0.59991624 0.48086663 0.60324961 1 P 0 ;0,1=20,2=0.000000
L 0.48086663 0.60324961 0.48033337 0.60658297 1 P 0 ;0,1=20,2=0.000000
L 0.48033337 0.60658297 0.4789998 0.60866663 1 P 0 ;0,1=20,2=0.000000
L 0.4789998 0.60866663 0.47713307 0.61033297 1 P 0 ;0,1=20,2=0.000000
L 0.47713307 0.61033297 0.47526683 0.61074951 1 P 0 ;0,1=20,2=0.000000
L 0.47526683 0.61074951 0.4734 0.61033297 1 P 0 ;0,1=20,2=0.000000
L 0.4734 0.61033297 0.4710001 0.60866663 1 P 0 ;0,1=20,2=0.000000
L 0.4710001 0.60866663 0.4717999 0.6195 1 P 0 ;0,1=20,2=0.000000
L 0.4717999 0.6195 0.4789998 0.6195 1 P 0 ;0,1=20,2=0.000000
L 0.47056663 0.5755 0.47056663 0.55328327 1 P 0 ;0,1=153,2=0.000000
L 0.47056663 0.55328327 0.4720997 0.54863238 1 P 0 ;0,1=153,2=0.000000
L 0.4720997 0.54863238 0.47516634 0.54553307 1 P 0 ;0,1=153,2=0.000000
L 0.47516634 0.54553307 0.47899961 0.5445 1 P 0 ;0,1=153,2=0.000000
L 0.47899961 0.5445 0.48283356 0.54553307 1 P 0 ;0,1=153,2=0.000000
L 0.48283356 0.54553307 0.4859002 0.54863238 1 P 0 ;0,1=153,2=0.000000
L 0.4859002 0.54863238 0.48743327 0.55328327 1 P 0 ;0,1=153,2=0.000000
L 0.48743327 0.55328327 0.48743327 0.5755 1 P 0 ;0,1=153,2=0.000000
L 0.50999961 0.5445 0.50999961 0.5755 1 P 0 ;0,1=153,2=0.000000
L 0.50999961 0.5755 0.5053999 0.5693003 1 P 0 ;0,1=153,2=0.000000
L 0.5053999 0.5445 0.51459931 0.5445 1 P 0 ;0,1=153,2=0.000000
L 0.5456 0.5445 0.5456 0.5755 1 P 0 ;0,1=153,2=0.000000
L 0.5456 0.5755 0.53141624 0.55328327 1 P 0 ;0,1=153,2=0.000000
L 0.53141624 0.55328327 0.55058366 0.55328327 1 P 0 ;0,1=153,2=0.000000
L 6.35853297 0.8045 6.35853297 0.8355 1 P 0 ;0,1=154,2=0.000000
L 6.35853297 0.8355 6.36849961 0.80966644 1 P 0 ;0,1=154,2=0.000000
L 6.36849961 0.80966644 6.37846693 0.8355 1 P 0 ;0,1=154,2=0.000000
L 6.37846693 0.8355 6.37846693 0.8045 1 P 0 ;0,1=154,2=0.000000
L 6.40716673 0.8045 6.39183317 0.8045 1 P 0 ;0,1=154,2=0.000000
L 6.39183317 0.8045 6.39183317 0.8355 1 P 0 ;0,1=154,2=0.000000
L 6.39183317 0.8355 6.40716673 0.8355 1 P 0 ;0,1=154,2=0.000000
L 6.40103327 0.82051703 6.39183317 0.82051703 1 P 0 ;0,1=154,2=0.000000
L 6.43049961 0.8045 6.43049961 0.8355 1 P 0 ;0,1=154,2=0.000000
L 6.43049961 0.8355 6.4258999 0.8293003 1 P 0 ;0,1=154,2=0.000000
L 6.4258999 0.8045 6.43509931 0.8045 1 P 0 ;0,1=154,2=0.000000
L 6.45421644 0.83033346 6.45651663 0.83343278 1 P 0 ;0,1=154,2=0.000000
L 6.45651663 0.83343278 6.4592001 0.83498337 1 P 0 ;0,1=154,2=0.000000
L 6.4592001 0.83498337 6.46226683 0.8355 1 P 0 ;0,1=154,2=0.000000
L 6.46226683 0.8355 6.4661 0.83446683 1 P 0 ;0,1=154,2=0.000000
L 6.4661 0.83446683 6.46878346 0.83188307 1 P 0 ;0,1=154,2=0.000000
L 6.46878346 0.83188307 6.46955 0.82878376 1 P 0 ;0,1=154,2=0.000000
L 6.46955 0.82878376 6.46916673 0.82568258 1 P 0 ;0,1=154,2=0.000000
L 6.46916673 0.82568258 6.46763307 0.8230998 1 P 0 ;0,1=154,2=0.000000
L 6.46763307 0.8230998 6.45996663 0.81793327 1 P 0 ;0,1=154,2=0.000000
L 6.45996663 0.81793327 6.45651663 0.81431644 1 P 0 ;0,1=154,2=0.000000
L 6.45651663 0.81431644 6.45421644 0.80914892 1 P 0 ;0,1=154,2=0.000000
L 6.45421644 0.80914892 6.4534499 0.8045 1 P 0 ;0,1=154,2=0.000000
L 6.4534499 0.8045 6.46955 0.8045 1 P 0 ;0,1=154,2=0.000000
L 0.25933297 3.8748 0.25933297 3.9058 1 P 0 ;0,1=155,2=0.000000
L 0.25933297 3.9058 0.26929961 3.87996644 1 P 0 ;0,1=155,2=0.000000
L 0.26929961 3.87996644 0.27926693 3.9058 1 P 0 ;0,1=155,2=0.000000
L 0.27926693 3.9058 0.27926693 3.8748 1 P 0 ;0,1=155,2=0.000000
L 0.30796673 3.8748 0.29263317 3.8748 1 P 0 ;0,1=155,2=0.000000
L 0.29263317 3.8748 0.29263317 3.9058 1 P 0 ;0,1=155,2=0.000000
L 0.29263317 3.9058 0.30796673 3.9058 1 P 0 ;0,1=155,2=0.000000
L 0.30183327 3.89081703 0.29263317 3.89081703 1 P 0 ;0,1=155,2=0.000000
L 0.32478287 3.87841585 0.32746634 3.87583307 1 P 0 ;0,1=155,2=0.000000
L 0.32746634 3.87583307 0.33053307 3.8748 1 P 0 ;0,1=155,2=0.000000
L 0.33053307 3.8748 0.3335998 3.87583307 1 P 0 ;0,1=155,2=0.000000
L 0.3335998 3.87583307 0.33628327 3.87893238 1 P 0 ;0,1=155,2=0.000000
L 0.33628327 3.87893238 0.3382002 3.88358327 1 P 0 ;0,1=155,2=0.000000
L 0.3382002 3.88358327 0.33896673 3.88823327 1 P 0 ;0,1=155,2=0.000000
L 0.33896673 3.88823327 0.33896673 3.89391634 1 P 0 ;0,1=155,2=0.000000
L 0.33896673 3.89391634 0.3382002 3.89856624 1 P 0 ;0,1=155,2=0.000000
L 0.3382002 3.89856624 0.33628327 3.9026997 1 P 0 ;0,1=155,2=0.000000
L 0.33628327 3.9026997 0.33398307 3.90476683 1 P 0 ;0,1=155,2=0.000000
L 0.33398307 3.90476683 0.33129961 3.9058 1 P 0 ;0,1=155,2=0.000000
L 0.33129961 3.9058 0.32823287 3.90476683 1 P 0 ;0,1=155,2=0.000000
L 0.32823287 3.90476683 0.32593337 3.9026997 1 P 0 ;0,1=155,2=0.000000
L 0.32593337 3.9026997 0.3243997 3.8996003 1 P 0 ;0,1=155,2=0.000000
L 0.3243997 3.8996003 0.32363317 3.89546594 1 P 0 ;0,1=155,2=0.000000
L 0.32363317 3.89546594 0.3243997 3.8918501 1 P 0 ;0,1=155,2=0.000000
L 0.3243997 3.8918501 0.32631663 3.88823327 1 P 0 ;0,1=155,2=0.000000
L 0.32631663 3.88823327 0.32861683 3.88616604 1 P 0 ;0,1=155,2=0.000000
L 0.32861683 3.88616604 0.33129961 3.88564951 1 P 0 ;0,1=155,2=0.000000
L 0.33129961 3.88564951 0.33436634 3.88668268 1 P 0 ;0,1=155,2=0.000000
L 0.33436634 3.88668268 0.33666654 3.88926634 1 P 0 ;0,1=155,2=0.000000
L 0.33666654 3.88926634 0.33896673 3.89391634 1 P 0 ;0,1=155,2=0.000000
L 0.06853297 0.2545 0.06853297 0.2855 1 P 0 ;0,1=156,2=0.000000
L 0.06853297 0.2855 0.07849961 0.25966644 1 P 0 ;0,1=156,2=0.000000
L 0.07849961 0.25966644 0.08846693 0.2855 1 P 0 ;0,1=156,2=0.000000
L 0.08846693 0.2855 0.08846693 0.2545 1 P 0 ;0,1=156,2=0.000000
L 0.11716673 0.2545 0.10183317 0.2545 1 P 0 ;0,1=156,2=0.000000
L 0.10183317 0.2545 0.10183317 0.2855 1 P 0 ;0,1=156,2=0.000000
L 0.10183317 0.2855 0.11716673 0.2855 1 P 0 ;0,1=156,2=0.000000
L 0.11103327 0.27051703 0.10183317 0.27051703 1 P 0 ;0,1=156,2=0.000000
L 0.14049961 0.2545 0.14049961 0.2855 1 P 0 ;0,1=156,2=0.000000
L 0.14049961 0.2855 0.1358999 0.2793003 1 P 0 ;0,1=156,2=0.000000
L 0.1358999 0.2545 0.14509931 0.2545 1 P 0 ;0,1=156,2=0.000000
L 0.17149961 0.2855 0.16843287 0.28446683 1 P 0 ;0,1=156,2=0.000000
L 0.16843287 0.28446683 0.16613337 0.28188307 1 P 0 ;0,1=156,2=0.000000
L 0.16613337 0.28188307 0.1645997 0.27878376 1 P 0 ;0,1=156,2=0.000000
L 0.1645997 0.27878376 0.1634499 0.27464941 1 P 0 ;0,1=156,2=0.000000
L 0.1634499 0.27464941 0.16306663 0.26999951 1 P 0 ;0,1=156,2=0.000000
L 0.16306663 0.26999951 0.1634499 0.26534951 1 P 0 ;0,1=156,2=0.000000
L 0.1634499 0.26534951 0.1645997 0.26121614 1 P 0 ;0,1=156,2=0.000000
L 0.1645997 0.26121614 0.16613337 0.25811585 1 P 0 ;0,1=156,2=0.000000
L 0.16613337 0.25811585 0.16843287 0.25553307 1 P 0 ;0,1=156,2=0.000000
L 0.16843287 0.25553307 0.17149961 0.2545 1 P 0 ;0,1=156,2=0.000000
L 0.17149961 0.2545 0.17456634 0.25553307 1 P 0 ;0,1=156,2=0.000000
L 0.17456634 0.25553307 0.17686654 0.25811585 1 P 0 ;0,1=156,2=0.000000
L 0.17686654 0.25811585 0.1784002 0.26121614 1 P 0 ;0,1=156,2=0.000000
L 0.1784002 0.26121614 0.17955 0.26534951 1 P 0 ;0,1=156,2=0.000000
L 0.17955 0.26534951 0.17993327 0.26999951 1 P 0 ;0,1=156,2=0.000000
L 0.17993327 0.26999951 0.17955 0.27464941 1 P 0 ;0,1=156,2=0.000000
L 0.17955 0.27464941 0.1784002 0.27878376 1 P 0 ;0,1=156,2=0.000000
L 0.1784002 0.27878376 0.17686654 0.28188307 1 P 0 ;0,1=156,2=0.000000
L 0.17686654 0.28188307 0.17456634 0.28446683 1 P 0 ;0,1=156,2=0.000000
L 0.17456634 0.28446683 0.17149961 0.2855 1 P 0 ;0,1=156,2=0.000000
L 6.36853297 3.9945 6.36853297 4.0255 1 P 0 ;0,1=157,2=0.000000
L 6.36853297 4.0255 6.37849961 3.99966644 1 P 0 ;0,1=157,2=0.000000
L 6.37849961 3.99966644 6.38846693 4.0255 1 P 0 ;0,1=157,2=0.000000
L 6.38846693 4.0255 6.38846693 3.9945 1 P 0 ;0,1=157,2=0.000000
L 6.41716673 3.9945 6.40183317 3.9945 1 P 0 ;0,1=157,2=0.000000
L 6.40183317 3.9945 6.40183317 4.0255 1 P 0 ;0,1=157,2=0.000000
L 6.40183317 4.0255 6.41716673 4.0255 1 P 0 ;0,1=157,2=0.000000
L 6.41103327 4.01051703 6.40183317 4.01051703 1 P 0 ;0,1=157,2=0.000000
L 6.44049961 3.9945 6.44049961 4.0255 1 P 0 ;0,1=157,2=0.000000
L 6.44049961 4.0255 6.4358999 4.0193003 1 P 0 ;0,1=157,2=0.000000
L 6.4358999 3.9945 6.44509931 3.9945 1 P 0 ;0,1=157,2=0.000000
L 6.47149961 3.9945 6.47149961 4.0255 1 P 0 ;0,1=157,2=0.000000
L 6.47149961 4.0255 6.4668999 4.0193003 1 P 0 ;0,1=157,2=0.000000
L 6.4668999 3.9945 6.47609931 3.9945 1 P 0 ;0,1=157,2=0.000000
L 1.104 0.7484 1.104 0.7084 1 P 0 
L 1.104 0.7084 1.0555 0.7084 1 P 0 
L 1.0555 0.7084 1.0555 0.6736 1 P 0 
L 1.0555 0.6736 1.104 0.6736 1 P 0 
L 1.104 0.6736 1.104 0.6336 1 P 0 
L 1.104 0.6336 1.0555 0.6336 1 P 0 
L 1.0555 0.6336 1.0555 0.62391004 1 P 0 
L 1.0555 0.75808996 1.0555 0.7484 1 P 0 
L 1.0555 0.7484 1.104 0.7484 1 P 0 
L 0.9725 0.75808996 1.0555 0.75808996 1 P 0 
L 1.0555 0.62391004 0.9725 0.62391004 1 P 0 
L 0.9725 0.62391004 0.9725 0.6336 1 P 0 
L 0.9725 0.6336 0.924 0.6336 1 P 0 
L 0.924 0.6336 0.924 0.7484 1 P 0 
L 0.924 0.7484 0.9725 0.7484 1 P 0 
L 0.9725 0.7484 0.9725 0.75808996 1 P 0 
S P 0
OB 0.9513 0.767 I
OC 0.9513 0.767 0.9363 0.767 Y
OE
SE
L 1.11156663 0.75414892 1.11386614 0.75156614 1 P 0 ;0,1=20,2=0.000000
L 1.11386614 0.75156614 1.11654961 0.75001654 1 P 0 ;0,1=20,2=0.000000
L 1.11654961 0.75001654 1.11999961 0.7495 1 P 0 ;0,1=20,2=0.000000
L 1.11999961 0.7495 1.1234503 0.75053307 1 P 0 ;0,1=20,2=0.000000
L 1.1234503 0.75053307 1.12613307 0.75259931 1 P 0 ;0,1=20,2=0.000000
L 1.12613307 0.75259931 1.12805 0.75621614 1 P 0 ;0,1=20,2=0.000000
L 1.12805 0.75621614 1.12843327 0.76034951 1 P 0 ;0,1=20,2=0.000000
L 1.12843327 0.76034951 1.12766673 0.76448287 1 P 0 ;0,1=20,2=0.000000
L 1.12766673 0.76448287 1.1257498 0.76706663 1 P 0 ;0,1=20,2=0.000000
L 1.1257498 0.76706663 1.12306634 0.76913287 1 P 0 ;0,1=20,2=0.000000
L 1.12306634 0.76913287 1.12038356 0.76964941 1 P 0 ;0,1=20,2=0.000000
L 1.12038356 0.76964941 1.1177001 0.76913287 1 P 0 ;0,1=20,2=0.000000
L 1.1177001 0.76913287 1.1142501 0.76706663 1 P 0 ;0,1=20,2=0.000000
L 1.1142501 0.76706663 1.1153999 0.7805 1 P 0 ;0,1=20,2=0.000000
L 1.1153999 0.7805 1.1257498 0.7805 1 P 0 ;0,1=20,2=0.000000
L 1.1346 0.6145 1.1346 0.6455 1 P 0 ;0,1=11,2=0.000000
L 1.1346 0.6455 1.12041624 0.62328327 1 P 0 ;0,1=11,2=0.000000
L 1.12041624 0.62328327 1.13958366 0.62328327 1 P 0 ;0,1=11,2=0.000000
L 1.02736663 0.8075 1.02736663 0.78528327 1 P 0 ;0,1=158,2=0.000000
L 1.02736663 0.78528327 1.0288997 0.78063238 1 P 0 ;0,1=158,2=0.000000
L 1.0288997 0.78063238 1.03196634 0.77753307 1 P 0 ;0,1=158,2=0.000000
L 1.03196634 0.77753307 1.03579961 0.7765 1 P 0 ;0,1=158,2=0.000000
L 1.03579961 0.7765 1.03963356 0.77753307 1 P 0 ;0,1=158,2=0.000000
L 1.03963356 0.77753307 1.0427002 0.78063238 1 P 0 ;0,1=158,2=0.000000
L 1.0427002 0.78063238 1.04423327 0.78528327 1 P 0 ;0,1=158,2=0.000000
L 1.04423327 0.78528327 1.04423327 0.8075 1 P 0 ;0,1=158,2=0.000000
L 1.06603307 0.7765 1.06679961 0.78321614 1 P 0 ;0,1=158,2=0.000000
L 1.06679961 0.78321614 1.0679501 0.78889921 1 P 0 ;0,1=158,2=0.000000
L 1.0679501 0.78889921 1.06948307 0.79406663 1 P 0 ;0,1=158,2=0.000000
L 1.06948307 0.79406663 1.0714 0.7997497 1 P 0 ;0,1=158,2=0.000000
L 1.0714 0.7997497 1.07446673 0.8075 1 P 0 ;0,1=158,2=0.000000
L 1.07446673 0.8075 1.05913317 0.8075 1 P 0 ;0,1=158,2=0.000000
L 0.93786663 0.59769961 0.94016614 0.59408278 1 P 0 ;0,1=10,2=0.000000
L 0.94016614 0.59408278 0.94323287 0.59201654 1 P 0 ;0,1=10,2=0.000000
L 0.94323287 0.59201654 0.94668356 0.5915 1 P 0 ;0,1=10,2=0.000000
L 0.94668356 0.5915 0.9497503 0.59201654 1 P 0 ;0,1=10,2=0.000000
L 0.9497503 0.59201654 0.95281703 0.59459931 1 P 0 ;0,1=10,2=0.000000
L 0.95281703 0.59459931 0.95473327 0.59769961 1 P 0 ;0,1=10,2=0.000000
L 0.95473327 0.59769961 0.95511654 0.6007999 1 P 0 ;0,1=10,2=0.000000
L 0.95511654 0.6007999 0.95435 0.60441575 1 P 0 ;0,1=10,2=0.000000
L 0.95435 0.60441575 0.95166654 0.60699951 1 P 0 ;0,1=10,2=0.000000
L 0.95166654 0.60699951 0.94898307 0.60803356 1 P 0 ;0,1=10,2=0.000000
L 0.94898307 0.60803356 0.94553307 0.60803356 1 P 0 ;0,1=10,2=0.000000
L 0.94898307 0.60803356 0.95128327 0.60958317 1 P 0 ;0,1=10,2=0.000000
L 0.95128327 0.60958317 0.9532002 0.61216594 1 P 0 ;0,1=10,2=0.000000
L 0.9532002 0.61216594 0.95396673 0.61526624 1 P 0 ;0,1=10,2=0.000000
L 0.95396673 0.61526624 0.9532002 0.61836654 1 P 0 ;0,1=10,2=0.000000
L 0.9532002 0.61836654 0.95128327 0.62094931 1 P 0 ;0,1=10,2=0.000000
L 0.95128327 0.62094931 0.94783327 0.6225 1 P 0 ;0,1=10,2=0.000000
L 0.94783327 0.6225 0.94438337 0.62198337 1 P 0 ;0,1=10,2=0.000000
L 0.94438337 0.62198337 0.94093337 0.61991624 1 P 0 ;0,1=10,2=0.000000
A 2.92066998 1.04043002 2.92066998 1.04043002 2.86066998 1.04043002 1 P 0 Y
L 2.85723297 0.9249 2.85723297 0.9559 1 P 0 ;0,1=159,2=0.000000
L 2.85723297 0.9559 2.86719961 0.93006644 1 P 0 ;0,1=159,2=0.000000
L 2.86719961 0.93006644 2.87716693 0.9559 1 P 0 ;0,1=159,2=0.000000
L 2.87716693 0.9559 2.87716693 0.9249 1 P 0 ;0,1=159,2=0.000000
L 2.88861624 0.9249 2.89819961 0.9559 1 P 0 ;0,1=159,2=0.000000
L 2.89819961 0.9559 2.90778366 0.9249 1 P 0 ;0,1=159,2=0.000000
L 2.90433307 0.93574951 2.89206614 0.93574951 1 P 0 ;0,1=159,2=0.000000
L 2.93763327 0.95331624 2.93533307 0.95486683 1 P 0 ;0,1=159,2=0.000000
L 2.93533307 0.95486683 2.9326503 0.9559 1 P 0 ;0,1=159,2=0.000000
L 2.9326503 0.9559 2.92958356 0.9559 1 P 0 ;0,1=159,2=0.000000
L 2.92958356 0.9559 2.92613287 0.95434931 1 P 0 ;0,1=159,2=0.000000
L 2.92613287 0.95434931 2.9234501 0.95176654 1 P 0 ;0,1=159,2=0.000000
L 2.9234501 0.95176654 2.92153317 0.94866624 1 P 0 ;0,1=159,2=0.000000
L 2.92153317 0.94866624 2.91999951 0.9434998 1 P 0 ;0,1=159,2=0.000000
L 2.91999951 0.9434998 2.91961624 0.9388498 1 P 0 ;0,1=159,2=0.000000
L 2.91961624 0.9388498 2.92038337 0.9341999 1 P 0 ;0,1=159,2=0.000000
L 2.92038337 0.9341999 2.92153317 0.93109961 1 P 0 ;0,1=159,2=0.000000
L 2.92153317 0.93109961 2.92383337 0.92799931 1 P 0 ;0,1=159,2=0.000000
L 2.92383337 0.92799931 2.92651683 0.92593307 1 P 0 ;0,1=159,2=0.000000
L 2.92651683 0.92593307 2.92919961 0.9249 1 P 0 ;0,1=159,2=0.000000
L 2.92919961 0.9249 2.93188307 0.9249 1 P 0 ;0,1=159,2=0.000000
L 2.93188307 0.9249 2.93456654 0.92593307 1 P 0 ;0,1=159,2=0.000000
L 2.93456654 0.92593307 2.93686673 0.92748278 1 P 0 ;0,1=159,2=0.000000
L 2.93686673 0.92748278 2.93878366 0.92954892 1 P 0 ;0,1=159,2=0.000000
L 2.9487 0.91456703 2.9717 0.91456703 1 P 0 ;0,1=159,2=0.000000
L 2.98353317 0.9249 2.98353317 0.9559 1 P 0 ;0,1=159,2=0.000000
L 2.98353317 0.9559 2.99273327 0.9559 1 P 0 ;0,1=159,2=0.000000
L 2.99273327 0.9559 2.9958 0.95434931 1 P 0 ;0,1=159,2=0.000000
L 2.9958 0.95434931 2.9981002 0.95073346 1 P 0 ;0,1=159,2=0.000000
L 2.9981002 0.95073346 2.99886673 0.9466 1 P 0 ;0,1=159,2=0.000000
L 2.99886673 0.9466 2.9981002 0.94246663 1 P 0 ;0,1=159,2=0.000000
L 2.9981002 0.94246663 2.99618327 0.93936634 1 P 0 ;0,1=159,2=0.000000
L 2.99618327 0.93936634 2.99273327 0.93781575 1 P 0 ;0,1=159,2=0.000000
L 2.99273327 0.93781575 2.98353317 0.93781575 1 P 0 ;0,1=159,2=0.000000
L 3.0175999 0.9559 3.02679931 0.9559 1 P 0 ;0,1=159,2=0.000000
L 3.02219961 0.9559 3.02219961 0.9249 1 P 0 ;0,1=159,2=0.000000
L 3.0175999 0.9249 3.02679931 0.9249 1 P 0 ;0,1=159,2=0.000000
L 3.04438337 0.9249 3.04438337 0.9559 1 P 0 ;0,1=159,2=0.000000
L 3.04438337 0.9559 3.06201654 0.9249 1 P 0 ;0,1=159,2=0.000000
L 3.06201654 0.9249 3.06201654 0.9559 1 P 0 ;0,1=159,2=0.000000
L 3.0888 0.9249 3.0888 0.9559 1 P 0 ;0,1=159,2=0.000000
L 3.0888 0.9559 3.07461624 0.93368327 1 P 0 ;0,1=159,2=0.000000
L 3.07461624 0.93368327 3.09378366 0.93368327 1 P 0 ;0,1=159,2=0.000000
A 2.83866998 0.93443002 2.83866998 0.93443002 2.77866998 0.93443002 1 P 0 Y
L 2.76523297 0.8189 2.76523297 0.8499 1 P 0 ;0,1=160,2=0.000000
L 2.76523297 0.8499 2.77519961 0.82406644 1 P 0 ;0,1=160,2=0.000000
L 2.77519961 0.82406644 2.78516693 0.8499 1 P 0 ;0,1=160,2=0.000000
L 2.78516693 0.8499 2.78516693 0.8189 1 P 0 ;0,1=160,2=0.000000
L 2.79661624 0.8189 2.80619961 0.8499 1 P 0 ;0,1=160,2=0.000000
L 2.80619961 0.8499 2.81578366 0.8189 1 P 0 ;0,1=160,2=0.000000
L 2.81233307 0.82974951 2.80006614 0.82974951 1 P 0 ;0,1=160,2=0.000000
L 2.84563327 0.84731624 2.84333307 0.84886683 1 P 0 ;0,1=160,2=0.000000
L 2.84333307 0.84886683 2.8406503 0.8499 1 P 0 ;0,1=160,2=0.000000
L 2.8406503 0.8499 2.83758356 0.8499 1 P 0 ;0,1=160,2=0.000000
L 2.83758356 0.8499 2.83413287 0.84834931 1 P 0 ;0,1=160,2=0.000000
L 2.83413287 0.84834931 2.8314501 0.84576654 1 P 0 ;0,1=160,2=0.000000
L 2.8314501 0.84576654 2.82953317 0.84266624 1 P 0 ;0,1=160,2=0.000000
L 2.82953317 0.84266624 2.82799951 0.8374998 1 P 0 ;0,1=160,2=0.000000
L 2.82799951 0.8374998 2.82761624 0.8328498 1 P 0 ;0,1=160,2=0.000000
L 2.82761624 0.8328498 2.82838337 0.8281999 1 P 0 ;0,1=160,2=0.000000
L 2.82838337 0.8281999 2.82953317 0.82509961 1 P 0 ;0,1=160,2=0.000000
L 2.82953317 0.82509961 2.83183337 0.82199931 1 P 0 ;0,1=160,2=0.000000
L 2.83183337 0.82199931 2.83451683 0.81993307 1 P 0 ;0,1=160,2=0.000000
L 2.83451683 0.81993307 2.83719961 0.8189 1 P 0 ;0,1=160,2=0.000000
L 2.83719961 0.8189 2.83988307 0.8189 1 P 0 ;0,1=160,2=0.000000
L 2.83988307 0.8189 2.84256654 0.81993307 1 P 0 ;0,1=160,2=0.000000
L 2.84256654 0.81993307 2.84486673 0.82148278 1 P 0 ;0,1=160,2=0.000000
L 2.84486673 0.82148278 2.84678366 0.82354892 1 P 0 ;0,1=160,2=0.000000
L 2.8567 0.80856703 2.8797 0.80856703 1 P 0 ;0,1=160,2=0.000000
L 2.89153317 0.8189 2.89153317 0.8499 1 P 0 ;0,1=160,2=0.000000
L 2.89153317 0.8499 2.90073327 0.8499 1 P 0 ;0,1=160,2=0.000000
L 2.90073327 0.8499 2.9038 0.84834931 1 P 0 ;0,1=160,2=0.000000
L 2.9038 0.84834931 2.9061002 0.84473346 1 P 0 ;0,1=160,2=0.000000
L 2.9061002 0.84473346 2.90686673 0.8406 1 P 0 ;0,1=160,2=0.000000
L 2.90686673 0.8406 2.9061002 0.83646663 1 P 0 ;0,1=160,2=0.000000
L 2.9061002 0.83646663 2.90418327 0.83336634 1 P 0 ;0,1=160,2=0.000000
L 2.90418327 0.83336634 2.90073327 0.83181575 1 P 0 ;0,1=160,2=0.000000
L 2.90073327 0.83181575 2.89153317 0.83181575 1 P 0 ;0,1=160,2=0.000000
L 2.9255999 0.8499 2.93479931 0.8499 1 P 0 ;0,1=160,2=0.000000
L 2.93019961 0.8499 2.93019961 0.8189 1 P 0 ;0,1=160,2=0.000000
L 2.9255999 0.8189 2.93479931 0.8189 1 P 0 ;0,1=160,2=0.000000
L 2.95238337 0.8189 2.95238337 0.8499 1 P 0 ;0,1=160,2=0.000000
L 2.95238337 0.8499 2.97001654 0.8189 1 P 0 ;0,1=160,2=0.000000
L 2.97001654 0.8189 2.97001654 0.8499 1 P 0 ;0,1=160,2=0.000000
L 2.98491644 0.83181575 2.9875999 0.83543356 1 P 0 ;0,1=160,2=0.000000
L 2.9875999 0.83543356 2.9899001 0.8374998 1 P 0 ;0,1=160,2=0.000000
L 2.9899001 0.8374998 2.99296683 0.83853287 1 P 0 ;0,1=160,2=0.000000
L 2.99296683 0.83853287 2.9956503 0.8374998 1 P 0 ;0,1=160,2=0.000000
L 2.9956503 0.8374998 2.99756654 0.83543356 1 P 0 ;0,1=160,2=0.000000
L 2.99756654 0.83543356 2.9991002 0.83233327 1 P 0 ;0,1=160,2=0.000000
L 2.9991002 0.83233327 2.99948346 0.82871644 1 P 0 ;0,1=160,2=0.000000
L 2.99948346 0.82871644 2.9991002 0.82561614 1 P 0 ;0,1=160,2=0.000000
L 2.9991002 0.82561614 2.99756654 0.82251585 1 P 0 ;0,1=160,2=0.000000
L 2.99756654 0.82251585 2.99526634 0.81993307 1 P 0 ;0,1=160,2=0.000000
L 2.99526634 0.81993307 2.99258356 0.8189 1 P 0 ;0,1=160,2=0.000000
L 2.99258356 0.8189 2.98951683 0.81993307 1 P 0 ;0,1=160,2=0.000000
L 2.98951683 0.81993307 2.98683337 0.82303238 1 P 0 ;0,1=160,2=0.000000
L 2.98683337 0.82303238 2.9852997 0.82768327 1 P 0 ;0,1=160,2=0.000000
L 2.9852997 0.82768327 2.98491644 0.8328498 1 P 0 ;0,1=160,2=0.000000
L 2.98491644 0.8328498 2.98568287 0.83956594 1 P 0 ;0,1=160,2=0.000000
L 2.98568287 0.83956594 2.98683337 0.84318376 1 P 0 ;0,1=160,2=0.000000
L 2.98683337 0.84318376 2.98874961 0.8467997 1 P 0 ;0,1=160,2=0.000000
L 2.98874961 0.8467997 2.99143307 0.84938337 1 P 0 ;0,1=160,2=0.000000
L 2.99143307 0.84938337 2.99411654 0.8499 1 P 0 ;0,1=160,2=0.000000
L 2.99411654 0.8499 2.9968 0.84886683 1 P 0 ;0,1=160,2=0.000000
L 2.9968 0.84886683 2.99871703 0.84628307 1 P 0 ;0,1=160,2=0.000000
A 2.71966998 0.93443002 2.71966998 0.93443002 2.65966998 0.93443002 1 P 0 Y
L 2.51623297 0.8189 2.51623297 0.8499 1 P 0 ;0,1=161,2=0.000000
L 2.51623297 0.8499 2.52619961 0.82406644 1 P 0 ;0,1=161,2=0.000000
L 2.52619961 0.82406644 2.53616693 0.8499 1 P 0 ;0,1=161,2=0.000000
L 2.53616693 0.8499 2.53616693 0.8189 1 P 0 ;0,1=161,2=0.000000
L 2.54761624 0.8189 2.55719961 0.8499 1 P 0 ;0,1=161,2=0.000000
L 2.55719961 0.8499 2.56678366 0.8189 1 P 0 ;0,1=161,2=0.000000
L 2.56333307 0.82974951 2.55106614 0.82974951 1 P 0 ;0,1=161,2=0.000000
L 2.59663327 0.84731624 2.59433307 0.84886683 1 P 0 ;0,1=161,2=0.000000
L 2.59433307 0.84886683 2.5916503 0.8499 1 P 0 ;0,1=161,2=0.000000
L 2.5916503 0.8499 2.58858356 0.8499 1 P 0 ;0,1=161,2=0.000000
L 2.58858356 0.8499 2.58513287 0.84834931 1 P 0 ;0,1=161,2=0.000000
L 2.58513287 0.84834931 2.5824501 0.84576654 1 P 0 ;0,1=161,2=0.000000
L 2.5824501 0.84576654 2.58053317 0.84266624 1 P 0 ;0,1=161,2=0.000000
L 2.58053317 0.84266624 2.57899951 0.8374998 1 P 0 ;0,1=161,2=0.000000
L 2.57899951 0.8374998 2.57861624 0.8328498 1 P 0 ;0,1=161,2=0.000000
L 2.57861624 0.8328498 2.57938337 0.8281999 1 P 0 ;0,1=161,2=0.000000
L 2.57938337 0.8281999 2.58053317 0.82509961 1 P 0 ;0,1=161,2=0.000000
L 2.58053317 0.82509961 2.58283337 0.82199931 1 P 0 ;0,1=161,2=0.000000
L 2.58283337 0.82199931 2.58551683 0.81993307 1 P 0 ;0,1=161,2=0.000000
L 2.58551683 0.81993307 2.58819961 0.8189 1 P 0 ;0,1=161,2=0.000000
L 2.58819961 0.8189 2.59088307 0.8189 1 P 0 ;0,1=161,2=0.000000
L 2.59088307 0.8189 2.59356654 0.81993307 1 P 0 ;0,1=161,2=0.000000
L 2.59356654 0.81993307 2.59586673 0.82148278 1 P 0 ;0,1=161,2=0.000000
L 2.59586673 0.82148278 2.59778366 0.82354892 1 P 0 ;0,1=161,2=0.000000
L 2.6077 0.80856703 2.6307 0.80856703 1 P 0 ;0,1=161,2=0.000000
L 2.64253317 0.8189 2.64253317 0.8499 1 P 0 ;0,1=161,2=0.000000
L 2.64253317 0.8499 2.65173327 0.8499 1 P 0 ;0,1=161,2=0.000000
L 2.65173327 0.8499 2.6548 0.84834931 1 P 0 ;0,1=161,2=0.000000
L 2.6548 0.84834931 2.6571002 0.84473346 1 P 0 ;0,1=161,2=0.000000
L 2.6571002 0.84473346 2.65786673 0.8406 1 P 0 ;0,1=161,2=0.000000
L 2.65786673 0.8406 2.6571002 0.83646663 1 P 0 ;0,1=161,2=0.000000
L 2.6571002 0.83646663 2.65518327 0.83336634 1 P 0 ;0,1=161,2=0.000000
L 2.65518327 0.83336634 2.65173327 0.83181575 1 P 0 ;0,1=161,2=0.000000
L 2.65173327 0.83181575 2.64253317 0.83181575 1 P 0 ;0,1=161,2=0.000000
L 2.6765999 0.8499 2.68579931 0.8499 1 P 0 ;0,1=161,2=0.000000
L 2.68119961 0.8499 2.68119961 0.8189 1 P 0 ;0,1=161,2=0.000000
L 2.6765999 0.8189 2.68579931 0.8189 1 P 0 ;0,1=161,2=0.000000
L 2.70338337 0.8189 2.70338337 0.8499 1 P 0 ;0,1=161,2=0.000000
L 2.70338337 0.8499 2.72101654 0.8189 1 P 0 ;0,1=161,2=0.000000
L 2.72101654 0.8189 2.72101654 0.8499 1 P 0 ;0,1=161,2=0.000000
L 2.74243307 0.8189 2.74319961 0.82561614 1 P 0 ;0,1=161,2=0.000000
L 2.74319961 0.82561614 2.7443501 0.83129921 1 P 0 ;0,1=161,2=0.000000
L 2.7443501 0.83129921 2.74588307 0.83646663 1 P 0 ;0,1=161,2=0.000000
L 2.74588307 0.83646663 2.7478 0.8421497 1 P 0 ;0,1=161,2=0.000000
L 2.7478 0.8421497 2.75086673 0.8499 1 P 0 ;0,1=161,2=0.000000
L 2.75086673 0.8499 2.73553317 0.8499 1 P 0 ;0,1=161,2=0.000000
A 2.59966998 0.93443002 2.59966998 0.93443002 2.53966998 0.93443002 1 P 0 Y
L 2.26623297 0.8189 2.26623297 0.8499 1 P 0 ;0,1=162,2=0.000000
L 2.26623297 0.8499 2.27619961 0.82406644 1 P 0 ;0,1=162,2=0.000000
L 2.27619961 0.82406644 2.28616693 0.8499 1 P 0 ;0,1=162,2=0.000000
L 2.28616693 0.8499 2.28616693 0.8189 1 P 0 ;0,1=162,2=0.000000
L 2.29761624 0.8189 2.30719961 0.8499 1 P 0 ;0,1=162,2=0.000000
L 2.30719961 0.8499 2.31678366 0.8189 1 P 0 ;0,1=162,2=0.000000
L 2.31333307 0.82974951 2.30106614 0.82974951 1 P 0 ;0,1=162,2=0.000000
L 2.34663327 0.84731624 2.34433307 0.84886683 1 P 0 ;0,1=162,2=0.000000
L 2.34433307 0.84886683 2.3416503 0.8499 1 P 0 ;0,1=162,2=0.000000
L 2.3416503 0.8499 2.33858356 0.8499 1 P 0 ;0,1=162,2=0.000000
L 2.33858356 0.8499 2.33513287 0.84834931 1 P 0 ;0,1=162,2=0.000000
L 2.33513287 0.84834931 2.3324501 0.84576654 1 P 0 ;0,1=162,2=0.000000
L 2.3324501 0.84576654 2.33053317 0.84266624 1 P 0 ;0,1=162,2=0.000000
L 2.33053317 0.84266624 2.32899951 0.8374998 1 P 0 ;0,1=162,2=0.000000
L 2.32899951 0.8374998 2.32861624 0.8328498 1 P 0 ;0,1=162,2=0.000000
L 2.32861624 0.8328498 2.32938337 0.8281999 1 P 0 ;0,1=162,2=0.000000
L 2.32938337 0.8281999 2.33053317 0.82509961 1 P 0 ;0,1=162,2=0.000000
L 2.33053317 0.82509961 2.33283337 0.82199931 1 P 0 ;0,1=162,2=0.000000
L 2.33283337 0.82199931 2.33551683 0.81993307 1 P 0 ;0,1=162,2=0.000000
L 2.33551683 0.81993307 2.33819961 0.8189 1 P 0 ;0,1=162,2=0.000000
L 2.33819961 0.8189 2.34088307 0.8189 1 P 0 ;0,1=162,2=0.000000
L 2.34088307 0.8189 2.34356654 0.81993307 1 P 0 ;0,1=162,2=0.000000
L 2.34356654 0.81993307 2.34586673 0.82148278 1 P 0 ;0,1=162,2=0.000000
L 2.34586673 0.82148278 2.34778366 0.82354892 1 P 0 ;0,1=162,2=0.000000
L 2.3577 0.80856703 2.3807 0.80856703 1 P 0 ;0,1=162,2=0.000000
L 2.39253317 0.8189 2.39253317 0.8499 1 P 0 ;0,1=162,2=0.000000
L 2.39253317 0.8499 2.40173327 0.8499 1 P 0 ;0,1=162,2=0.000000
L 2.40173327 0.8499 2.4048 0.84834931 1 P 0 ;0,1=162,2=0.000000
L 2.4048 0.84834931 2.4071002 0.84473346 1 P 0 ;0,1=162,2=0.000000
L 2.4071002 0.84473346 2.40786673 0.8406 1 P 0 ;0,1=162,2=0.000000
L 2.40786673 0.8406 2.4071002 0.83646663 1 P 0 ;0,1=162,2=0.000000
L 2.4071002 0.83646663 2.40518327 0.83336634 1 P 0 ;0,1=162,2=0.000000
L 2.40518327 0.83336634 2.40173327 0.83181575 1 P 0 ;0,1=162,2=0.000000
L 2.40173327 0.83181575 2.39253317 0.83181575 1 P 0 ;0,1=162,2=0.000000
L 2.4265999 0.8499 2.43579931 0.8499 1 P 0 ;0,1=162,2=0.000000
L 2.43119961 0.8499 2.43119961 0.8189 1 P 0 ;0,1=162,2=0.000000
L 2.4265999 0.8189 2.43579931 0.8189 1 P 0 ;0,1=162,2=0.000000
L 2.45338337 0.8189 2.45338337 0.8499 1 P 0 ;0,1=162,2=0.000000
L 2.45338337 0.8499 2.47101654 0.8189 1 P 0 ;0,1=162,2=0.000000
L 2.47101654 0.8189 2.47101654 0.8499 1 P 0 ;0,1=162,2=0.000000
L 2.49319961 0.8189 2.49588307 0.81941654 1 P 0 ;0,1=162,2=0.000000
L 2.49588307 0.81941654 2.4989498 0.82096614 1 P 0 ;0,1=162,2=0.000000
L 2.4989498 0.82096614 2.50086673 0.82354892 1 P 0 ;0,1=162,2=0.000000
L 2.50086673 0.82354892 2.50163327 0.82716673 1 P 0 ;0,1=162,2=0.000000
L 2.50163327 0.82716673 2.50086673 0.83078268 1 P 0 ;0,1=162,2=0.000000
L 2.50086673 0.83078268 2.49856654 0.83388287 1 P 0 ;0,1=162,2=0.000000
L 2.49856654 0.83388287 2.49511654 0.83543356 1 P 0 ;0,1=162,2=0.000000
L 2.49511654 0.83543356 2.49128337 0.83543356 1 P 0 ;0,1=162,2=0.000000
L 2.49128337 0.83543356 2.48898317 0.83646663 1 P 0 ;0,1=162,2=0.000000
L 2.48898317 0.83646663 2.48706614 0.83904941 1 P 0 ;0,1=162,2=0.000000
L 2.48706614 0.83904941 2.4862997 0.84266624 1 P 0 ;0,1=162,2=0.000000
L 2.4862997 0.84266624 2.4874501 0.84628307 1 P 0 ;0,1=162,2=0.000000
L 2.4874501 0.84628307 2.49013287 0.84886683 1 P 0 ;0,1=162,2=0.000000
L 2.49013287 0.84886683 2.49319961 0.8499 1 P 0 ;0,1=162,2=0.000000
L 2.49319961 0.8499 2.49626634 0.84886683 1 P 0 ;0,1=162,2=0.000000
L 2.49626634 0.84886683 2.4989498 0.84628307 1 P 0 ;0,1=162,2=0.000000
L 2.4989498 0.84628307 2.5001002 0.84266624 1 P 0 ;0,1=162,2=0.000000
L 2.5001002 0.84266624 2.49933307 0.83904941 1 P 0 ;0,1=162,2=0.000000
L 2.49933307 0.83904941 2.49741673 0.83646663 1 P 0 ;0,1=162,2=0.000000
L 2.49741673 0.83646663 2.49511654 0.83543356 1 P 0 ;0,1=162,2=0.000000
L 2.49511654 0.83543356 2.49128337 0.83543356 1 P 0 ;0,1=162,2=0.000000
L 2.49128337 0.83543356 2.48783337 0.83388287 1 P 0 ;0,1=162,2=0.000000
L 2.48783337 0.83388287 2.48553317 0.83078268 1 P 0 ;0,1=162,2=0.000000
L 2.48553317 0.83078268 2.48476663 0.82716673 1 P 0 ;0,1=162,2=0.000000
L 2.48476663 0.82716673 2.48553317 0.82354892 1 P 0 ;0,1=162,2=0.000000
L 2.48553317 0.82354892 2.4874501 0.82096614 1 P 0 ;0,1=162,2=0.000000
L 2.4874501 0.82096614 2.49051683 0.81941654 1 P 0 ;0,1=162,2=0.000000
L 2.49051683 0.81941654 2.49319961 0.8189 1 P 0 ;0,1=162,2=0.000000
A 1.32066998 1.04043002 1.32066998 1.04043002 1.26066998 1.04043002 1 P 0 Y
L 1.05653297 1.12966998 1.05653297 1.16066998 1 P 0 ;0,1=163,2=0.000000
L 1.05653297 1.16066998 1.06649961 1.13483642 1 P 0 ;0,1=163,2=0.000000
L 1.06649961 1.13483642 1.07646693 1.16066998 1 P 0 ;0,1=163,2=0.000000
L 1.07646693 1.16066998 1.07646693 1.12966998 1 P 0 ;0,1=163,2=0.000000
L 1.08791624 1.12966998 1.09749961 1.16066998 1 P 0 ;0,1=163,2=0.000000
L 1.09749961 1.16066998 1.10708366 1.12966998 1 P 0 ;0,1=163,2=0.000000
L 1.10363307 1.14051949 1.09136614 1.14051949 1 P 0 ;0,1=163,2=0.000000
L 1.13693327 1.15808622 1.13463307 1.15963681 1 P 0 ;0,1=163,2=0.000000
L 1.13463307 1.15963681 1.1319503 1.16066998 1 P 0 ;0,1=163,2=0.000000
L 1.1319503 1.16066998 1.12888356 1.16066998 1 P 0 ;0,1=163,2=0.000000
L 1.12888356 1.16066998 1.12543287 1.15911929 1 P 0 ;0,1=163,2=0.000000
L 1.12543287 1.15911929 1.1227501 1.15653652 1 P 0 ;0,1=163,2=0.000000
L 1.1227501 1.15653652 1.12083317 1.15343622 1 P 0 ;0,1=163,2=0.000000
L 1.12083317 1.15343622 1.11929951 1.14826978 1 P 0 ;0,1=163,2=0.000000
L 1.11929951 1.14826978 1.11891624 1.14361978 1 P 0 ;0,1=163,2=0.000000
L 1.11891624 1.14361978 1.11968337 1.13896988 1 P 0 ;0,1=163,2=0.000000
L 1.11968337 1.13896988 1.12083317 1.13586959 1 P 0 ;0,1=163,2=0.000000
L 1.12083317 1.13586959 1.12313337 1.13276929 1 P 0 ;0,1=163,2=0.000000
L 1.12313337 1.13276929 1.12581683 1.13070305 1 P 0 ;0,1=163,2=0.000000
L 1.12581683 1.13070305 1.12849961 1.12966998 1 P 0 ;0,1=163,2=0.000000
L 1.12849961 1.12966998 1.13118307 1.12966998 1 P 0 ;0,1=163,2=0.000000
L 1.13118307 1.12966998 1.13386654 1.13070305 1 P 0 ;0,1=163,2=0.000000
L 1.13386654 1.13070305 1.13616673 1.13225276 1 P 0 ;0,1=163,2=0.000000
L 1.13616673 1.13225276 1.13808366 1.1343189 1 P 0 ;0,1=163,2=0.000000
L 1.148 1.11933701 1.171 1.11933701 1 P 0 ;0,1=163,2=0.000000
L 1.18283317 1.12966998 1.18283317 1.16066998 1 P 0 ;0,1=163,2=0.000000
L 1.18283317 1.16066998 1.19203327 1.16066998 1 P 0 ;0,1=163,2=0.000000
L 1.19203327 1.16066998 1.1951 1.15911929 1 P 0 ;0,1=163,2=0.000000
L 1.1951 1.15911929 1.1974002 1.15550344 1 P 0 ;0,1=163,2=0.000000
L 1.1974002 1.15550344 1.19816673 1.15136998 1 P 0 ;0,1=163,2=0.000000
L 1.19816673 1.15136998 1.1974002 1.14723661 1 P 0 ;0,1=163,2=0.000000
L 1.1974002 1.14723661 1.19548327 1.14413632 1 P 0 ;0,1=163,2=0.000000
L 1.19548327 1.14413632 1.19203327 1.14258573 1 P 0 ;0,1=163,2=0.000000
L 1.19203327 1.14258573 1.18283317 1.14258573 1 P 0 ;0,1=163,2=0.000000
L 1.2168999 1.16066998 1.22609931 1.16066998 1 P 0 ;0,1=163,2=0.000000
L 1.22149961 1.16066998 1.22149961 1.12966998 1 P 0 ;0,1=163,2=0.000000
L 1.2168999 1.12966998 1.22609931 1.12966998 1 P 0 ;0,1=163,2=0.000000
L 1.24368337 1.12966998 1.24368337 1.16066998 1 P 0 ;0,1=163,2=0.000000
L 1.24368337 1.16066998 1.26131654 1.12966998 1 P 0 ;0,1=163,2=0.000000
L 1.26131654 1.12966998 1.26131654 1.16066998 1 P 0 ;0,1=163,2=0.000000
L 1.27506663 1.13586959 1.27736614 1.13225276 1 P 0 ;0,1=163,2=0.000000
L 1.27736614 1.13225276 1.28043287 1.13018652 1 P 0 ;0,1=163,2=0.000000
L 1.28043287 1.13018652 1.28388356 1.12966998 1 P 0 ;0,1=163,2=0.000000
L 1.28388356 1.12966998 1.2869503 1.13018652 1 P 0 ;0,1=163,2=0.000000
L 1.2869503 1.13018652 1.29001703 1.13276929 1 P 0 ;0,1=163,2=0.000000
L 1.29001703 1.13276929 1.29193327 1.13586959 1 P 0 ;0,1=163,2=0.000000
L 1.29193327 1.13586959 1.29231654 1.13896988 1 P 0 ;0,1=163,2=0.000000
L 1.29231654 1.13896988 1.29155 1.14258573 1 P 0 ;0,1=163,2=0.000000
L 1.29155 1.14258573 1.28886654 1.14516949 1 P 0 ;0,1=163,2=0.000000
L 1.28886654 1.14516949 1.28618307 1.14620354 1 P 0 ;0,1=163,2=0.000000
L 1.28618307 1.14620354 1.28273307 1.14620354 1 P 0 ;0,1=163,2=0.000000
L 1.28618307 1.14620354 1.28848327 1.14775315 1 P 0 ;0,1=163,2=0.000000
L 1.28848327 1.14775315 1.2904002 1.15033593 1 P 0 ;0,1=163,2=0.000000
L 1.2904002 1.15033593 1.29116673 1.15343622 1 P 0 ;0,1=163,2=0.000000
L 1.29116673 1.15343622 1.2904002 1.15653652 1 P 0 ;0,1=163,2=0.000000
L 1.2904002 1.15653652 1.28848327 1.15911929 1 P 0 ;0,1=163,2=0.000000
L 1.28848327 1.15911929 1.28503327 1.16066998 1 P 0 ;0,1=163,2=0.000000
L 1.28503327 1.16066998 1.28158337 1.16015335 1 P 0 ;0,1=163,2=0.000000
L 1.28158337 1.16015335 1.27813337 1.15808622 1 P 0 ;0,1=163,2=0.000000
A 2.92066998 2.64043002 2.92066998 2.64043002 2.86066998 2.64043002 1 P 0 Y
L 2.78153297 2.74966998 2.78153297 2.78066998 1 P 0 ;0,1=164,2=0.000000
L 2.78153297 2.78066998 2.79149961 2.75483642 1 P 0 ;0,1=164,2=0.000000
L 2.79149961 2.75483642 2.80146693 2.78066998 1 P 0 ;0,1=164,2=0.000000
L 2.80146693 2.78066998 2.80146693 2.74966998 1 P 0 ;0,1=164,2=0.000000
L 2.81291624 2.74966998 2.82249961 2.78066998 1 P 0 ;0,1=164,2=0.000000
L 2.82249961 2.78066998 2.83208366 2.74966998 1 P 0 ;0,1=164,2=0.000000
L 2.82863307 2.76051949 2.81636614 2.76051949 1 P 0 ;0,1=164,2=0.000000
L 2.86193327 2.77808622 2.85963307 2.77963681 1 P 0 ;0,1=164,2=0.000000
L 2.85963307 2.77963681 2.8569503 2.78066998 1 P 0 ;0,1=164,2=0.000000
L 2.8569503 2.78066998 2.85388356 2.78066998 1 P 0 ;0,1=164,2=0.000000
L 2.85388356 2.78066998 2.85043287 2.77911929 1 P 0 ;0,1=164,2=0.000000
L 2.85043287 2.77911929 2.8477501 2.77653652 1 P 0 ;0,1=164,2=0.000000
L 2.8477501 2.77653652 2.84583317 2.77343622 1 P 0 ;0,1=164,2=0.000000
L 2.84583317 2.77343622 2.84429951 2.76826978 1 P 0 ;0,1=164,2=0.000000
L 2.84429951 2.76826978 2.84391624 2.76361978 1 P 0 ;0,1=164,2=0.000000
L 2.84391624 2.76361978 2.84468337 2.75896988 1 P 0 ;0,1=164,2=0.000000
L 2.84468337 2.75896988 2.84583317 2.75586959 1 P 0 ;0,1=164,2=0.000000
L 2.84583317 2.75586959 2.84813337 2.75276929 1 P 0 ;0,1=164,2=0.000000
L 2.84813337 2.75276929 2.85081683 2.75070305 1 P 0 ;0,1=164,2=0.000000
L 2.85081683 2.75070305 2.85349961 2.74966998 1 P 0 ;0,1=164,2=0.000000
L 2.85349961 2.74966998 2.85618307 2.74966998 1 P 0 ;0,1=164,2=0.000000
L 2.85618307 2.74966998 2.85886654 2.75070305 1 P 0 ;0,1=164,2=0.000000
L 2.85886654 2.75070305 2.86116673 2.75225276 1 P 0 ;0,1=164,2=0.000000
L 2.86116673 2.75225276 2.86308366 2.7543189 1 P 0 ;0,1=164,2=0.000000
L 2.873 2.73933701 2.896 2.73933701 1 P 0 ;0,1=164,2=0.000000
L 2.90783317 2.74966998 2.90783317 2.78066998 1 P 0 ;0,1=164,2=0.000000
L 2.90783317 2.78066998 2.91703327 2.78066998 1 P 0 ;0,1=164,2=0.000000
L 2.91703327 2.78066998 2.9201 2.77911929 1 P 0 ;0,1=164,2=0.000000
L 2.9201 2.77911929 2.9224002 2.77550344 1 P 0 ;0,1=164,2=0.000000
L 2.9224002 2.77550344 2.92316673 2.77136998 1 P 0 ;0,1=164,2=0.000000
L 2.92316673 2.77136998 2.9224002 2.76723661 1 P 0 ;0,1=164,2=0.000000
L 2.9224002 2.76723661 2.92048327 2.76413632 1 P 0 ;0,1=164,2=0.000000
L 2.92048327 2.76413632 2.91703327 2.76258573 1 P 0 ;0,1=164,2=0.000000
L 2.91703327 2.76258573 2.90783317 2.76258573 1 P 0 ;0,1=164,2=0.000000
L 2.9418999 2.78066998 2.95109931 2.78066998 1 P 0 ;0,1=164,2=0.000000
L 2.94649961 2.78066998 2.94649961 2.74966998 1 P 0 ;0,1=164,2=0.000000
L 2.9418999 2.74966998 2.95109931 2.74966998 1 P 0 ;0,1=164,2=0.000000
L 2.96868337 2.74966998 2.96868337 2.78066998 1 P 0 ;0,1=164,2=0.000000
L 2.96868337 2.78066998 2.98631654 2.74966998 1 P 0 ;0,1=164,2=0.000000
L 2.98631654 2.74966998 2.98631654 2.78066998 1 P 0 ;0,1=164,2=0.000000
L 3.00006663 2.7543189 3.00236614 2.75173612 1 P 0 ;0,1=164,2=0.000000
L 3.00236614 2.75173612 3.00504961 2.75018652 1 P 0 ;0,1=164,2=0.000000
L 3.00504961 2.75018652 3.00849961 2.74966998 1 P 0 ;0,1=164,2=0.000000
L 3.00849961 2.74966998 3.0119503 2.75070305 1 P 0 ;0,1=164,2=0.000000
L 3.0119503 2.75070305 3.01463307 2.75276929 1 P 0 ;0,1=164,2=0.000000
L 3.01463307 2.75276929 3.01655 2.75638612 1 P 0 ;0,1=164,2=0.000000
L 3.01655 2.75638612 3.01693327 2.76051949 1 P 0 ;0,1=164,2=0.000000
L 3.01693327 2.76051949 3.01616673 2.76465285 1 P 0 ;0,1=164,2=0.000000
L 3.01616673 2.76465285 3.0142498 2.76723661 1 P 0 ;0,1=164,2=0.000000
L 3.0142498 2.76723661 3.01156634 2.76930285 1 P 0 ;0,1=164,2=0.000000
L 3.01156634 2.76930285 3.00888356 2.76981939 1 P 0 ;0,1=164,2=0.000000
L 3.00888356 2.76981939 3.0062001 2.76930285 1 P 0 ;0,1=164,2=0.000000
L 3.0062001 2.76930285 3.0027501 2.76723661 1 P 0 ;0,1=164,2=0.000000
L 3.0027501 2.76723661 3.0038999 2.78066998 1 P 0 ;0,1=164,2=0.000000
L 3.0038999 2.78066998 3.0142498 2.78066998 1 P 0 ;0,1=164,2=0.000000
A 1.32066998 2.64043002 1.32066998 2.64043002 1.26066998 2.64043002 1 P 0 Y
L 1.14723297 2.5149 1.14723297 2.5459 1 P 0 ;0,1=165,2=0.000000
L 1.14723297 2.5459 1.15719961 2.52006644 1 P 0 ;0,1=165,2=0.000000
L 1.15719961 2.52006644 1.16716693 2.5459 1 P 0 ;0,1=165,2=0.000000
L 1.16716693 2.5459 1.16716693 2.5149 1 P 0 ;0,1=165,2=0.000000
L 1.17861624 2.5149 1.18819961 2.5459 1 P 0 ;0,1=165,2=0.000000
L 1.18819961 2.5459 1.19778366 2.5149 1 P 0 ;0,1=165,2=0.000000
L 1.19433307 2.52574951 1.18206614 2.52574951 1 P 0 ;0,1=165,2=0.000000
L 1.22763327 2.54331624 1.22533307 2.54486683 1 P 0 ;0,1=165,2=0.000000
L 1.22533307 2.54486683 1.2226503 2.5459 1 P 0 ;0,1=165,2=0.000000
L 1.2226503 2.5459 1.21958356 2.5459 1 P 0 ;0,1=165,2=0.000000
L 1.21958356 2.5459 1.21613287 2.54434931 1 P 0 ;0,1=165,2=0.000000
L 1.21613287 2.54434931 1.2134501 2.54176654 1 P 0 ;0,1=165,2=0.000000
L 1.2134501 2.54176654 1.21153317 2.53866624 1 P 0 ;0,1=165,2=0.000000
L 1.21153317 2.53866624 1.20999951 2.5334998 1 P 0 ;0,1=165,2=0.000000
L 1.20999951 2.5334998 1.20961624 2.5288498 1 P 0 ;0,1=165,2=0.000000
L 1.20961624 2.5288498 1.21038337 2.5241999 1 P 0 ;0,1=165,2=0.000000
L 1.21038337 2.5241999 1.21153317 2.52109961 1 P 0 ;0,1=165,2=0.000000
L 1.21153317 2.52109961 1.21383337 2.51799931 1 P 0 ;0,1=165,2=0.000000
L 1.21383337 2.51799931 1.21651683 2.51593307 1 P 0 ;0,1=165,2=0.000000
L 1.21651683 2.51593307 1.21919961 2.5149 1 P 0 ;0,1=165,2=0.000000
L 1.21919961 2.5149 1.22188307 2.5149 1 P 0 ;0,1=165,2=0.000000
L 1.22188307 2.5149 1.22456654 2.51593307 1 P 0 ;0,1=165,2=0.000000
L 1.22456654 2.51593307 1.22686673 2.51748278 1 P 0 ;0,1=165,2=0.000000
L 1.22686673 2.51748278 1.22878366 2.51954892 1 P 0 ;0,1=165,2=0.000000
L 1.2387 2.50456703 1.2617 2.50456703 1 P 0 ;0,1=165,2=0.000000
L 1.27353317 2.5149 1.27353317 2.5459 1 P 0 ;0,1=165,2=0.000000
L 1.27353317 2.5459 1.28273327 2.5459 1 P 0 ;0,1=165,2=0.000000
L 1.28273327 2.5459 1.2858 2.54434931 1 P 0 ;0,1=165,2=0.000000
L 1.2858 2.54434931 1.2881002 2.54073346 1 P 0 ;0,1=165,2=0.000000
L 1.2881002 2.54073346 1.28886673 2.5366 1 P 0 ;0,1=165,2=0.000000
L 1.28886673 2.5366 1.2881002 2.53246663 1 P 0 ;0,1=165,2=0.000000
L 1.2881002 2.53246663 1.28618327 2.52936634 1 P 0 ;0,1=165,2=0.000000
L 1.28618327 2.52936634 1.28273327 2.52781575 1 P 0 ;0,1=165,2=0.000000
L 1.28273327 2.52781575 1.27353317 2.52781575 1 P 0 ;0,1=165,2=0.000000
L 1.3075999 2.5459 1.31679931 2.5459 1 P 0 ;0,1=165,2=0.000000
L 1.31219961 2.5459 1.31219961 2.5149 1 P 0 ;0,1=165,2=0.000000
L 1.3075999 2.5149 1.31679931 2.5149 1 P 0 ;0,1=165,2=0.000000
L 1.33438337 2.5149 1.33438337 2.5459 1 P 0 ;0,1=165,2=0.000000
L 1.33438337 2.5459 1.35201654 2.5149 1 P 0 ;0,1=165,2=0.000000
L 1.35201654 2.5149 1.35201654 2.5459 1 P 0 ;0,1=165,2=0.000000
L 1.37419961 2.5149 1.37419961 2.5459 1 P 0 ;0,1=165,2=0.000000
L 1.37419961 2.5459 1.3695999 2.5397003 1 P 0 ;0,1=165,2=0.000000
L 1.3695999 2.5149 1.37879931 2.5149 1 P 0 ;0,1=165,2=0.000000
A 1.32066998 1.84043002 1.32066998 1.84043002 1.26066998 1.84043002 1 P 0 Y
L 1.14723297 1.7249 1.14723297 1.7559 1 P 0 ;0,1=166,2=0.000000
L 1.14723297 1.7559 1.15719961 1.73006644 1 P 0 ;0,1=166,2=0.000000
L 1.15719961 1.73006644 1.16716693 1.7559 1 P 0 ;0,1=166,2=0.000000
L 1.16716693 1.7559 1.16716693 1.7249 1 P 0 ;0,1=166,2=0.000000
L 1.17861624 1.7249 1.18819961 1.7559 1 P 0 ;0,1=166,2=0.000000
L 1.18819961 1.7559 1.19778366 1.7249 1 P 0 ;0,1=166,2=0.000000
L 1.19433307 1.73574951 1.18206614 1.73574951 1 P 0 ;0,1=166,2=0.000000
L 1.22763327 1.75331624 1.22533307 1.75486683 1 P 0 ;0,1=166,2=0.000000
L 1.22533307 1.75486683 1.2226503 1.7559 1 P 0 ;0,1=166,2=0.000000
L 1.2226503 1.7559 1.21958356 1.7559 1 P 0 ;0,1=166,2=0.000000
L 1.21958356 1.7559 1.21613287 1.75434931 1 P 0 ;0,1=166,2=0.000000
L 1.21613287 1.75434931 1.2134501 1.75176654 1 P 0 ;0,1=166,2=0.000000
L 1.2134501 1.75176654 1.21153317 1.74866624 1 P 0 ;0,1=166,2=0.000000
L 1.21153317 1.74866624 1.20999951 1.7434998 1 P 0 ;0,1=166,2=0.000000
L 1.20999951 1.7434998 1.20961624 1.7388498 1 P 0 ;0,1=166,2=0.000000
L 1.20961624 1.7388498 1.21038337 1.7341999 1 P 0 ;0,1=166,2=0.000000
L 1.21038337 1.7341999 1.21153317 1.73109961 1 P 0 ;0,1=166,2=0.000000
L 1.21153317 1.73109961 1.21383337 1.72799931 1 P 0 ;0,1=166,2=0.000000
L 1.21383337 1.72799931 1.21651683 1.72593307 1 P 0 ;0,1=166,2=0.000000
L 1.21651683 1.72593307 1.21919961 1.7249 1 P 0 ;0,1=166,2=0.000000
L 1.21919961 1.7249 1.22188307 1.7249 1 P 0 ;0,1=166,2=0.000000
L 1.22188307 1.7249 1.22456654 1.72593307 1 P 0 ;0,1=166,2=0.000000
L 1.22456654 1.72593307 1.22686673 1.72748278 1 P 0 ;0,1=166,2=0.000000
L 1.22686673 1.72748278 1.22878366 1.72954892 1 P 0 ;0,1=166,2=0.000000
L 1.2387 1.71456703 1.2617 1.71456703 1 P 0 ;0,1=166,2=0.000000
L 1.27353317 1.7249 1.27353317 1.7559 1 P 0 ;0,1=166,2=0.000000
L 1.27353317 1.7559 1.28273327 1.7559 1 P 0 ;0,1=166,2=0.000000
L 1.28273327 1.7559 1.2858 1.75434931 1 P 0 ;0,1=166,2=0.000000
L 1.2858 1.75434931 1.2881002 1.75073346 1 P 0 ;0,1=166,2=0.000000
L 1.2881002 1.75073346 1.28886673 1.7466 1 P 0 ;0,1=166,2=0.000000
L 1.28886673 1.7466 1.2881002 1.74246663 1 P 0 ;0,1=166,2=0.000000
L 1.2881002 1.74246663 1.28618327 1.73936634 1 P 0 ;0,1=166,2=0.000000
L 1.28618327 1.73936634 1.28273327 1.73781575 1 P 0 ;0,1=166,2=0.000000
L 1.28273327 1.73781575 1.27353317 1.73781575 1 P 0 ;0,1=166,2=0.000000
L 1.3075999 1.7559 1.31679931 1.7559 1 P 0 ;0,1=166,2=0.000000
L 1.31219961 1.7559 1.31219961 1.7249 1 P 0 ;0,1=166,2=0.000000
L 1.3075999 1.7249 1.31679931 1.7249 1 P 0 ;0,1=166,2=0.000000
L 1.33438337 1.7249 1.33438337 1.7559 1 P 0 ;0,1=166,2=0.000000
L 1.33438337 1.7559 1.35201654 1.7249 1 P 0 ;0,1=166,2=0.000000
L 1.35201654 1.7249 1.35201654 1.7559 1 P 0 ;0,1=166,2=0.000000
L 1.36691644 1.75073346 1.36921663 1.75383278 1 P 0 ;0,1=166,2=0.000000
L 1.36921663 1.75383278 1.3719001 1.75538337 1 P 0 ;0,1=166,2=0.000000
L 1.3719001 1.75538337 1.37496683 1.7559 1 P 0 ;0,1=166,2=0.000000
L 1.37496683 1.7559 1.3788 1.75486683 1 P 0 ;0,1=166,2=0.000000
L 1.3788 1.75486683 1.38148346 1.75228307 1 P 0 ;0,1=166,2=0.000000
L 1.38148346 1.75228307 1.38225 1.74918376 1 P 0 ;0,1=166,2=0.000000
L 1.38225 1.74918376 1.38186673 1.74608258 1 P 0 ;0,1=166,2=0.000000
L 1.38186673 1.74608258 1.38033307 1.7434998 1 P 0 ;0,1=166,2=0.000000
L 1.38033307 1.7434998 1.37266663 1.73833327 1 P 0 ;0,1=166,2=0.000000
L 1.37266663 1.73833327 1.36921663 1.73471644 1 P 0 ;0,1=166,2=0.000000
L 1.36921663 1.73471644 1.36691644 1.72954892 1 P 0 ;0,1=166,2=0.000000
L 1.36691644 1.72954892 1.3661499 1.7249 1 P 0 ;0,1=166,2=0.000000
L 1.3661499 1.7249 1.38225 1.7249 1 P 0 ;0,1=166,2=0.000000
L 6.05118002 2.17431998 6.05118002 2.01368002 1 P 0 
L 5.92881998 2.17431998 6.05118002 2.17431998 1 P 0 
L 6.05118002 2.01368002 5.92881998 2.01368002 1 P 0 
L 5.92881998 2.01368002 5.92881998 2.17431998 1 P 0 
S P 0
OB 5.91 1.995 I
OC 5.91 1.995 5.89000246063 1.994998917323 Y
OE
SE
L 6.06085108 2.18156663 6.06343386 2.18386614 1 P 0 ;0,1=20,2=270.000000
L 6.06343386 2.18386614 6.06498346 2.18654961 1 P 0 ;0,1=20,2=270.000000
L 6.06498346 2.18654961 6.0655 2.18999961 1 P 0 ;0,1=20,2=270.000000
L 6.0655 2.18999961 6.06446693 2.1934503 1 P 0 ;0,1=20,2=270.000000
L 6.06446693 2.1934503 6.06240069 2.19613307 1 P 0 ;0,1=20,2=270.000000
L 6.06240069 2.19613307 6.05878386 2.19805 1 P 0 ;0,1=20,2=270.000000
L 6.05878386 2.19805 6.05465049 2.19843327 1 P 0 ;0,1=20,2=270.000000
L 6.05465049 2.19843327 6.05051713 2.19766673 1 P 0 ;0,1=20,2=270.000000
L 6.05051713 2.19766673 6.04793337 2.1957498 1 P 0 ;0,1=20,2=270.000000
L 6.04793337 2.1957498 6.04586713 2.19306634 1 P 0 ;0,1=20,2=270.000000
L 6.04586713 2.19306634 6.04535059 2.19038356 1 P 0 ;0,1=20,2=270.000000
L 6.04535059 2.19038356 6.04586713 2.1877001 1 P 0 ;0,1=20,2=270.000000
L 6.04586713 2.1877001 6.04793337 2.1842501 1 P 0 ;0,1=20,2=270.000000
L 6.04793337 2.1842501 6.0345 2.1853999 1 P 0 ;0,1=20,2=270.000000
L 6.0345 2.1853999 6.0345 2.1957498 1 P 0 ;0,1=20,2=270.000000
L 6.0695 2.02556663 6.09171673 2.02556663 1 P 0 ;0,1=167,2=270.000000
L 6.09171673 2.02556663 6.09636762 2.0270997 1 P 0 ;0,1=167,2=270.000000
L 6.09636762 2.0270997 6.09946693 2.03016634 1 P 0 ;0,1=167,2=270.000000
L 6.09946693 2.03016634 6.1005 2.03399961 1 P 0 ;0,1=167,2=270.000000
L 6.1005 2.03399961 6.09946693 2.03783356 1 P 0 ;0,1=167,2=270.000000
L 6.09946693 2.03783356 6.09636762 2.0409002 1 P 0 ;0,1=167,2=270.000000
L 6.09636762 2.0409002 6.09171673 2.04243327 1 P 0 ;0,1=167,2=270.000000
L 6.09171673 2.04243327 6.0695 2.04243327 1 P 0 ;0,1=167,2=270.000000
L 6.07466654 2.05771644 6.07156722 2.06001663 1 P 0 ;0,1=167,2=270.000000
L 6.07156722 2.06001663 6.07001663 2.0627001 1 P 0 ;0,1=167,2=270.000000
L 6.07001663 2.0627001 6.0695 2.06576683 1 P 0 ;0,1=167,2=270.000000
L 6.0695 2.06576683 6.07053317 2.0696 1 P 0 ;0,1=167,2=270.000000
L 6.07053317 2.0696 6.07311693 2.07228346 1 P 0 ;0,1=167,2=270.000000
L 6.07311693 2.07228346 6.07621624 2.07305 1 P 0 ;0,1=167,2=270.000000
L 6.07621624 2.07305 6.07931742 2.07266673 1 P 0 ;0,1=167,2=270.000000
L 6.07931742 2.07266673 6.0819002 2.07113307 1 P 0 ;0,1=167,2=270.000000
L 6.0819002 2.07113307 6.08706673 2.06346663 1 P 0 ;0,1=167,2=270.000000
L 6.08706673 2.06346663 6.09068356 2.06001663 1 P 0 ;0,1=167,2=270.000000
L 6.09068356 2.06001663 6.09585108 2.05771644 1 P 0 ;0,1=167,2=270.000000
L 6.09585108 2.05771644 6.1005 2.0569499 1 P 0 ;0,1=167,2=270.000000
L 6.1005 2.0569499 6.1005 2.07305 1 P 0 ;0,1=167,2=270.000000
L 6.1005 2.09523307 6.09378386 2.09599961 1 P 0 ;0,1=167,2=270.000000
L 6.09378386 2.09599961 6.08810079 2.0971501 1 P 0 ;0,1=167,2=270.000000
L 6.08810079 2.0971501 6.08293337 2.09868307 1 P 0 ;0,1=167,2=270.000000
L 6.08293337 2.09868307 6.0772503 2.1006 1 P 0 ;0,1=167,2=270.000000
L 6.0772503 2.1006 6.0695 2.10366673 1 P 0 ;0,1=167,2=270.000000
L 6.0695 2.10366673 6.0695 2.08833317 1 P 0 ;0,1=167,2=270.000000
L 6.0605 1.9946 6.0295 1.9946 1 P 0 ;0,1=11,2=270.000000
L 6.0295 1.9946 6.05171673 1.98041624 1 P 0 ;0,1=11,2=270.000000
L 6.05171673 1.98041624 6.05171673 1.99958366 1 P 0 ;0,1=11,2=270.000000
L 5.9305 2.18999961 5.92998346 2.19268307 1 P 0 ;0,1=16,2=270.000000
L 5.92998346 2.19268307 5.92843386 2.1957498 1 P 0 ;0,1=16,2=270.000000
L 5.92843386 2.1957498 5.92585108 2.19766673 1 P 0 ;0,1=16,2=270.000000
L 5.92585108 2.19766673 5.92223327 2.19843327 1 P 0 ;0,1=16,2=270.000000
L 5.92223327 2.19843327 5.91861732 2.19766673 1 P 0 ;0,1=16,2=270.000000
L 5.91861732 2.19766673 5.91551713 2.19536654 1 P 0 ;0,1=16,2=270.000000
L 5.91551713 2.19536654 5.91396644 2.19191654 1 P 0 ;0,1=16,2=270.000000
L 5.91396644 2.19191654 5.91396644 2.18808337 1 P 0 ;0,1=16,2=270.000000
L 5.91396644 2.18808337 5.91293337 2.18578317 1 P 0 ;0,1=16,2=270.000000
L 5.91293337 2.18578317 5.91035059 2.18386614 1 P 0 ;0,1=16,2=270.000000
L 5.91035059 2.18386614 5.90673376 2.1830997 1 P 0 ;0,1=16,2=270.000000
L 5.90673376 2.1830997 5.90311693 2.1842501 1 P 0 ;0,1=16,2=270.000000
L 5.90311693 2.1842501 5.90053317 2.18693287 1 P 0 ;0,1=16,2=270.000000
L 5.90053317 2.18693287 5.8995 2.18999961 1 P 0 ;0,1=16,2=270.000000
L 5.8995 2.18999961 5.90053317 2.19306634 1 P 0 ;0,1=16,2=270.000000
L 5.90053317 2.19306634 5.90311693 2.1957498 1 P 0 ;0,1=16,2=270.000000
L 5.90311693 2.1957498 5.90673376 2.1969002 1 P 0 ;0,1=16,2=270.000000
L 5.90673376 2.1969002 5.91035059 2.19613307 1 P 0 ;0,1=16,2=270.000000
L 5.91035059 2.19613307 5.91293337 2.19421673 1 P 0 ;0,1=16,2=270.000000
L 5.91293337 2.19421673 5.91396644 2.19191654 1 P 0 ;0,1=16,2=270.000000
L 5.91396644 2.19191654 5.91396644 2.18808337 1 P 0 ;0,1=16,2=270.000000
L 5.91396644 2.18808337 5.91551713 2.18463337 1 P 0 ;0,1=16,2=270.000000
L 5.91551713 2.18463337 5.91861732 2.18233317 1 P 0 ;0,1=16,2=270.000000
L 5.91861732 2.18233317 5.92223327 2.18156663 1 P 0 ;0,1=16,2=270.000000
L 5.92223327 2.18156663 5.92585108 2.18233317 1 P 0 ;0,1=16,2=270.000000
L 5.92585108 2.18233317 5.92843386 2.1842501 1 P 0 ;0,1=16,2=270.000000
L 5.92843386 2.1842501 5.92998346 2.18731683 1 P 0 ;0,1=16,2=270.000000
L 5.92998346 2.18731683 5.9305 2.18999961 1 P 0 ;0,1=16,2=270.000000
L 6.61786998 3.79896998 6.61786998 3.22071004 1 P 0 
L 5.82578996 3.79896998 6.61786998 3.79896998 1 P 0 
L 5.82578996 3.22071004 5.82578996 3.79896998 1 P 0 
L 6.61786998 3.22071004 5.82578996 3.22071004 1 P 0 
L 6.33183317 3.82 6.33183317 3.851 1 P 0 ;0,1=168,2=0.000000
L 6.33183317 3.851 6.34103327 3.851 1 P 0 ;0,1=168,2=0.000000
L 6.34103327 3.851 6.3441 3.84944931 1 P 0 ;0,1=168,2=0.000000
L 6.3441 3.84944931 6.3464002 3.84583346 1 P 0 ;0,1=168,2=0.000000
L 6.3464002 3.84583346 6.34716673 3.8417 1 P 0 ;0,1=168,2=0.000000
L 6.34716673 3.8417 6.3464002 3.83756663 1 P 0 ;0,1=168,2=0.000000
L 6.3464002 3.83756663 6.34448327 3.83446634 1 P 0 ;0,1=168,2=0.000000
L 6.34448327 3.83446634 6.34103327 3.83291575 1 P 0 ;0,1=168,2=0.000000
L 6.34103327 3.83291575 6.33183317 3.83291575 1 P 0 ;0,1=168,2=0.000000
L 6.36206663 3.82619961 6.36436614 3.82258278 1 P 0 ;0,1=168,2=0.000000
L 6.36436614 3.82258278 6.36743287 3.82051654 1 P 0 ;0,1=168,2=0.000000
L 6.36743287 3.82051654 6.37088356 3.82 1 P 0 ;0,1=168,2=0.000000
L 6.37088356 3.82 6.3739503 3.82051654 1 P 0 ;0,1=168,2=0.000000
L 6.3739503 3.82051654 6.37701703 3.82309931 1 P 0 ;0,1=168,2=0.000000
L 6.37701703 3.82309931 6.37893327 3.82619961 1 P 0 ;0,1=168,2=0.000000
L 6.37893327 3.82619961 6.37931654 3.8292999 1 P 0 ;0,1=168,2=0.000000
L 6.37931654 3.8292999 6.37855 3.83291575 1 P 0 ;0,1=168,2=0.000000
L 6.37855 3.83291575 6.37586654 3.83549951 1 P 0 ;0,1=168,2=0.000000
L 6.37586654 3.83549951 6.37318307 3.83653356 1 P 0 ;0,1=168,2=0.000000
L 6.37318307 3.83653356 6.36973307 3.83653356 1 P 0 ;0,1=168,2=0.000000
L 6.37318307 3.83653356 6.37548327 3.83808317 1 P 0 ;0,1=168,2=0.000000
L 6.37548327 3.83808317 6.3774002 3.84066594 1 P 0 ;0,1=168,2=0.000000
L 6.3774002 3.84066594 6.37816673 3.84376624 1 P 0 ;0,1=168,2=0.000000
L 6.37816673 3.84376624 6.3774002 3.84686654 1 P 0 ;0,1=168,2=0.000000
L 6.3774002 3.84686654 6.37548327 3.84944931 1 P 0 ;0,1=168,2=0.000000
L 6.37548327 3.84944931 6.37203327 3.851 1 P 0 ;0,1=168,2=0.000000
L 6.37203327 3.851 6.36858337 3.85048337 1 P 0 ;0,1=168,2=0.000000
L 6.36858337 3.85048337 6.36513337 3.84841624 1 P 0 ;0,1=168,2=0.000000
L 6.08499961 3.8095 6.08499961 3.8405 1 P 0 ;0,1=2,2=0.000000
L 6.08499961 3.8405 6.0803999 3.8343003 1 P 0 ;0,1=2,2=0.000000
L 6.0803999 3.8095 6.08959931 3.8095 1 P 0 ;0,1=2,2=0.000000
L 6.09656663 3.18569961 6.09886614 3.18208278 1 P 0 ;0,1=10,2=0.000000
L 6.09886614 3.18208278 6.10193287 3.18001654 1 P 0 ;0,1=10,2=0.000000
L 6.10193287 3.18001654 6.10538356 3.1795 1 P 0 ;0,1=10,2=0.000000
L 6.10538356 3.1795 6.1084503 3.18001654 1 P 0 ;0,1=10,2=0.000000
L 6.1084503 3.18001654 6.11151703 3.18259931 1 P 0 ;0,1=10,2=0.000000
L 6.11151703 3.18259931 6.11343327 3.18569961 1 P 0 ;0,1=10,2=0.000000
L 6.11343327 3.18569961 6.11381654 3.1887999 1 P 0 ;0,1=10,2=0.000000
L 6.11381654 3.1887999 6.11305 3.19241575 1 P 0 ;0,1=10,2=0.000000
L 6.11305 3.19241575 6.11036654 3.19499951 1 P 0 ;0,1=10,2=0.000000
L 6.11036654 3.19499951 6.10768307 3.19603356 1 P 0 ;0,1=10,2=0.000000
L 6.10768307 3.19603356 6.10423307 3.19603356 1 P 0 ;0,1=10,2=0.000000
L 6.10768307 3.19603356 6.10998327 3.19758317 1 P 0 ;0,1=10,2=0.000000
L 6.10998327 3.19758317 6.1119002 3.20016594 1 P 0 ;0,1=10,2=0.000000
L 6.1119002 3.20016594 6.11266673 3.20326624 1 P 0 ;0,1=10,2=0.000000
L 6.11266673 3.20326624 6.1119002 3.20636654 1 P 0 ;0,1=10,2=0.000000
L 6.1119002 3.20636654 6.10998327 3.20894931 1 P 0 ;0,1=10,2=0.000000
L 6.10998327 3.20894931 6.10653327 3.2105 1 P 0 ;0,1=10,2=0.000000
L 6.10653327 3.2105 6.10308337 3.20998337 1 P 0 ;0,1=10,2=0.000000
L 6.10308337 3.20998337 6.09963337 3.20791624 1 P 0 ;0,1=10,2=0.000000
L 5.95771644 3.18741575 5.9603999 3.19103356 1 P 0 ;0,1=8,2=0.000000
L 5.9603999 3.19103356 5.9627001 3.1930998 1 P 0 ;0,1=8,2=0.000000
L 5.9627001 3.1930998 5.96576683 3.19413287 1 P 0 ;0,1=8,2=0.000000
L 5.96576683 3.19413287 5.9684503 3.1930998 1 P 0 ;0,1=8,2=0.000000
L 5.9684503 3.1930998 5.97036654 3.19103356 1 P 0 ;0,1=8,2=0.000000
L 5.97036654 3.19103356 5.9719002 3.18793327 1 P 0 ;0,1=8,2=0.000000
L 5.9719002 3.18793327 5.97228346 3.18431644 1 P 0 ;0,1=8,2=0.000000
L 5.97228346 3.18431644 5.9719002 3.18121614 1 P 0 ;0,1=8,2=0.000000
L 5.9719002 3.18121614 5.97036654 3.17811585 1 P 0 ;0,1=8,2=0.000000
L 5.97036654 3.17811585 5.96806634 3.17553307 1 P 0 ;0,1=8,2=0.000000
L 5.96806634 3.17553307 5.96538356 3.1745 1 P 0 ;0,1=8,2=0.000000
L 5.96538356 3.1745 5.96231683 3.17553307 1 P 0 ;0,1=8,2=0.000000
L 5.96231683 3.17553307 5.95963337 3.17863238 1 P 0 ;0,1=8,2=0.000000
L 5.95963337 3.17863238 5.9580997 3.18328327 1 P 0 ;0,1=8,2=0.000000
L 5.9580997 3.18328327 5.95771644 3.1884498 1 P 0 ;0,1=8,2=0.000000
L 5.95771644 3.1884498 5.95848287 3.19516594 1 P 0 ;0,1=8,2=0.000000
L 5.95848287 3.19516594 5.95963337 3.19878376 1 P 0 ;0,1=8,2=0.000000
L 5.95963337 3.19878376 5.96154961 3.2023997 1 P 0 ;0,1=8,2=0.000000
L 5.96154961 3.2023997 5.96423307 3.20498337 1 P 0 ;0,1=8,2=0.000000
L 5.96423307 3.20498337 5.96691654 3.2055 1 P 0 ;0,1=8,2=0.000000
L 5.96691654 3.2055 5.9696 3.20446683 1 P 0 ;0,1=8,2=0.000000
L 5.9696 3.20446683 5.97151703 3.20188307 1 P 0 ;0,1=8,2=0.000000
L 5.9096 3.8145 5.9096 3.8455 1 P 0 ;0,1=11,2=0.000000
L 5.9096 3.8455 5.89541624 3.82328327 1 P 0 ;0,1=11,2=0.000000
L 5.89541624 3.82328327 5.91458366 3.82328327 1 P 0 ;0,1=11,2=0.000000
A 5.07293996 4.12008002 5.07293996 4.12008002 4.94093996 4.12008002 1 P 0 Y
L 4.70903297 4.1095 4.70903297 4.1405 1 P 0 ;0,1=169,2=0.000000
L 4.70903297 4.1405 4.71899961 4.11466644 1 P 0 ;0,1=169,2=0.000000
L 4.71899961 4.11466644 4.72896693 4.1405 1 P 0 ;0,1=169,2=0.000000
L 4.72896693 4.1405 4.72896693 4.1095 1 P 0 ;0,1=169,2=0.000000
L 4.75766673 4.1095 4.74233317 4.1095 1 P 0 ;0,1=169,2=0.000000
L 4.74233317 4.1095 4.74233317 4.1405 1 P 0 ;0,1=169,2=0.000000
L 4.74233317 4.1405 4.75766673 4.1405 1 P 0 ;0,1=169,2=0.000000
L 4.75153327 4.12551703 4.74233317 4.12551703 1 P 0 ;0,1=169,2=0.000000
L 4.77256663 4.11569961 4.77486614 4.11208278 1 P 0 ;0,1=169,2=0.000000
L 4.77486614 4.11208278 4.77793287 4.11001654 1 P 0 ;0,1=169,2=0.000000
L 4.77793287 4.11001654 4.78138356 4.1095 1 P 0 ;0,1=169,2=0.000000
L 4.78138356 4.1095 4.7844503 4.11001654 1 P 0 ;0,1=169,2=0.000000
L 4.7844503 4.11001654 4.78751703 4.11259931 1 P 0 ;0,1=169,2=0.000000
L 4.78751703 4.11259931 4.78943327 4.11569961 1 P 0 ;0,1=169,2=0.000000
L 4.78943327 4.11569961 4.78981654 4.1187999 1 P 0 ;0,1=169,2=0.000000
L 4.78981654 4.1187999 4.78905 4.12241575 1 P 0 ;0,1=169,2=0.000000
L 4.78905 4.12241575 4.78636654 4.12499951 1 P 0 ;0,1=169,2=0.000000
L 4.78636654 4.12499951 4.78368307 4.12603356 1 P 0 ;0,1=169,2=0.000000
L 4.78368307 4.12603356 4.78023307 4.12603356 1 P 0 ;0,1=169,2=0.000000
L 4.78368307 4.12603356 4.78598327 4.12758317 1 P 0 ;0,1=169,2=0.000000
L 4.78598327 4.12758317 4.7879002 4.13016594 1 P 0 ;0,1=169,2=0.000000
L 4.7879002 4.13016594 4.78866673 4.13326624 1 P 0 ;0,1=169,2=0.000000
L 4.78866673 4.13326624 4.7879002 4.13636654 1 P 0 ;0,1=169,2=0.000000
L 4.7879002 4.13636654 4.78598327 4.13894931 1 P 0 ;0,1=169,2=0.000000
L 4.78598327 4.13894931 4.78253327 4.1405 1 P 0 ;0,1=169,2=0.000000
L 4.78253327 4.1405 4.77908337 4.13998337 1 P 0 ;0,1=169,2=0.000000
L 4.77908337 4.13998337 4.77563337 4.13791624 1 P 0 ;0,1=169,2=0.000000
A 5.07293996 3.09646004 5.07293996 3.09646004 4.94093996 3.09646004 1 P 0 Y
L 4.89403297 3.2445 4.89403297 3.2755 1 P 0 ;0,1=170,2=0.000000
L 4.89403297 3.2755 4.90399961 3.24966644 1 P 0 ;0,1=170,2=0.000000
L 4.90399961 3.24966644 4.91396693 3.2755 1 P 0 ;0,1=170,2=0.000000
L 4.91396693 3.2755 4.91396693 3.2445 1 P 0 ;0,1=170,2=0.000000
L 4.94266673 3.2445 4.92733317 3.2445 1 P 0 ;0,1=170,2=0.000000
L 4.92733317 3.2445 4.92733317 3.2755 1 P 0 ;0,1=170,2=0.000000
L 4.92733317 3.2755 4.94266673 3.2755 1 P 0 ;0,1=170,2=0.000000
L 4.93653327 3.26051703 4.92733317 3.26051703 1 P 0 ;0,1=170,2=0.000000
L 4.9706 3.2445 4.9706 3.2755 1 P 0 ;0,1=170,2=0.000000
L 4.9706 3.2755 4.95641624 3.25328327 1 P 0 ;0,1=170,2=0.000000
L 4.95641624 3.25328327 4.97558366 3.25328327 1 P 0 ;0,1=170,2=0.000000
A 2.69106004 4.12008002 2.69106004 4.12008002 2.55906004 4.12008002 1 P 0 Y
L 2.52903297 3.9345 2.52903297 3.9655 1 P 0 ;0,1=171,2=0.000000
L 2.52903297 3.9655 2.53899961 3.93966644 1 P 0 ;0,1=171,2=0.000000
L 2.53899961 3.93966644 2.54896693 3.9655 1 P 0 ;0,1=171,2=0.000000
L 2.54896693 3.9655 2.54896693 3.9345 1 P 0 ;0,1=171,2=0.000000
L 2.57766673 3.9345 2.56233317 3.9345 1 P 0 ;0,1=171,2=0.000000
L 2.56233317 3.9345 2.56233317 3.9655 1 P 0 ;0,1=171,2=0.000000
L 2.56233317 3.9655 2.57766673 3.9655 1 P 0 ;0,1=171,2=0.000000
L 2.57153327 3.95051703 2.56233317 3.95051703 1 P 0 ;0,1=171,2=0.000000
L 2.60099961 3.9345 2.60099961 3.9655 1 P 0 ;0,1=171,2=0.000000
L 2.60099961 3.9655 2.5963999 3.9593003 1 P 0 ;0,1=171,2=0.000000
L 2.5963999 3.9345 2.60559931 3.9345 1 P 0 ;0,1=171,2=0.000000
A 2.69106004 3.09646004 2.69106004 3.09646004 2.55906004 3.09646004 1 P 0 Y
L 2.52403297 3.2545 2.52403297 3.2855 1 P 0 ;0,1=172,2=0.000000
L 2.52403297 3.2855 2.53399961 3.25966644 1 P 0 ;0,1=172,2=0.000000
L 2.53399961 3.25966644 2.54396693 3.2855 1 P 0 ;0,1=172,2=0.000000
L 2.54396693 3.2855 2.54396693 3.2545 1 P 0 ;0,1=172,2=0.000000
L 2.57266673 3.2545 2.55733317 3.2545 1 P 0 ;0,1=172,2=0.000000
L 2.55733317 3.2545 2.55733317 3.2855 1 P 0 ;0,1=172,2=0.000000
L 2.55733317 3.2855 2.57266673 3.2855 1 P 0 ;0,1=172,2=0.000000
L 2.56653327 3.27051703 2.55733317 3.27051703 1 P 0 ;0,1=172,2=0.000000
L 2.58871644 3.28033346 2.59101663 3.28343278 1 P 0 ;0,1=172,2=0.000000
L 2.59101663 3.28343278 2.5937001 3.28498337 1 P 0 ;0,1=172,2=0.000000
L 2.5937001 3.28498337 2.59676683 3.2855 1 P 0 ;0,1=172,2=0.000000
L 2.59676683 3.2855 2.6006 3.28446683 1 P 0 ;0,1=172,2=0.000000
L 2.6006 3.28446683 2.60328346 3.28188307 1 P 0 ;0,1=172,2=0.000000
L 2.60328346 3.28188307 2.60405 3.27878376 1 P 0 ;0,1=172,2=0.000000
L 2.60405 3.27878376 2.60366673 3.27568258 1 P 0 ;0,1=172,2=0.000000
L 2.60366673 3.27568258 2.60213307 3.2730998 1 P 0 ;0,1=172,2=0.000000
L 2.60213307 3.2730998 2.59446663 3.26793327 1 P 0 ;0,1=172,2=0.000000
L 2.59446663 3.26793327 2.59101663 3.26431644 1 P 0 ;0,1=172,2=0.000000
L 2.59101663 3.26431644 2.58871644 3.25914892 1 P 0 ;0,1=172,2=0.000000
L 2.58871644 3.25914892 2.5879499 3.2545 1 P 0 ;0,1=172,2=0.000000
L 2.5879499 3.2545 2.60405 3.2545 1 P 0 ;0,1=172,2=0.000000
L 0.73813996 2.71233996 0.84081998 2.71233996 1 P 0 
L 0.84081998 2.71233996 0.84081998 2.60966004 1 P 0 
L 0.84081998 2.60966004 0.73813996 2.60966004 1 P 0 
L 0.73813996 2.60966004 0.73813996 2.71233996 1 P 0 
S P 0
OB 0.875 2.75 I
OC 0.875 2.75 0.855006397638 2.750004625984 Y
OE
SE
L 0.8649997 2.5925 0.86686644 2.59291654 1 P 0 ;0,1=16,2=0.000000
L 0.86686644 2.59291654 0.8689998 2.59416624 1 P 0 ;0,1=16,2=0.000000
L 0.8689998 2.59416624 0.87033337 2.59624911 1 P 0 ;0,1=16,2=0.000000
L 0.87033337 2.59624911 0.87086663 2.59916673 1 P 0 ;0,1=16,2=0.000000
L 0.87086663 2.59916673 0.87033337 2.60208278 1 P 0 ;0,1=16,2=0.000000
L 0.87033337 2.60208278 0.86873327 2.60458297 1 P 0 ;0,1=16,2=0.000000
L 0.86873327 2.60458297 0.86633327 2.60583346 1 P 0 ;0,1=16,2=0.000000
L 0.86633327 2.60583346 0.86366663 2.60583346 1 P 0 ;0,1=16,2=0.000000
L 0.86366663 2.60583346 0.86206654 2.60666663 1 P 0 ;0,1=16,2=0.000000
L 0.86206654 2.60666663 0.86073297 2.60874951 1 P 0 ;0,1=16,2=0.000000
L 0.86073297 2.60874951 0.8601998 2.61166634 1 P 0 ;0,1=16,2=0.000000
L 0.8601998 2.61166634 0.8610001 2.61458317 1 P 0 ;0,1=16,2=0.000000
L 0.8610001 2.61458317 0.86286634 2.61666683 1 P 0 ;0,1=16,2=0.000000
L 0.86286634 2.61666683 0.8649997 2.6175 1 P 0 ;0,1=16,2=0.000000
L 0.8649997 2.6175 0.86713307 2.61666683 1 P 0 ;0,1=16,2=0.000000
L 0.86713307 2.61666683 0.8689998 2.61458317 1 P 0 ;0,1=16,2=0.000000
L 0.8689998 2.61458317 0.8698001 2.61166634 1 P 0 ;0,1=16,2=0.000000
L 0.8698001 2.61166634 0.86926644 2.60874951 1 P 0 ;0,1=16,2=0.000000
L 0.86926644 2.60874951 0.86793337 2.60666663 1 P 0 ;0,1=16,2=0.000000
L 0.86793337 2.60666663 0.86633327 2.60583346 1 P 0 ;0,1=16,2=0.000000
L 0.86633327 2.60583346 0.86366663 2.60583346 1 P 0 ;0,1=16,2=0.000000
L 0.86366663 2.60583346 0.86126663 2.60458297 1 P 0 ;0,1=16,2=0.000000
L 0.86126663 2.60458297 0.85966654 2.60208278 1 P 0 ;0,1=16,2=0.000000
L 0.85966654 2.60208278 0.85913327 2.59916673 1 P 0 ;0,1=16,2=0.000000
L 0.85913327 2.59916673 0.85966654 2.59624911 1 P 0 ;0,1=16,2=0.000000
L 0.85966654 2.59624911 0.8610001 2.59416624 1 P 0 ;0,1=16,2=0.000000
L 0.8610001 2.59416624 0.86313346 2.59291654 1 P 0 ;0,1=16,2=0.000000
L 0.86313346 2.59291654 0.8649997 2.5925 1 P 0 ;0,1=16,2=0.000000
L 0.73056663 2.7605 0.73056663 2.73828327 1 P 0 ;0,1=173,2=0.000000
L 0.73056663 2.73828327 0.7320997 2.73363238 1 P 0 ;0,1=173,2=0.000000
L 0.7320997 2.73363238 0.73516634 2.73053307 1 P 0 ;0,1=173,2=0.000000
L 0.73516634 2.73053307 0.73899961 2.7295 1 P 0 ;0,1=173,2=0.000000
L 0.73899961 2.7295 0.74283356 2.73053307 1 P 0 ;0,1=173,2=0.000000
L 0.74283356 2.73053307 0.7459002 2.73363238 1 P 0 ;0,1=173,2=0.000000
L 0.7459002 2.73363238 0.74743327 2.73828327 1 P 0 ;0,1=173,2=0.000000
L 0.74743327 2.73828327 0.74743327 2.7605 1 P 0 ;0,1=173,2=0.000000
L 0.76271644 2.75533346 0.76501663 2.75843278 1 P 0 ;0,1=173,2=0.000000
L 0.76501663 2.75843278 0.7677001 2.75998337 1 P 0 ;0,1=173,2=0.000000
L 0.7677001 2.75998337 0.77076683 2.7605 1 P 0 ;0,1=173,2=0.000000
L 0.77076683 2.7605 0.7746 2.75946683 1 P 0 ;0,1=173,2=0.000000
L 0.7746 2.75946683 0.77728346 2.75688307 1 P 0 ;0,1=173,2=0.000000
L 0.77728346 2.75688307 0.77805 2.75378376 1 P 0 ;0,1=173,2=0.000000
L 0.77805 2.75378376 0.77766673 2.75068258 1 P 0 ;0,1=173,2=0.000000
L 0.77766673 2.75068258 0.77613307 2.7480998 1 P 0 ;0,1=173,2=0.000000
L 0.77613307 2.7480998 0.76846663 2.74293327 1 P 0 ;0,1=173,2=0.000000
L 0.76846663 2.74293327 0.76501663 2.73931644 1 P 0 ;0,1=173,2=0.000000
L 0.76501663 2.73931644 0.76271644 2.73414892 1 P 0 ;0,1=173,2=0.000000
L 0.76271644 2.73414892 0.7619499 2.7295 1 P 0 ;0,1=173,2=0.000000
L 0.7619499 2.7295 0.77805 2.7295 1 P 0 ;0,1=173,2=0.000000
L 0.80099961 2.7295 0.80368307 2.73001654 1 P 0 ;0,1=173,2=0.000000
L 0.80368307 2.73001654 0.8067498 2.73156614 1 P 0 ;0,1=173,2=0.000000
L 0.8067498 2.73156614 0.80866673 2.73414892 1 P 0 ;0,1=173,2=0.000000
L 0.80866673 2.73414892 0.80943327 2.73776673 1 P 0 ;0,1=173,2=0.000000
L 0.80943327 2.73776673 0.80866673 2.74138268 1 P 0 ;0,1=173,2=0.000000
L 0.80866673 2.74138268 0.80636654 2.74448287 1 P 0 ;0,1=173,2=0.000000
L 0.80636654 2.74448287 0.80291654 2.74603356 1 P 0 ;0,1=173,2=0.000000
L 0.80291654 2.74603356 0.79908337 2.74603356 1 P 0 ;0,1=173,2=0.000000
L 0.79908337 2.74603356 0.79678317 2.74706663 1 P 0 ;0,1=173,2=0.000000
L 0.79678317 2.74706663 0.79486614 2.74964941 1 P 0 ;0,1=173,2=0.000000
L 0.79486614 2.74964941 0.7940997 2.75326624 1 P 0 ;0,1=173,2=0.000000
L 0.7940997 2.75326624 0.7952501 2.75688307 1 P 0 ;0,1=173,2=0.000000
L 0.7952501 2.75688307 0.79793287 2.75946683 1 P 0 ;0,1=173,2=0.000000
L 0.79793287 2.75946683 0.80099961 2.7605 1 P 0 ;0,1=173,2=0.000000
L 0.80099961 2.7605 0.80406634 2.75946683 1 P 0 ;0,1=173,2=0.000000
L 0.80406634 2.75946683 0.8067498 2.75688307 1 P 0 ;0,1=173,2=0.000000
L 0.8067498 2.75688307 0.8079002 2.75326624 1 P 0 ;0,1=173,2=0.000000
L 0.8079002 2.75326624 0.80713307 2.74964941 1 P 0 ;0,1=173,2=0.000000
L 0.80713307 2.74964941 0.80521673 2.74706663 1 P 0 ;0,1=173,2=0.000000
L 0.80521673 2.74706663 0.80291654 2.74603356 1 P 0 ;0,1=173,2=0.000000
L 0.80291654 2.74603356 0.79908337 2.74603356 1 P 0 ;0,1=173,2=0.000000
L 0.79908337 2.74603356 0.79563337 2.74448287 1 P 0 ;0,1=173,2=0.000000
L 0.79563337 2.74448287 0.79333317 2.74138268 1 P 0 ;0,1=173,2=0.000000
L 0.79333317 2.74138268 0.79256663 2.73776673 1 P 0 ;0,1=173,2=0.000000
L 0.79256663 2.73776673 0.79333317 2.73414892 1 P 0 ;0,1=173,2=0.000000
L 0.79333317 2.73414892 0.7952501 2.73156614 1 P 0 ;0,1=173,2=0.000000
L 0.7952501 2.73156614 0.79831683 2.73001654 1 P 0 ;0,1=173,2=0.000000
L 0.79831683 2.73001654 0.80099961 2.7295 1 P 0 ;0,1=173,2=0.000000
L 0.70993317 2.75333337 0.71153327 2.75583287 1 P 0 ;0,1=4,2=0.000000
L 0.71153327 2.75583287 0.7134 2.75708337 1 P 0 ;0,1=4,2=0.000000
L 0.7134 2.75708337 0.71553337 2.7575 1 P 0 ;0,1=4,2=0.000000
L 0.71553337 2.7575 0.7182 2.75666683 1 P 0 ;0,1=4,2=0.000000
L 0.7182 2.75666683 0.72006673 2.75458317 1 P 0 ;0,1=4,2=0.000000
L 0.72006673 2.75458317 0.7206 2.75208366 1 P 0 ;0,1=4,2=0.000000
L 0.7206 2.75208366 0.72033337 2.74958268 1 P 0 ;0,1=4,2=0.000000
L 0.72033337 2.74958268 0.71926644 2.7474998 1 P 0 ;0,1=4,2=0.000000
L 0.71926644 2.7474998 0.71393327 2.74333327 1 P 0 ;0,1=4,2=0.000000
L 0.71393327 2.74333327 0.71153327 2.74041644 1 P 0 ;0,1=4,2=0.000000
L 0.71153327 2.74041644 0.70993317 2.73624911 1 P 0 ;0,1=4,2=0.000000
L 0.70993317 2.73624911 0.7093999 2.7325 1 P 0 ;0,1=4,2=0.000000
L 0.7093999 2.7325 0.7206 2.7325 1 P 0 ;0,1=4,2=0.000000
L 0.71694331 2.66311959 0.71854301 2.66020285 1 P 0 ;0,1=10,2=0.000000
L 0.71854301 2.66020285 0.72067638 2.65853652 1 P 0 ;0,1=10,2=0.000000
L 0.72067638 2.65853652 0.72307687 2.65811998 1 P 0 ;0,1=10,2=0.000000
L 0.72307687 2.65811998 0.72521024 2.65853652 1 P 0 ;0,1=10,2=0.000000
L 0.72521024 2.65853652 0.7273436 2.66061939 1 P 0 ;0,1=10,2=0.000000
L 0.7273436 2.66061939 0.72867667 2.66311959 1 P 0 ;0,1=10,2=0.000000
L 0.72867667 2.66311959 0.72894321 2.66561988 1 P 0 ;0,1=10,2=0.000000
L 0.72894321 2.66561988 0.72841004 2.66853593 1 P 0 ;0,1=10,2=0.000000
L 0.72841004 2.66853593 0.72654331 2.67061959 1 P 0 ;0,1=10,2=0.000000
L 0.72654331 2.67061959 0.72467648 2.67145344 1 P 0 ;0,1=10,2=0.000000
L 0.72467648 2.67145344 0.72227657 2.67145344 1 P 0 ;0,1=10,2=0.000000
L 0.72467648 2.67145344 0.72627667 2.67270325 1 P 0 ;0,1=10,2=0.000000
L 0.72627667 2.67270325 0.72761014 2.67478612 1 P 0 ;0,1=10,2=0.000000
L 0.72761014 2.67478612 0.72814341 2.67728632 1 P 0 ;0,1=10,2=0.000000
L 0.72814341 2.67728632 0.72761014 2.67978652 1 P 0 ;0,1=10,2=0.000000
L 0.72761014 2.67978652 0.72627667 2.68186939 1 P 0 ;0,1=10,2=0.000000
L 0.72627667 2.68186939 0.72387667 2.68311998 1 P 0 ;0,1=10,2=0.000000
L 0.72387667 2.68311998 0.72147667 2.68270335 1 P 0 ;0,1=10,2=0.000000
L 0.72147667 2.68270335 0.71907667 2.68103632 1 P 0 ;0,1=10,2=0.000000
L 0.71434331 2.61564911 0.71594301 2.61356624 1 P 0 ;0,1=20,2=0.000000
L 0.71594301 2.61356624 0.71780974 2.61231654 1 P 0 ;0,1=20,2=0.000000
L 0.71780974 2.61231654 0.72020974 2.6119 1 P 0 ;0,1=20,2=0.000000
L 0.72020974 2.6119 0.72261024 2.61273307 1 P 0 ;0,1=20,2=0.000000
L 0.72261024 2.61273307 0.72447648 2.61439941 1 P 0 ;0,1=20,2=0.000000
L 0.72447648 2.61439941 0.72581004 2.61731624 1 P 0 ;0,1=20,2=0.000000
L 0.72581004 2.61731624 0.72607667 2.62064961 1 P 0 ;0,1=20,2=0.000000
L 0.72607667 2.62064961 0.72554341 2.62398297 1 P 0 ;0,1=20,2=0.000000
L 0.72554341 2.62398297 0.72420984 2.62606663 1 P 0 ;0,1=20,2=0.000000
L 0.72420984 2.62606663 0.72234311 2.62773297 1 P 0 ;0,1=20,2=0.000000
L 0.72234311 2.62773297 0.72047687 2.62814951 1 P 0 ;0,1=20,2=0.000000
L 0.72047687 2.62814951 0.71861004 2.62773297 1 P 0 ;0,1=20,2=0.000000
L 0.71861004 2.62773297 0.71621014 2.62606663 1 P 0 ;0,1=20,2=0.000000
L 0.71621014 2.62606663 0.71700994 2.6369 1 P 0 ;0,1=20,2=0.000000
L 0.71700994 2.6369 0.72420984 2.6369 1 P 0 ;0,1=20,2=0.000000
L 0.72493317 2.58791594 0.7267999 2.59083346 1 P 0 ;0,1=8,2=0.000000
L 0.7267999 2.59083346 0.7284 2.5924998 1 P 0 ;0,1=8,2=0.000000
L 0.7284 2.5924998 0.73053337 2.59333297 1 P 0 ;0,1=8,2=0.000000
L 0.73053337 2.59333297 0.7324002 2.5924998 1 P 0 ;0,1=8,2=0.000000
L 0.7324002 2.5924998 0.73373327 2.59083346 1 P 0 ;0,1=8,2=0.000000
L 0.73373327 2.59083346 0.7348001 2.58833327 1 P 0 ;0,1=8,2=0.000000
L 0.7348001 2.58833327 0.73506673 2.58541644 1 P 0 ;0,1=8,2=0.000000
L 0.73506673 2.58541644 0.7348001 2.58291624 1 P 0 ;0,1=8,2=0.000000
L 0.7348001 2.58291624 0.73373327 2.58041604 1 P 0 ;0,1=8,2=0.000000
L 0.73373327 2.58041604 0.73213307 2.57833307 1 P 0 ;0,1=8,2=0.000000
L 0.73213307 2.57833307 0.73026683 2.5775 1 P 0 ;0,1=8,2=0.000000
L 0.73026683 2.5775 0.72813346 2.57833307 1 P 0 ;0,1=8,2=0.000000
L 0.72813346 2.57833307 0.72626663 2.58083258 1 P 0 ;0,1=8,2=0.000000
L 0.72626663 2.58083258 0.7251998 2.58458327 1 P 0 ;0,1=8,2=0.000000
L 0.7251998 2.58458327 0.72493317 2.5887498 1 P 0 ;0,1=8,2=0.000000
L 0.72493317 2.5887498 0.72546634 2.59416614 1 P 0 ;0,1=8,2=0.000000
L 0.72546634 2.59416614 0.72626663 2.59708366 1 P 0 ;0,1=8,2=0.000000
L 0.72626663 2.59708366 0.7275997 2.5999997 1 P 0 ;0,1=8,2=0.000000
L 0.7275997 2.5999997 0.72946654 2.60208337 1 P 0 ;0,1=8,2=0.000000
L 0.72946654 2.60208337 0.73133327 2.6025 1 P 0 ;0,1=8,2=0.000000
L 0.73133327 2.6025 0.7332 2.60166683 1 P 0 ;0,1=8,2=0.000000
L 0.7332 2.60166683 0.73453356 2.59958317 1 P 0 ;0,1=8,2=0.000000
L 3.30498002 2.42653996 3.47501998 2.42653996 1 P 0 
L 3.30498002 2.20146004 3.30498002 2.42653996 1 P 0 
L 3.47501998 2.42653996 3.47501998 2.20146004 1 P 0 
L 3.47501998 2.20146004 3.30498002 2.20146004 1 P 0 
S P 0
OB 3.52 2.435 I
OC 3.52 2.435 3.5 2.435 Y
OE
SE
L 3.48393317 2.40333337 3.48553327 2.40583287 1 P 0 ;0,1=140,2=0.000000
L 3.48553327 2.40583287 3.4874 2.40708337 1 P 0 ;0,1=140,2=0.000000
L 3.4874 2.40708337 3.48953337 2.4075 1 P 0 ;0,1=140,2=0.000000
L 3.48953337 2.4075 3.4922 2.40666683 1 P 0 ;0,1=140,2=0.000000
L 3.4922 2.40666683 3.49406673 2.40458317 1 P 0 ;0,1=140,2=0.000000
L 3.49406673 2.40458317 3.4946 2.40208366 1 P 0 ;0,1=140,2=0.000000
L 3.4946 2.40208366 3.49433337 2.39958268 1 P 0 ;0,1=140,2=0.000000
L 3.49433337 2.39958268 3.49326644 2.3974998 1 P 0 ;0,1=140,2=0.000000
L 3.49326644 2.3974998 3.48793327 2.39333327 1 P 0 ;0,1=140,2=0.000000
L 3.48793327 2.39333327 3.48553327 2.39041644 1 P 0 ;0,1=140,2=0.000000
L 3.48553327 2.39041644 3.48393317 2.38624911 1 P 0 ;0,1=140,2=0.000000
L 3.48393317 2.38624911 3.4833999 2.3825 1 P 0 ;0,1=140,2=0.000000
L 3.4833999 2.3825 3.4946 2.3825 1 P 0 ;0,1=140,2=0.000000
L 3.5109997 2.3825 3.51286644 2.38291654 1 P 0 ;0,1=140,2=0.000000
L 3.51286644 2.38291654 3.5149998 2.38416624 1 P 0 ;0,1=140,2=0.000000
L 3.5149998 2.38416624 3.51633337 2.38624911 1 P 0 ;0,1=140,2=0.000000
L 3.51633337 2.38624911 3.51686663 2.38916673 1 P 0 ;0,1=140,2=0.000000
L 3.51686663 2.38916673 3.51633337 2.39208278 1 P 0 ;0,1=140,2=0.000000
L 3.51633337 2.39208278 3.51473327 2.39458297 1 P 0 ;0,1=140,2=0.000000
L 3.51473327 2.39458297 3.51233327 2.39583346 1 P 0 ;0,1=140,2=0.000000
L 3.51233327 2.39583346 3.50966663 2.39583346 1 P 0 ;0,1=140,2=0.000000
L 3.50966663 2.39583346 3.50806654 2.39666663 1 P 0 ;0,1=140,2=0.000000
L 3.50806654 2.39666663 3.50673297 2.39874951 1 P 0 ;0,1=140,2=0.000000
L 3.50673297 2.39874951 3.5061998 2.40166634 1 P 0 ;0,1=140,2=0.000000
L 3.5061998 2.40166634 3.5070001 2.40458317 1 P 0 ;0,1=140,2=0.000000
L 3.5070001 2.40458317 3.50886634 2.40666683 1 P 0 ;0,1=140,2=0.000000
L 3.50886634 2.40666683 3.5109997 2.4075 1 P 0 ;0,1=140,2=0.000000
L 3.5109997 2.4075 3.51313307 2.40666683 1 P 0 ;0,1=140,2=0.000000
L 3.51313307 2.40666683 3.5149998 2.40458317 1 P 0 ;0,1=140,2=0.000000
L 3.5149998 2.40458317 3.5158001 2.40166634 1 P 0 ;0,1=140,2=0.000000
L 3.5158001 2.40166634 3.51526644 2.39874951 1 P 0 ;0,1=140,2=0.000000
L 3.51526644 2.39874951 3.51393337 2.39666663 1 P 0 ;0,1=140,2=0.000000
L 3.51393337 2.39666663 3.51233327 2.39583346 1 P 0 ;0,1=140,2=0.000000
L 3.51233327 2.39583346 3.50966663 2.39583346 1 P 0 ;0,1=140,2=0.000000
L 3.50966663 2.39583346 3.50726663 2.39458297 1 P 0 ;0,1=140,2=0.000000
L 3.50726663 2.39458297 3.50566654 2.39208278 1 P 0 ;0,1=140,2=0.000000
L 3.50566654 2.39208278 3.50513327 2.38916673 1 P 0 ;0,1=140,2=0.000000
L 3.50513327 2.38916673 3.50566654 2.38624911 1 P 0 ;0,1=140,2=0.000000
L 3.50566654 2.38624911 3.5070001 2.38416624 1 P 0 ;0,1=140,2=0.000000
L 3.5070001 2.38416624 3.50913346 2.38291654 1 P 0 ;0,1=140,2=0.000000
L 3.50913346 2.38291654 3.5109997 2.3825 1 P 0 ;0,1=140,2=0.000000
L 3.48795315 2.24625335 3.48955325 2.24875285 1 P 0 ;0,1=174,2=0.000000
L 3.48955325 2.24875285 3.49141998 2.25000335 1 P 0 ;0,1=174,2=0.000000
L 3.49141998 2.25000335 3.49355335 2.25041998 1 P 0 ;0,1=174,2=0.000000
L 3.49355335 2.25041998 3.49621998 2.24958681 1 P 0 ;0,1=174,2=0.000000
L 3.49621998 2.24958681 3.49808671 2.24750315 1 P 0 ;0,1=174,2=0.000000
L 3.49808671 2.24750315 3.49861998 2.24500364 1 P 0 ;0,1=174,2=0.000000
L 3.49861998 2.24500364 3.49835335 2.24250266 1 P 0 ;0,1=174,2=0.000000
L 3.49835335 2.24250266 3.49728642 2.24041978 1 P 0 ;0,1=174,2=0.000000
L 3.49728642 2.24041978 3.49195325 2.23625325 1 P 0 ;0,1=174,2=0.000000
L 3.49195325 2.23625325 3.48955325 2.23333642 1 P 0 ;0,1=174,2=0.000000
L 3.48955325 2.23333642 3.48795315 2.22916909 1 P 0 ;0,1=174,2=0.000000
L 3.48795315 2.22916909 3.48741988 2.22541998 1 P 0 ;0,1=174,2=0.000000
L 3.48741988 2.22541998 3.49861998 2.22541998 1 P 0 ;0,1=174,2=0.000000
L 3.51501969 2.25041998 3.51288632 2.24958681 1 P 0 ;0,1=174,2=0.000000
L 3.51288632 2.24958681 3.51128661 2.24750315 1 P 0 ;0,1=174,2=0.000000
L 3.51128661 2.24750315 3.51021978 2.24500364 1 P 0 ;0,1=174,2=0.000000
L 3.51021978 2.24500364 3.50941988 2.24166949 1 P 0 ;0,1=174,2=0.000000
L 3.50941988 2.24166949 3.50915325 2.23791959 1 P 0 ;0,1=174,2=0.000000
L 3.50915325 2.23791959 3.50941988 2.23416959 1 P 0 ;0,1=174,2=0.000000
L 3.50941988 2.23416959 3.51021978 2.23083622 1 P 0 ;0,1=174,2=0.000000
L 3.51021978 2.23083622 3.51128661 2.22833602 1 P 0 ;0,1=174,2=0.000000
L 3.51128661 2.22833602 3.51288632 2.22625305 1 P 0 ;0,1=174,2=0.000000
L 3.51288632 2.22625305 3.51501969 2.22541998 1 P 0 ;0,1=174,2=0.000000
L 3.51501969 2.22541998 3.51715305 2.22625305 1 P 0 ;0,1=174,2=0.000000
L 3.51715305 2.22625305 3.51875325 2.22833602 1 P 0 ;0,1=174,2=0.000000
L 3.51875325 2.22833602 3.51982008 2.23083622 1 P 0 ;0,1=174,2=0.000000
L 3.51982008 2.23083622 3.52061998 2.23416959 1 P 0 ;0,1=174,2=0.000000
L 3.52061998 2.23416959 3.52088661 2.23791959 1 P 0 ;0,1=174,2=0.000000
L 3.52088661 2.23791959 3.52061998 2.24166949 1 P 0 ;0,1=174,2=0.000000
L 3.52061998 2.24166949 3.51982008 2.24500364 1 P 0 ;0,1=174,2=0.000000
L 3.51982008 2.24500364 3.51875325 2.24750315 1 P 0 ;0,1=174,2=0.000000
L 3.51875325 2.24750315 3.51715305 2.24958681 1 P 0 ;0,1=174,2=0.000000
L 3.51715305 2.24958681 3.51501969 2.25041998 1 P 0 ;0,1=174,2=0.000000
L 3.34816329 2.44128907 3.34976299 2.4392062 1 P 0 ;0,1=20,2=0.000000
L 3.34976299 2.4392062 3.35162972 2.4379565 1 P 0 ;0,1=20,2=0.000000
L 3.35162972 2.4379565 3.35402972 2.43753996 1 P 0 ;0,1=20,2=0.000000
L 3.35402972 2.43753996 3.35643022 2.43837303 1 P 0 ;0,1=20,2=0.000000
L 3.35643022 2.43837303 3.35829646 2.44003937 1 P 0 ;0,1=20,2=0.000000
L 3.35829646 2.44003937 3.35963002 2.4429562 1 P 0 ;0,1=20,2=0.000000
L 3.35963002 2.4429562 3.35989665 2.44628957 1 P 0 ;0,1=20,2=0.000000
L 3.35989665 2.44628957 3.35936339 2.44962293 1 P 0 ;0,1=20,2=0.000000
L 3.35936339 2.44962293 3.35802982 2.45170659 1 P 0 ;0,1=20,2=0.000000
L 3.35802982 2.45170659 3.35616309 2.45337293 1 P 0 ;0,1=20,2=0.000000
L 3.35616309 2.45337293 3.35429685 2.45378947 1 P 0 ;0,1=20,2=0.000000
L 3.35429685 2.45378947 3.35243002 2.45337293 1 P 0 ;0,1=20,2=0.000000
L 3.35243002 2.45337293 3.35003012 2.45170659 1 P 0 ;0,1=20,2=0.000000
L 3.35003012 2.45170659 3.35082992 2.46253996 1 P 0 ;0,1=20,2=0.000000
L 3.35082992 2.46253996 3.35802982 2.46253996 1 P 0 ;0,1=20,2=0.000000
L 3.41714321 2.46105335 3.41874331 2.46355285 1 P 0 ;0,1=4,2=0.000000
L 3.41874331 2.46355285 3.42061004 2.46480335 1 P 0 ;0,1=4,2=0.000000
L 3.42061004 2.46480335 3.42274341 2.46521998 1 P 0 ;0,1=4,2=0.000000
L 3.42274341 2.46521998 3.42541004 2.46438681 1 P 0 ;0,1=4,2=0.000000
L 3.42541004 2.46438681 3.42727677 2.46230315 1 P 0 ;0,1=4,2=0.000000
L 3.42727677 2.46230315 3.42781004 2.45980364 1 P 0 ;0,1=4,2=0.000000
L 3.42781004 2.45980364 3.42754341 2.45730266 1 P 0 ;0,1=4,2=0.000000
L 3.42754341 2.45730266 3.42647648 2.45521978 1 P 0 ;0,1=4,2=0.000000
L 3.42647648 2.45521978 3.42114331 2.45105325 1 P 0 ;0,1=4,2=0.000000
L 3.42114331 2.45105325 3.41874331 2.44813642 1 P 0 ;0,1=4,2=0.000000
L 3.41874331 2.44813642 3.41714321 2.44396909 1 P 0 ;0,1=4,2=0.000000
L 3.41714321 2.44396909 3.41660994 2.44021998 1 P 0 ;0,1=4,2=0.000000
L 3.41660994 2.44021998 3.42781004 2.44021998 1 P 0 ;0,1=4,2=0.000000
L 3.27815315 2.40495591 3.28001988 2.40787343 1 P 0 ;0,1=8,2=0.000000
L 3.28001988 2.40787343 3.28161998 2.40953976 1 P 0 ;0,1=8,2=0.000000
L 3.28161998 2.40953976 3.28375335 2.41037293 1 P 0 ;0,1=8,2=0.000000
L 3.28375335 2.41037293 3.28562018 2.40953976 1 P 0 ;0,1=8,2=0.000000
L 3.28562018 2.40953976 3.28695325 2.40787343 1 P 0 ;0,1=8,2=0.000000
L 3.28695325 2.40787343 3.28802008 2.40537323 1 P 0 ;0,1=8,2=0.000000
L 3.28802008 2.40537323 3.28828671 2.4024564 1 P 0 ;0,1=8,2=0.000000
L 3.28828671 2.4024564 3.28802008 2.3999562 1 P 0 ;0,1=8,2=0.000000
L 3.28802008 2.3999562 3.28695325 2.397456 1 P 0 ;0,1=8,2=0.000000
L 3.28695325 2.397456 3.28535305 2.39537303 1 P 0 ;0,1=8,2=0.000000
L 3.28535305 2.39537303 3.28348681 2.39453996 1 P 0 ;0,1=8,2=0.000000
L 3.28348681 2.39453996 3.28135344 2.39537303 1 P 0 ;0,1=8,2=0.000000
L 3.28135344 2.39537303 3.27948661 2.39787254 1 P 0 ;0,1=8,2=0.000000
L 3.27948661 2.39787254 3.27841978 2.40162323 1 P 0 ;0,1=8,2=0.000000
L 3.27841978 2.40162323 3.27815315 2.40578976 1 P 0 ;0,1=8,2=0.000000
L 3.27815315 2.40578976 3.27868632 2.4112061 1 P 0 ;0,1=8,2=0.000000
L 3.27868632 2.4112061 3.27948661 2.41412362 1 P 0 ;0,1=8,2=0.000000
L 3.27948661 2.41412362 3.28081969 2.41703967 1 P 0 ;0,1=8,2=0.000000
L 3.28081969 2.41703967 3.28268652 2.41912333 1 P 0 ;0,1=8,2=0.000000
L 3.28268652 2.41912333 3.28455325 2.41953996 1 P 0 ;0,1=8,2=0.000000
L 3.28455325 2.41953996 3.28641998 2.41870679 1 P 0 ;0,1=8,2=0.000000
L 3.28641998 2.41870679 3.28775354 2.41662313 1 P 0 ;0,1=8,2=0.000000
L 3.2689997 2.2225 3.2689997 2.2475 1 P 0 ;0,1=144,2=0.000000
L 3.2689997 2.2475 3.2657999 2.2425003 1 P 0 ;0,1=144,2=0.000000
L 3.2657999 2.2225 3.27219951 2.2225 1 P 0 ;0,1=144,2=0.000000
L 3.28513327 2.22624911 3.28673297 2.22416624 1 P 0 ;0,1=144,2=0.000000
L 3.28673297 2.22416624 3.2885997 2.22291654 1 P 0 ;0,1=144,2=0.000000
L 3.2885997 2.22291654 3.2909997 2.2225 1 P 0 ;0,1=144,2=0.000000
L 3.2909997 2.2225 3.2934002 2.22333307 1 P 0 ;0,1=144,2=0.000000
L 3.2934002 2.22333307 3.29526644 2.22499941 1 P 0 ;0,1=144,2=0.000000
L 3.29526644 2.22499941 3.2966 2.22791624 1 P 0 ;0,1=144,2=0.000000
L 3.2966 2.22791624 3.29686663 2.23124961 1 P 0 ;0,1=144,2=0.000000
L 3.29686663 2.23124961 3.29633337 2.23458297 1 P 0 ;0,1=144,2=0.000000
L 3.29633337 2.23458297 3.2949998 2.23666663 1 P 0 ;0,1=144,2=0.000000
L 3.2949998 2.23666663 3.29313307 2.23833297 1 P 0 ;0,1=144,2=0.000000
L 3.29313307 2.23833297 3.29126683 2.23874951 1 P 0 ;0,1=144,2=0.000000
L 3.29126683 2.23874951 3.2894 2.23833297 1 P 0 ;0,1=144,2=0.000000
L 3.2894 2.23833297 3.2870001 2.23666663 1 P 0 ;0,1=144,2=0.000000
L 3.2870001 2.23666663 3.2877999 2.2475 1 P 0 ;0,1=144,2=0.000000
L 3.2877999 2.2475 3.2949998 2.2475 1 P 0 ;0,1=144,2=0.000000
L 3.2545 2.27056663 3.27671673 2.27056663 1 P 0 ;0,1=175,2=270.000000
L 3.27671673 2.27056663 3.28136762 2.2720997 1 P 0 ;0,1=175,2=270.000000
L 3.28136762 2.2720997 3.28446693 2.27516634 1 P 0 ;0,1=175,2=270.000000
L 3.28446693 2.27516634 3.2855 2.27899961 1 P 0 ;0,1=175,2=270.000000
L 3.2855 2.27899961 3.28446693 2.28283356 1 P 0 ;0,1=175,2=270.000000
L 3.28446693 2.28283356 3.28136762 2.2859002 1 P 0 ;0,1=175,2=270.000000
L 3.28136762 2.2859002 3.27671673 2.28743327 1 P 0 ;0,1=175,2=270.000000
L 3.27671673 2.28743327 3.2545 2.28743327 1 P 0 ;0,1=175,2=270.000000
L 3.25966654 2.30271644 3.25656722 2.30501663 1 P 0 ;0,1=175,2=270.000000
L 3.25656722 2.30501663 3.25501663 2.3077001 1 P 0 ;0,1=175,2=270.000000
L 3.25501663 2.3077001 3.2545 2.31076683 1 P 0 ;0,1=175,2=270.000000
L 3.2545 2.31076683 3.25553317 2.3146 1 P 0 ;0,1=175,2=270.000000
L 3.25553317 2.3146 3.25811693 2.31728346 1 P 0 ;0,1=175,2=270.000000
L 3.25811693 2.31728346 3.26121624 2.31805 1 P 0 ;0,1=175,2=270.000000
L 3.26121624 2.31805 3.26431742 2.31766673 1 P 0 ;0,1=175,2=270.000000
L 3.26431742 2.31766673 3.2669002 2.31613307 1 P 0 ;0,1=175,2=270.000000
L 3.2669002 2.31613307 3.27206673 2.30846663 1 P 0 ;0,1=175,2=270.000000
L 3.27206673 2.30846663 3.27568356 2.30501663 1 P 0 ;0,1=175,2=270.000000
L 3.27568356 2.30501663 3.28085108 2.30271644 1 P 0 ;0,1=175,2=270.000000
L 3.28085108 2.30271644 3.2855 2.3019499 1 P 0 ;0,1=175,2=270.000000
L 3.2855 2.3019499 3.2855 2.31805 1 P 0 ;0,1=175,2=270.000000
L 3.28188415 2.33448287 3.28446693 2.33716634 1 P 0 ;0,1=175,2=270.000000
L 3.28446693 2.33716634 3.2855 2.34023307 1 P 0 ;0,1=175,2=270.000000
L 3.2855 2.34023307 3.28446693 2.3432998 1 P 0 ;0,1=175,2=270.000000
L 3.28446693 2.3432998 3.28136762 2.34598327 1 P 0 ;0,1=175,2=270.000000
L 3.28136762 2.34598327 3.27671673 2.3479002 1 P 0 ;0,1=175,2=270.000000
L 3.27671673 2.3479002 3.27206673 2.34866673 1 P 0 ;0,1=175,2=270.000000
L 3.27206673 2.34866673 3.26638366 2.34866673 1 P 0 ;0,1=175,2=270.000000
L 3.26638366 2.34866673 3.26173376 2.3479002 1 P 0 ;0,1=175,2=270.000000
L 3.26173376 2.3479002 3.2576003 2.34598327 1 P 0 ;0,1=175,2=270.000000
L 3.2576003 2.34598327 3.25553317 2.34368307 1 P 0 ;0,1=175,2=270.000000
L 3.25553317 2.34368307 3.2545 2.34099961 1 P 0 ;0,1=175,2=270.000000
L 3.2545 2.34099961 3.25553317 2.33793287 1 P 0 ;0,1=175,2=270.000000
L 3.25553317 2.33793287 3.2576003 2.33563337 1 P 0 ;0,1=175,2=270.000000
L 3.2576003 2.33563337 3.2606997 2.3340997 1 P 0 ;0,1=175,2=270.000000
L 3.2606997 2.3340997 3.26483406 2.33333317 1 P 0 ;0,1=175,2=270.000000
L 3.26483406 2.33333317 3.2684499 2.3340997 1 P 0 ;0,1=175,2=270.000000
L 3.2684499 2.3340997 3.27206673 2.33601663 1 P 0 ;0,1=175,2=270.000000
L 3.27206673 2.33601663 3.27413396 2.33831683 1 P 0 ;0,1=175,2=270.000000
L 3.27413396 2.33831683 3.27465049 2.34099961 1 P 0 ;0,1=175,2=270.000000
L 3.27465049 2.34099961 3.27361732 2.34406634 1 P 0 ;0,1=175,2=270.000000
L 3.27361732 2.34406634 3.27103366 2.34636654 1 P 0 ;0,1=175,2=270.000000
L 3.27103366 2.34636654 3.26638366 2.34866673 1 P 0 ;0,1=175,2=270.000000
L 3.593 1.442 3.593 1.498 1 P 0 
L 3.697 1.442 3.593 1.442 1 P 0 
L 3.593 1.498 3.697 1.498 1 P 0 
L 3.697 1.498 3.697 1.442 1 P 0 
L 3.60133317 1.4305 3.60133317 1.3995 1 P 0 ;0,1=176,2=0.000000
L 3.60133317 1.3995 3.61666673 1.3995 1 P 0 ;0,1=176,2=0.000000
L 3.63156663 1.40569961 3.63386614 1.40208278 1 P 0 ;0,1=176,2=0.000000
L 3.63386614 1.40208278 3.63693287 1.40001654 1 P 0 ;0,1=176,2=0.000000
L 3.63693287 1.40001654 3.64038356 1.3995 1 P 0 ;0,1=176,2=0.000000
L 3.64038356 1.3995 3.6434503 1.40001654 1 P 0 ;0,1=176,2=0.000000
L 3.6434503 1.40001654 3.64651703 1.40259931 1 P 0 ;0,1=176,2=0.000000
L 3.64651703 1.40259931 3.64843327 1.40569961 1 P 0 ;0,1=176,2=0.000000
L 3.64843327 1.40569961 3.64881654 1.4087999 1 P 0 ;0,1=176,2=0.000000
L 3.64881654 1.4087999 3.64805 1.41241575 1 P 0 ;0,1=176,2=0.000000
L 3.64805 1.41241575 3.64536654 1.41499951 1 P 0 ;0,1=176,2=0.000000
L 3.64536654 1.41499951 3.64268307 1.41603356 1 P 0 ;0,1=176,2=0.000000
L 3.64268307 1.41603356 3.63923307 1.41603356 1 P 0 ;0,1=176,2=0.000000
L 3.64268307 1.41603356 3.64498327 1.41758317 1 P 0 ;0,1=176,2=0.000000
L 3.64498327 1.41758317 3.6469002 1.42016594 1 P 0 ;0,1=176,2=0.000000
L 3.6469002 1.42016594 3.64766673 1.42326624 1 P 0 ;0,1=176,2=0.000000
L 3.64766673 1.42326624 3.6469002 1.42636654 1 P 0 ;0,1=176,2=0.000000
L 3.6469002 1.42636654 3.64498327 1.42894931 1 P 0 ;0,1=176,2=0.000000
L 3.64498327 1.42894931 3.64153327 1.4305 1 P 0 ;0,1=176,2=0.000000
L 3.64153327 1.4305 3.63808337 1.42998337 1 P 0 ;0,1=176,2=0.000000
L 3.63808337 1.42998337 3.63463337 1.42791624 1 P 0 ;0,1=176,2=0.000000
L 3.6756 1.3995 3.6756 1.4305 1 P 0 ;0,1=176,2=0.000000
L 3.6756 1.4305 3.66141624 1.40828327 1 P 0 ;0,1=176,2=0.000000
L 3.66141624 1.40828327 3.68058366 1.40828327 1 P 0 ;0,1=176,2=0.000000
L 1.732 3.212 1.788 3.212 1 P 0 
L 1.788 3.212 1.788 3.108 1 P 0 
L 1.788 3.108 1.732 3.108 1 P 0 
L 1.732 3.108 1.732 3.212 1 P 0 
L 1.8945 3.17133317 1.9255 3.17133317 1 P 0 ;0,1=177,2=270.000000
L 1.9255 3.17133317 1.9255 3.18666673 1 P 0 ;0,1=177,2=270.000000
L 1.89966654 3.20271644 1.89656722 3.20501663 1 P 0 ;0,1=177,2=270.000000
L 1.89656722 3.20501663 1.89501663 3.2077001 1 P 0 ;0,1=177,2=270.000000
L 1.89501663 3.2077001 1.8945 3.21076683 1 P 0 ;0,1=177,2=270.000000
L 1.8945 3.21076683 1.89553317 3.2146 1 P 0 ;0,1=177,2=270.000000
L 1.89553317 3.2146 1.89811693 3.21728346 1 P 0 ;0,1=177,2=270.000000
L 1.89811693 3.21728346 1.90121624 3.21805 1 P 0 ;0,1=177,2=270.000000
L 1.90121624 3.21805 1.90431742 3.21766673 1 P 0 ;0,1=177,2=270.000000
L 1.90431742 3.21766673 1.9069002 3.21613307 1 P 0 ;0,1=177,2=270.000000
L 1.9069002 3.21613307 1.91206673 3.20846663 1 P 0 ;0,1=177,2=270.000000
L 1.91206673 3.20846663 1.91568356 3.20501663 1 P 0 ;0,1=177,2=270.000000
L 1.91568356 3.20501663 1.92085108 3.20271644 1 P 0 ;0,1=177,2=270.000000
L 1.92085108 3.20271644 1.9255 3.2019499 1 P 0 ;0,1=177,2=270.000000
L 1.9255 3.2019499 1.9255 3.21805 1 P 0 ;0,1=177,2=270.000000
L 1.91930039 3.23256663 1.92291722 3.23486614 1 P 0 ;0,1=177,2=270.000000
L 1.92291722 3.23486614 1.92498346 3.23793287 1 P 0 ;0,1=177,2=270.000000
L 1.92498346 3.23793287 1.9255 3.24138356 1 P 0 ;0,1=177,2=270.000000
L 1.9255 3.24138356 1.92498346 3.2444503 1 P 0 ;0,1=177,2=270.000000
L 1.92498346 3.2444503 1.92240069 3.24751703 1 P 0 ;0,1=177,2=270.000000
L 1.92240069 3.24751703 1.91930039 3.24943327 1 P 0 ;0,1=177,2=270.000000
L 1.91930039 3.24943327 1.9162001 3.24981654 1 P 0 ;0,1=177,2=270.000000
L 1.9162001 3.24981654 1.91258425 3.24905 1 P 0 ;0,1=177,2=270.000000
L 1.91258425 3.24905 1.91000049 3.24636654 1 P 0 ;0,1=177,2=270.000000
L 1.91000049 3.24636654 1.90896644 3.24368307 1 P 0 ;0,1=177,2=270.000000
L 1.90896644 3.24368307 1.90896644 3.24023307 1 P 0 ;0,1=177,2=270.000000
L 1.90896644 3.24368307 1.90741683 3.24598327 1 P 0 ;0,1=177,2=270.000000
L 1.90741683 3.24598327 1.90483406 3.2479002 1 P 0 ;0,1=177,2=270.000000
L 1.90483406 3.2479002 1.90173376 3.24866673 1 P 0 ;0,1=177,2=270.000000
L 1.90173376 3.24866673 1.89863346 3.2479002 1 P 0 ;0,1=177,2=270.000000
L 1.89863346 3.2479002 1.89605069 3.24598327 1 P 0 ;0,1=177,2=270.000000
L 1.89605069 3.24598327 1.8945 3.24253327 1 P 0 ;0,1=177,2=270.000000
L 1.8945 3.24253327 1.89501663 3.23908337 1 P 0 ;0,1=177,2=270.000000
L 1.89501663 3.23908337 1.89708376 3.23563337 1 P 0 ;0,1=177,2=270.000000
L 1.427 3.217 1.483 3.217 1 P 0 
L 1.483 3.217 1.483 3.113 1 P 0 
L 1.483 3.113 1.427 3.113 1 P 0 
L 1.427 3.113 1.427 3.217 1 P 0 
L 1.4395 3.23133317 1.4705 3.23133317 1 P 0 ;0,1=178,2=270.000000
L 1.4705 3.23133317 1.4705 3.24666673 1 P 0 ;0,1=178,2=270.000000
L 1.44466654 3.26271644 1.44156722 3.26501663 1 P 0 ;0,1=178,2=270.000000
L 1.44156722 3.26501663 1.44001663 3.2677001 1 P 0 ;0,1=178,2=270.000000
L 1.44001663 3.2677001 1.4395 3.27076683 1 P 0 ;0,1=178,2=270.000000
L 1.4395 3.27076683 1.44053317 3.2746 1 P 0 ;0,1=178,2=270.000000
L 1.44053317 3.2746 1.44311693 3.27728346 1 P 0 ;0,1=178,2=270.000000
L 1.44311693 3.27728346 1.44621624 3.27805 1 P 0 ;0,1=178,2=270.000000
L 1.44621624 3.27805 1.44931742 3.27766673 1 P 0 ;0,1=178,2=270.000000
L 1.44931742 3.27766673 1.4519002 3.27613307 1 P 0 ;0,1=178,2=270.000000
L 1.4519002 3.27613307 1.45706673 3.26846663 1 P 0 ;0,1=178,2=270.000000
L 1.45706673 3.26846663 1.46068356 3.26501663 1 P 0 ;0,1=178,2=270.000000
L 1.46068356 3.26501663 1.46585108 3.26271644 1 P 0 ;0,1=178,2=270.000000
L 1.46585108 3.26271644 1.4705 3.2619499 1 P 0 ;0,1=178,2=270.000000
L 1.4705 3.2619499 1.4705 3.27805 1 P 0 ;0,1=178,2=270.000000
L 1.4705 3.3056 1.4395 3.3056 1 P 0 ;0,1=178,2=270.000000
L 1.4395 3.3056 1.46171673 3.29141624 1 P 0 ;0,1=178,2=270.000000
L 1.46171673 3.29141624 1.46171673 3.31058366 1 P 0 ;0,1=178,2=270.000000
L 5.262 1.753 5.262 1.697 1 P 0 
L 5.158 1.753 5.262 1.753 1 P 0 
L 5.262 1.697 5.158 1.697 1 P 0 
L 5.158 1.697 5.158 1.753 1 P 0 
L 5.17133317 1.7905 5.17133317 1.7595 1 P 0 ;0,1=179,2=0.000000
L 5.17133317 1.7595 5.18666673 1.7595 1 P 0 ;0,1=179,2=0.000000
L 5.20999961 1.7595 5.20999961 1.7905 1 P 0 ;0,1=179,2=0.000000
L 5.20999961 1.7905 5.2053999 1.7843003 1 P 0 ;0,1=179,2=0.000000
L 5.2053999 1.7595 5.21459931 1.7595 1 P 0 ;0,1=179,2=0.000000
L 5.23371644 1.78533346 5.23601663 1.78843278 1 P 0 ;0,1=179,2=0.000000
L 5.23601663 1.78843278 5.2387001 1.78998337 1 P 0 ;0,1=179,2=0.000000
L 5.2387001 1.78998337 5.24176683 1.7905 1 P 0 ;0,1=179,2=0.000000
L 5.24176683 1.7905 5.2456 1.78946683 1 P 0 ;0,1=179,2=0.000000
L 5.2456 1.78946683 5.24828346 1.78688307 1 P 0 ;0,1=179,2=0.000000
L 5.24828346 1.78688307 5.24905 1.78378376 1 P 0 ;0,1=179,2=0.000000
L 5.24905 1.78378376 5.24866673 1.78068258 1 P 0 ;0,1=179,2=0.000000
L 5.24866673 1.78068258 5.24713307 1.7780998 1 P 0 ;0,1=179,2=0.000000
L 5.24713307 1.7780998 5.23946663 1.77293327 1 P 0 ;0,1=179,2=0.000000
L 5.23946663 1.77293327 5.23601663 1.76931644 1 P 0 ;0,1=179,2=0.000000
L 5.23601663 1.76931644 5.23371644 1.76414892 1 P 0 ;0,1=179,2=0.000000
L 5.23371644 1.76414892 5.2329499 1.7595 1 P 0 ;0,1=179,2=0.000000
L 5.2329499 1.7595 5.24905 1.7595 1 P 0 ;0,1=179,2=0.000000
L 5.092 3.932 5.148 3.932 1 P 0 
L 5.092 3.828 5.092 3.932 1 P 0 
L 5.148 3.932 5.148 3.828 1 P 0 
L 5.148 3.828 5.092 3.828 1 P 0 
L 5.1295 3.94633317 5.1605 3.94633317 1 P 0 ;0,1=180,2=270.000000
L 5.1605 3.94633317 5.1605 3.96166673 1 P 0 ;0,1=180,2=270.000000
L 5.1605 3.98499961 5.1295 3.98499961 1 P 0 ;0,1=180,2=270.000000
L 5.1295 3.98499961 5.1356997 3.9803999 1 P 0 ;0,1=180,2=270.000000
L 5.1605 3.9803999 5.1605 3.98959931 1 P 0 ;0,1=180,2=270.000000
L 5.15585108 4.00756663 5.15843386 4.00986614 1 P 0 ;0,1=180,2=270.000000
L 5.15843386 4.00986614 5.15998346 4.01254961 1 P 0 ;0,1=180,2=270.000000
L 5.15998346 4.01254961 5.1605 4.01599961 1 P 0 ;0,1=180,2=270.000000
L 5.1605 4.01599961 5.15946693 4.0194503 1 P 0 ;0,1=180,2=270.000000
L 5.15946693 4.0194503 5.15740069 4.02213307 1 P 0 ;0,1=180,2=270.000000
L 5.15740069 4.02213307 5.15378386 4.02405 1 P 0 ;0,1=180,2=270.000000
L 5.15378386 4.02405 5.14965049 4.02443327 1 P 0 ;0,1=180,2=270.000000
L 5.14965049 4.02443327 5.14551713 4.02366673 1 P 0 ;0,1=180,2=270.000000
L 5.14551713 4.02366673 5.14293337 4.0217498 1 P 0 ;0,1=180,2=270.000000
L 5.14293337 4.0217498 5.14086713 4.01906634 1 P 0 ;0,1=180,2=270.000000
L 5.14086713 4.01906634 5.14035059 4.01638356 1 P 0 ;0,1=180,2=270.000000
L 5.14035059 4.01638356 5.14086713 4.0137001 1 P 0 ;0,1=180,2=270.000000
L 5.14086713 4.0137001 5.14293337 4.0102501 1 P 0 ;0,1=180,2=270.000000
L 5.14293337 4.0102501 5.1295 4.0113999 1 P 0 ;0,1=180,2=270.000000
L 5.1295 4.0113999 5.1295 4.0217498 1 P 0 ;0,1=180,2=270.000000
L 4.677 3.832 4.573 3.832 1 P 0 
L 4.573 3.832 4.573 3.888 1 P 0 
L 4.573 3.888 4.677 3.888 1 P 0 
L 4.677 3.888 4.677 3.832 1 P 0 
L 4.58633317 3.8205 4.58633317 3.7895 1 P 0 ;0,1=181,2=0.000000
L 4.58633317 3.7895 4.60166673 3.7895 1 P 0 ;0,1=181,2=0.000000
L 4.62499961 3.7895 4.62499961 3.8205 1 P 0 ;0,1=181,2=0.000000
L 4.62499961 3.8205 4.6203999 3.8143003 1 P 0 ;0,1=181,2=0.000000
L 4.6203999 3.7895 4.62959931 3.7895 1 P 0 ;0,1=181,2=0.000000
L 4.64871644 3.80241575 4.6513999 3.80603356 1 P 0 ;0,1=181,2=0.000000
L 4.6513999 3.80603356 4.6537001 3.8080998 1 P 0 ;0,1=181,2=0.000000
L 4.6537001 3.8080998 4.65676683 3.80913287 1 P 0 ;0,1=181,2=0.000000
L 4.65676683 3.80913287 4.6594503 3.8080998 1 P 0 ;0,1=181,2=0.000000
L 4.6594503 3.8080998 4.66136654 3.80603356 1 P 0 ;0,1=181,2=0.000000
L 4.66136654 3.80603356 4.6629002 3.80293327 1 P 0 ;0,1=181,2=0.000000
L 4.6629002 3.80293327 4.66328346 3.79931644 1 P 0 ;0,1=181,2=0.000000
L 4.66328346 3.79931644 4.6629002 3.79621614 1 P 0 ;0,1=181,2=0.000000
L 4.6629002 3.79621614 4.66136654 3.79311585 1 P 0 ;0,1=181,2=0.000000
L 4.66136654 3.79311585 4.65906634 3.79053307 1 P 0 ;0,1=181,2=0.000000
L 4.65906634 3.79053307 4.65638356 3.7895 1 P 0 ;0,1=181,2=0.000000
L 4.65638356 3.7895 4.65331683 3.79053307 1 P 0 ;0,1=181,2=0.000000
L 4.65331683 3.79053307 4.65063337 3.79363238 1 P 0 ;0,1=181,2=0.000000
L 4.65063337 3.79363238 4.6490997 3.79828327 1 P 0 ;0,1=181,2=0.000000
L 4.6490997 3.79828327 4.64871644 3.8034498 1 P 0 ;0,1=181,2=0.000000
L 4.64871644 3.8034498 4.64948287 3.81016594 1 P 0 ;0,1=181,2=0.000000
L 4.64948287 3.81016594 4.65063337 3.81378376 1 P 0 ;0,1=181,2=0.000000
L 4.65063337 3.81378376 4.65254961 3.8173997 1 P 0 ;0,1=181,2=0.000000
L 4.65254961 3.8173997 4.65523307 3.81998337 1 P 0 ;0,1=181,2=0.000000
L 4.65523307 3.81998337 4.65791654 3.8205 1 P 0 ;0,1=181,2=0.000000
L 4.65791654 3.8205 4.6606 3.81946683 1 P 0 ;0,1=181,2=0.000000
L 4.6606 3.81946683 4.66251703 3.81688307 1 P 0 ;0,1=181,2=0.000000
L 3.707 2.233 3.707 2.177 1 P 0 
L 3.707 2.177 3.603 2.177 1 P 0 
L 3.603 2.177 3.603 2.233 1 P 0 
L 3.603 2.233 3.707 2.233 1 P 0 
L 3.61633317 2.1705 3.61633317 2.1395 1 P 0 ;0,1=182,2=0.000000
L 3.61633317 2.1395 3.63166673 2.1395 1 P 0 ;0,1=182,2=0.000000
L 3.64656663 2.14569961 3.64886614 2.14208278 1 P 0 ;0,1=182,2=0.000000
L 3.64886614 2.14208278 3.65193287 2.14001654 1 P 0 ;0,1=182,2=0.000000
L 3.65193287 2.14001654 3.65538356 2.1395 1 P 0 ;0,1=182,2=0.000000
L 3.65538356 2.1395 3.6584503 2.14001654 1 P 0 ;0,1=182,2=0.000000
L 3.6584503 2.14001654 3.66151703 2.14259931 1 P 0 ;0,1=182,2=0.000000
L 3.66151703 2.14259931 3.66343327 2.14569961 1 P 0 ;0,1=182,2=0.000000
L 3.66343327 2.14569961 3.66381654 2.1487999 1 P 0 ;0,1=182,2=0.000000
L 3.66381654 2.1487999 3.66305 2.15241575 1 P 0 ;0,1=182,2=0.000000
L 3.66305 2.15241575 3.66036654 2.15499951 1 P 0 ;0,1=182,2=0.000000
L 3.66036654 2.15499951 3.65768307 2.15603356 1 P 0 ;0,1=182,2=0.000000
L 3.65768307 2.15603356 3.65423307 2.15603356 1 P 0 ;0,1=182,2=0.000000
L 3.65768307 2.15603356 3.65998327 2.15758317 1 P 0 ;0,1=182,2=0.000000
L 3.65998327 2.15758317 3.6619002 2.16016594 1 P 0 ;0,1=182,2=0.000000
L 3.6619002 2.16016594 3.66266673 2.16326624 1 P 0 ;0,1=182,2=0.000000
L 3.66266673 2.16326624 3.6619002 2.16636654 1 P 0 ;0,1=182,2=0.000000
L 3.6619002 2.16636654 3.65998327 2.16894931 1 P 0 ;0,1=182,2=0.000000
L 3.65998327 2.16894931 3.65653327 2.1705 1 P 0 ;0,1=182,2=0.000000
L 3.65653327 2.1705 3.65308337 2.16998337 1 P 0 ;0,1=182,2=0.000000
L 3.65308337 2.16998337 3.64963337 2.16791624 1 P 0 ;0,1=182,2=0.000000
L 3.67756663 2.14569961 3.67986614 2.14208278 1 P 0 ;0,1=182,2=0.000000
L 3.67986614 2.14208278 3.68293287 2.14001654 1 P 0 ;0,1=182,2=0.000000
L 3.68293287 2.14001654 3.68638356 2.1395 1 P 0 ;0,1=182,2=0.000000
L 3.68638356 2.1395 3.6894503 2.14001654 1 P 0 ;0,1=182,2=0.000000
L 3.6894503 2.14001654 3.69251703 2.14259931 1 P 0 ;0,1=182,2=0.000000
L 3.69251703 2.14259931 3.69443327 2.14569961 1 P 0 ;0,1=182,2=0.000000
L 3.69443327 2.14569961 3.69481654 2.1487999 1 P 0 ;0,1=182,2=0.000000
L 3.69481654 2.1487999 3.69405 2.15241575 1 P 0 ;0,1=182,2=0.000000
L 3.69405 2.15241575 3.69136654 2.15499951 1 P 0 ;0,1=182,2=0.000000
L 3.69136654 2.15499951 3.68868307 2.15603356 1 P 0 ;0,1=182,2=0.000000
L 3.68868307 2.15603356 3.68523307 2.15603356 1 P 0 ;0,1=182,2=0.000000
L 3.68868307 2.15603356 3.69098327 2.15758317 1 P 0 ;0,1=182,2=0.000000
L 3.69098327 2.15758317 3.6929002 2.16016594 1 P 0 ;0,1=182,2=0.000000
L 3.6929002 2.16016594 3.69366673 2.16326624 1 P 0 ;0,1=182,2=0.000000
L 3.69366673 2.16326624 3.6929002 2.16636654 1 P 0 ;0,1=182,2=0.000000
L 3.6929002 2.16636654 3.69098327 2.16894931 1 P 0 ;0,1=182,2=0.000000
L 3.69098327 2.16894931 3.68753327 2.1705 1 P 0 ;0,1=182,2=0.000000
L 3.68753327 2.1705 3.68408337 2.16998337 1 P 0 ;0,1=182,2=0.000000
L 3.68408337 2.16998337 3.68063337 2.16791624 1 P 0 ;0,1=182,2=0.000000
L 1.613 3.804 1.613 3.748 1 P 0 
L 1.509 3.804 1.613 3.804 1 P 0 
L 1.613 3.748 1.509 3.748 1 P 0 
L 1.509 3.748 1.509 3.804 1 P 0 
L 1.55683317 3.7355 1.55683317 3.7045 1 P 0 ;0,1=183,2=0.000000
L 1.55683317 3.7045 1.57216673 3.7045 1 P 0 ;0,1=183,2=0.000000
L 1.59473307 3.7045 1.59549961 3.71121614 1 P 0 ;0,1=183,2=0.000000
L 1.59549961 3.71121614 1.5966501 3.71689921 1 P 0 ;0,1=183,2=0.000000
L 1.5966501 3.71689921 1.59818307 3.72206663 1 P 0 ;0,1=183,2=0.000000
L 1.59818307 3.72206663 1.6001 3.7277497 1 P 0 ;0,1=183,2=0.000000
L 1.6001 3.7277497 1.60316673 3.7355 1 P 0 ;0,1=183,2=0.000000
L 1.60316673 3.7355 1.58783317 3.7355 1 P 0 ;0,1=183,2=0.000000
L 3.49 4.23 3.49 4.174 1 P 0 
L 3.49 4.174 3.386 4.174 1 P 0 
L 3.386 4.174 3.386 4.23 1 P 0 
L 3.386 4.23 3.49 4.23 1 P 0 
L 3.40683317 4.2705 3.40683317 4.2395 1 P 0 ;0,1=184,2=0.000000
L 3.40683317 4.2395 3.42216673 4.2395 1 P 0 ;0,1=184,2=0.000000
L 3.44549961 4.2395 3.44818307 4.24001654 1 P 0 ;0,1=184,2=0.000000
L 3.44818307 4.24001654 3.4512498 4.24156614 1 P 0 ;0,1=184,2=0.000000
L 3.4512498 4.24156614 3.45316673 4.24414892 1 P 0 ;0,1=184,2=0.000000
L 3.45316673 4.24414892 3.45393327 4.24776673 1 P 0 ;0,1=184,2=0.000000
L 3.45393327 4.24776673 3.45316673 4.25138268 1 P 0 ;0,1=184,2=0.000000
L 3.45316673 4.25138268 3.45086654 4.25448287 1 P 0 ;0,1=184,2=0.000000
L 3.45086654 4.25448287 3.44741654 4.25603356 1 P 0 ;0,1=184,2=0.000000
L 3.44741654 4.25603356 3.44358337 4.25603356 1 P 0 ;0,1=184,2=0.000000
L 3.44358337 4.25603356 3.44128317 4.25706663 1 P 0 ;0,1=184,2=0.000000
L 3.44128317 4.25706663 3.43936614 4.25964941 1 P 0 ;0,1=184,2=0.000000
L 3.43936614 4.25964941 3.4385997 4.26326624 1 P 0 ;0,1=184,2=0.000000
L 3.4385997 4.26326624 3.4397501 4.26688307 1 P 0 ;0,1=184,2=0.000000
L 3.4397501 4.26688307 3.44243287 4.26946683 1 P 0 ;0,1=184,2=0.000000
L 3.44243287 4.26946683 3.44549961 4.2705 1 P 0 ;0,1=184,2=0.000000
L 3.44549961 4.2705 3.44856634 4.26946683 1 P 0 ;0,1=184,2=0.000000
L 3.44856634 4.26946683 3.4512498 4.26688307 1 P 0 ;0,1=184,2=0.000000
L 3.4512498 4.26688307 3.4524002 4.26326624 1 P 0 ;0,1=184,2=0.000000
L 3.4524002 4.26326624 3.45163307 4.25964941 1 P 0 ;0,1=184,2=0.000000
L 3.45163307 4.25964941 3.44971673 4.25706663 1 P 0 ;0,1=184,2=0.000000
L 3.44971673 4.25706663 3.44741654 4.25603356 1 P 0 ;0,1=184,2=0.000000
L 3.44741654 4.25603356 3.44358337 4.25603356 1 P 0 ;0,1=184,2=0.000000
L 3.44358337 4.25603356 3.44013337 4.25448287 1 P 0 ;0,1=184,2=0.000000
L 3.44013337 4.25448287 3.43783317 4.25138268 1 P 0 ;0,1=184,2=0.000000
L 3.43783317 4.25138268 3.43706663 4.24776673 1 P 0 ;0,1=184,2=0.000000
L 3.43706663 4.24776673 3.43783317 4.24414892 1 P 0 ;0,1=184,2=0.000000
L 3.43783317 4.24414892 3.4397501 4.24156614 1 P 0 ;0,1=184,2=0.000000
L 3.4397501 4.24156614 3.44281683 4.24001654 1 P 0 ;0,1=184,2=0.000000
L 3.44281683 4.24001654 3.44549961 4.2395 1 P 0 ;0,1=184,2=0.000000
L 5.423 2.308 5.423 2.204 1 P 0 
L 5.423 2.204 5.367 2.204 1 P 0 
L 5.367 2.204 5.367 2.308 1 P 0 
L 5.367 2.308 5.423 2.308 1 P 0 
L 5.2695 2.25683317 5.3005 2.25683317 1 P 0 ;0,1=185,2=270.000000
L 5.3005 2.25683317 5.3005 2.27216673 1 P 0 ;0,1=185,2=270.000000
L 5.29688415 2.28898287 5.29946693 2.29166634 1 P 0 ;0,1=185,2=270.000000
L 5.29946693 2.29166634 5.3005 2.29473307 1 P 0 ;0,1=185,2=270.000000
L 5.3005 2.29473307 5.29946693 2.2977998 1 P 0 ;0,1=185,2=270.000000
L 5.29946693 2.2977998 5.29636762 2.30048327 1 P 0 ;0,1=185,2=270.000000
L 5.29636762 2.30048327 5.29171673 2.3024002 1 P 0 ;0,1=185,2=270.000000
L 5.29171673 2.3024002 5.28706673 2.30316673 1 P 0 ;0,1=185,2=270.000000
L 5.28706673 2.30316673 5.28138366 2.30316673 1 P 0 ;0,1=185,2=270.000000
L 5.28138366 2.30316673 5.27673376 2.3024002 1 P 0 ;0,1=185,2=270.000000
L 5.27673376 2.3024002 5.2726003 2.30048327 1 P 0 ;0,1=185,2=270.000000
L 5.2726003 2.30048327 5.27053317 2.29818307 1 P 0 ;0,1=185,2=270.000000
L 5.27053317 2.29818307 5.2695 2.29549961 1 P 0 ;0,1=185,2=270.000000
L 5.2695 2.29549961 5.27053317 2.29243287 1 P 0 ;0,1=185,2=270.000000
L 5.27053317 2.29243287 5.2726003 2.29013337 1 P 0 ;0,1=185,2=270.000000
L 5.2726003 2.29013337 5.2756997 2.2885997 1 P 0 ;0,1=185,2=270.000000
L 5.2756997 2.2885997 5.27983406 2.28783317 1 P 0 ;0,1=185,2=270.000000
L 5.27983406 2.28783317 5.2834499 2.2885997 1 P 0 ;0,1=185,2=270.000000
L 5.2834499 2.2885997 5.28706673 2.29051663 1 P 0 ;0,1=185,2=270.000000
L 5.28706673 2.29051663 5.28913396 2.29281683 1 P 0 ;0,1=185,2=270.000000
L 5.28913396 2.29281683 5.28965049 2.29549961 1 P 0 ;0,1=185,2=270.000000
L 5.28965049 2.29549961 5.28861732 2.29856634 1 P 0 ;0,1=185,2=270.000000
L 5.28861732 2.29856634 5.28603366 2.30086654 1 P 0 ;0,1=185,2=270.000000
L 5.28603366 2.30086654 5.28138366 2.30316673 1 P 0 ;0,1=185,2=270.000000
L 0.543 3.924 0.599 3.924 1 P 0 
L 0.543 3.82 0.543 3.924 1 P 0 
L 0.599 3.924 0.599 3.82 1 P 0 
L 0.599 3.82 0.543 3.82 1 P 0 
L 0.5045 3.83133317 0.5355 3.83133317 1 P 0 ;0,1=186,2=270.000000
L 0.5355 3.83133317 0.5355 3.84666673 1 P 0 ;0,1=186,2=270.000000
L 0.50966654 3.86271644 0.50656722 3.86501663 1 P 0 ;0,1=186,2=270.000000
L 0.50656722 3.86501663 0.50501663 3.8677001 1 P 0 ;0,1=186,2=270.000000
L 0.50501663 3.8677001 0.5045 3.87076683 1 P 0 ;0,1=186,2=270.000000
L 0.5045 3.87076683 0.50553317 3.8746 1 P 0 ;0,1=186,2=270.000000
L 0.50553317 3.8746 0.50811693 3.87728346 1 P 0 ;0,1=186,2=270.000000
L 0.50811693 3.87728346 0.51121624 3.87805 1 P 0 ;0,1=186,2=270.000000
L 0.51121624 3.87805 0.51431742 3.87766673 1 P 0 ;0,1=186,2=270.000000
L 0.51431742 3.87766673 0.5169002 3.87613307 1 P 0 ;0,1=186,2=270.000000
L 0.5169002 3.87613307 0.52206673 3.86846663 1 P 0 ;0,1=186,2=270.000000
L 0.52206673 3.86846663 0.52568356 3.86501663 1 P 0 ;0,1=186,2=270.000000
L 0.52568356 3.86501663 0.53085108 3.86271644 1 P 0 ;0,1=186,2=270.000000
L 0.53085108 3.86271644 0.5355 3.8619499 1 P 0 ;0,1=186,2=270.000000
L 0.5355 3.8619499 0.5355 3.87805 1 P 0 ;0,1=186,2=270.000000
L 0.5045 3.90099961 0.50553317 3.89793287 1 P 0 ;0,1=186,2=270.000000
L 0.50553317 3.89793287 0.50811693 3.89563337 1 P 0 ;0,1=186,2=270.000000
L 0.50811693 3.89563337 0.51121624 3.8940997 1 P 0 ;0,1=186,2=270.000000
L 0.51121624 3.8940997 0.51535059 3.8929499 1 P 0 ;0,1=186,2=270.000000
L 0.51535059 3.8929499 0.52000049 3.89256663 1 P 0 ;0,1=186,2=270.000000
L 0.52000049 3.89256663 0.52465049 3.8929499 1 P 0 ;0,1=186,2=270.000000
L 0.52465049 3.8929499 0.52878386 3.8940997 1 P 0 ;0,1=186,2=270.000000
L 0.52878386 3.8940997 0.53188415 3.89563337 1 P 0 ;0,1=186,2=270.000000
L 0.53188415 3.89563337 0.53446693 3.89793287 1 P 0 ;0,1=186,2=270.000000
L 0.53446693 3.89793287 0.5355 3.90099961 1 P 0 ;0,1=186,2=270.000000
L 0.5355 3.90099961 0.53446693 3.90406634 1 P 0 ;0,1=186,2=270.000000
L 0.53446693 3.90406634 0.53188415 3.90636654 1 P 0 ;0,1=186,2=270.000000
L 0.53188415 3.90636654 0.52878386 3.9079002 1 P 0 ;0,1=186,2=270.000000
L 0.52878386 3.9079002 0.52465049 3.90905 1 P 0 ;0,1=186,2=270.000000
L 0.52465049 3.90905 0.52000049 3.90943327 1 P 0 ;0,1=186,2=270.000000
L 0.52000049 3.90943327 0.51535059 3.90905 1 P 0 ;0,1=186,2=270.000000
L 0.51535059 3.90905 0.51121624 3.9079002 1 P 0 ;0,1=186,2=270.000000
L 0.51121624 3.9079002 0.50811693 3.90636654 1 P 0 ;0,1=186,2=270.000000
L 0.50811693 3.90636654 0.50553317 3.90406634 1 P 0 ;0,1=186,2=270.000000
L 0.50553317 3.90406634 0.5045 3.90099961 1 P 0 ;0,1=186,2=270.000000
L 4.905 2.545 4.961 2.545 1 P 0 
L 4.905 2.441 4.905 2.545 1 P 0 
L 4.961 2.545 4.961 2.441 1 P 0 
L 4.961 2.441 4.905 2.441 1 P 0 
L 4.8595 2.46683317 4.8905 2.46683317 1 P 0 ;0,1=187,2=270.000000
L 4.8905 2.46683317 4.8905 2.48216673 1 P 0 ;0,1=187,2=270.000000
L 4.87758425 2.49821644 4.87396644 2.5008999 1 P 0 ;0,1=187,2=270.000000
L 4.87396644 2.5008999 4.8719002 2.5032001 1 P 0 ;0,1=187,2=270.000000
L 4.8719002 2.5032001 4.87086713 2.50626683 1 P 0 ;0,1=187,2=270.000000
L 4.87086713 2.50626683 4.8719002 2.5089503 1 P 0 ;0,1=187,2=270.000000
L 4.8719002 2.5089503 4.87396644 2.51086654 1 P 0 ;0,1=187,2=270.000000
L 4.87396644 2.51086654 4.87706673 2.5124002 1 P 0 ;0,1=187,2=270.000000
L 4.87706673 2.5124002 4.88068356 2.51278346 1 P 0 ;0,1=187,2=270.000000
L 4.88068356 2.51278346 4.88378386 2.5124002 1 P 0 ;0,1=187,2=270.000000
L 4.88378386 2.5124002 4.88688415 2.51086654 1 P 0 ;0,1=187,2=270.000000
L 4.88688415 2.51086654 4.88946693 2.50856634 1 P 0 ;0,1=187,2=270.000000
L 4.88946693 2.50856634 4.8905 2.50588356 1 P 0 ;0,1=187,2=270.000000
L 4.8905 2.50588356 4.88946693 2.50281683 1 P 0 ;0,1=187,2=270.000000
L 4.88946693 2.50281683 4.88636762 2.50013337 1 P 0 ;0,1=187,2=270.000000
L 4.88636762 2.50013337 4.88171673 2.4985997 1 P 0 ;0,1=187,2=270.000000
L 4.88171673 2.4985997 4.8765502 2.49821644 1 P 0 ;0,1=187,2=270.000000
L 4.8765502 2.49821644 4.86983406 2.49898287 1 P 0 ;0,1=187,2=270.000000
L 4.86983406 2.49898287 4.86621624 2.50013337 1 P 0 ;0,1=187,2=270.000000
L 4.86621624 2.50013337 4.8626003 2.50204961 1 P 0 ;0,1=187,2=270.000000
L 4.8626003 2.50204961 4.86001663 2.50473307 1 P 0 ;0,1=187,2=270.000000
L 4.86001663 2.50473307 4.8595 2.50741654 1 P 0 ;0,1=187,2=270.000000
L 4.8595 2.50741654 4.86053317 2.5101 1 P 0 ;0,1=187,2=270.000000
L 4.86053317 2.5101 4.86311693 2.51201703 1 P 0 ;0,1=187,2=270.000000
L 5.672 1.012 5.728 1.012 1 P 0 
L 5.728 1.012 5.728 0.908 1 P 0 
L 5.728 0.908 5.672 0.908 1 P 0 
L 5.672 0.908 5.672 1.012 1 P 0 
L 5.6795 1.03633317 5.7105 1.03633317 1 P 0 ;0,1=188,2=270.000000
L 5.7105 1.03633317 5.7105 1.05166673 1 P 0 ;0,1=188,2=270.000000
L 5.7105 1.07499961 5.6795 1.07499961 1 P 0 ;0,1=188,2=270.000000
L 5.6795 1.07499961 5.6856997 1.0703999 1 P 0 ;0,1=188,2=270.000000
L 5.7105 1.0703999 5.7105 1.07959931 1 P 0 ;0,1=188,2=270.000000
L 5.70430039 1.09756663 5.70791722 1.09986614 1 P 0 ;0,1=188,2=270.000000
L 5.70791722 1.09986614 5.70998346 1.10293287 1 P 0 ;0,1=188,2=270.000000
L 5.70998346 1.10293287 5.7105 1.10638356 1 P 0 ;0,1=188,2=270.000000
L 5.7105 1.10638356 5.70998346 1.1094503 1 P 0 ;0,1=188,2=270.000000
L 5.70998346 1.1094503 5.70740069 1.11251703 1 P 0 ;0,1=188,2=270.000000
L 5.70740069 1.11251703 5.70430039 1.11443327 1 P 0 ;0,1=188,2=270.000000
L 5.70430039 1.11443327 5.7012001 1.11481654 1 P 0 ;0,1=188,2=270.000000
L 5.7012001 1.11481654 5.69758425 1.11405 1 P 0 ;0,1=188,2=270.000000
L 5.69758425 1.11405 5.69500049 1.11136654 1 P 0 ;0,1=188,2=270.000000
L 5.69500049 1.11136654 5.69396644 1.10868307 1 P 0 ;0,1=188,2=270.000000
L 5.69396644 1.10868307 5.69396644 1.10523307 1 P 0 ;0,1=188,2=270.000000
L 5.69396644 1.10868307 5.69241683 1.11098327 1 P 0 ;0,1=188,2=270.000000
L 5.69241683 1.11098327 5.68983406 1.1129002 1 P 0 ;0,1=188,2=270.000000
L 5.68983406 1.1129002 5.68673376 1.11366673 1 P 0 ;0,1=188,2=270.000000
L 5.68673376 1.11366673 5.68363346 1.1129002 1 P 0 ;0,1=188,2=270.000000
L 5.68363346 1.1129002 5.68105069 1.11098327 1 P 0 ;0,1=188,2=270.000000
L 5.68105069 1.11098327 5.6795 1.10753327 1 P 0 ;0,1=188,2=270.000000
L 5.6795 1.10753327 5.68001663 1.10408337 1 P 0 ;0,1=188,2=270.000000
L 5.68001663 1.10408337 5.68208376 1.10063337 1 P 0 ;0,1=188,2=270.000000
L 3.733 3.127 3.733 3.071 1 P 0 
L 3.629 3.127 3.733 3.127 1 P 0 
L 3.733 3.071 3.629 3.071 1 P 0 
L 3.629 3.071 3.629 3.127 1 P 0 
L 3.52633317 3.1255 3.52633317 3.0945 1 P 0 ;0,1=189,2=0.000000
L 3.52633317 3.0945 3.54166673 3.0945 1 P 0 ;0,1=189,2=0.000000
L 3.56499961 3.0945 3.56499961 3.1255 1 P 0 ;0,1=189,2=0.000000
L 3.56499961 3.1255 3.5603999 3.1193003 1 P 0 ;0,1=189,2=0.000000
L 3.5603999 3.0945 3.56959931 3.0945 1 P 0 ;0,1=189,2=0.000000
L 3.59599961 3.0945 3.59599961 3.1255 1 P 0 ;0,1=189,2=0.000000
L 3.59599961 3.1255 3.5913999 3.1193003 1 P 0 ;0,1=189,2=0.000000
L 3.5913999 3.0945 3.60059931 3.0945 1 P 0 ;0,1=189,2=0.000000
L 0.9255 3.667 0.9255 4.15 1 P 0 
L 0.9255 4.15 0.6405 4.15 1 P 0 
L 0.6405 3.667 0.9255 3.667 1 P 0 
L 0.6405 4.15 0.6405 3.667 1 P 0 
L 0.91771644 3.65033346 0.92001663 3.65343278 1 P 0 ;0,1=4,2=0.000000
L 0.92001663 3.65343278 0.9227001 3.65498337 1 P 0 ;0,1=4,2=0.000000
L 0.9227001 3.65498337 0.92576683 3.6555 1 P 0 ;0,1=4,2=0.000000
L 0.92576683 3.6555 0.9296 3.65446683 1 P 0 ;0,1=4,2=0.000000
L 0.9296 3.65446683 0.93228346 3.65188307 1 P 0 ;0,1=4,2=0.000000
L 0.93228346 3.65188307 0.93305 3.64878376 1 P 0 ;0,1=4,2=0.000000
L 0.93305 3.64878376 0.93266673 3.64568258 1 P 0 ;0,1=4,2=0.000000
L 0.93266673 3.64568258 0.93113307 3.6430998 1 P 0 ;0,1=4,2=0.000000
L 0.93113307 3.6430998 0.92346663 3.63793327 1 P 0 ;0,1=4,2=0.000000
L 0.92346663 3.63793327 0.92001663 3.63431644 1 P 0 ;0,1=4,2=0.000000
L 0.92001663 3.63431644 0.91771644 3.62914892 1 P 0 ;0,1=4,2=0.000000
L 0.91771644 3.62914892 0.9169499 3.6245 1 P 0 ;0,1=4,2=0.000000
L 0.9169499 3.6245 0.93305 3.6245 1 P 0 ;0,1=4,2=0.000000
L 0.76756663 4.16769961 0.76986614 4.16408278 1 P 0 ;0,1=10,2=0.000000
L 0.76986614 4.16408278 0.77293287 4.16201654 1 P 0 ;0,1=10,2=0.000000
L 0.77293287 4.16201654 0.77638356 4.1615 1 P 0 ;0,1=10,2=0.000000
L 0.77638356 4.1615 0.7794503 4.16201654 1 P 0 ;0,1=10,2=0.000000
L 0.7794503 4.16201654 0.78251703 4.16459931 1 P 0 ;0,1=10,2=0.000000
L 0.78251703 4.16459931 0.78443327 4.16769961 1 P 0 ;0,1=10,2=0.000000
L 0.78443327 4.16769961 0.78481654 4.1707999 1 P 0 ;0,1=10,2=0.000000
L 0.78481654 4.1707999 0.78405 4.17441575 1 P 0 ;0,1=10,2=0.000000
L 0.78405 4.17441575 0.78136654 4.17699951 1 P 0 ;0,1=10,2=0.000000
L 0.78136654 4.17699951 0.77868307 4.17803356 1 P 0 ;0,1=10,2=0.000000
L 0.77868307 4.17803356 0.77523307 4.17803356 1 P 0 ;0,1=10,2=0.000000
L 0.77868307 4.17803356 0.78098327 4.17958317 1 P 0 ;0,1=10,2=0.000000
L 0.78098327 4.17958317 0.7829002 4.18216594 1 P 0 ;0,1=10,2=0.000000
L 0.7829002 4.18216594 0.78366673 4.18526624 1 P 0 ;0,1=10,2=0.000000
L 0.78366673 4.18526624 0.7829002 4.18836654 1 P 0 ;0,1=10,2=0.000000
L 0.7829002 4.18836654 0.78098327 4.19094931 1 P 0 ;0,1=10,2=0.000000
L 0.78098327 4.19094931 0.77753327 4.1925 1 P 0 ;0,1=10,2=0.000000
L 0.77753327 4.1925 0.77408337 4.19198337 1 P 0 ;0,1=10,2=0.000000
L 0.77408337 4.19198337 0.77063337 4.18991624 1 P 0 ;0,1=10,2=0.000000
L 0.72693327 3.63291624 0.72463307 3.63446683 1 P 0 ;0,1=190,2=0.000000
L 0.72463307 3.63446683 0.7219503 3.6355 1 P 0 ;0,1=190,2=0.000000
L 0.7219503 3.6355 0.71888356 3.6355 1 P 0 ;0,1=190,2=0.000000
L 0.71888356 3.6355 0.71543287 3.63394931 1 P 0 ;0,1=190,2=0.000000
L 0.71543287 3.63394931 0.7127501 3.63136654 1 P 0 ;0,1=190,2=0.000000
L 0.7127501 3.63136654 0.71083317 3.62826624 1 P 0 ;0,1=190,2=0.000000
L 0.71083317 3.62826624 0.70929951 3.6230998 1 P 0 ;0,1=190,2=0.000000
L 0.70929951 3.6230998 0.70891624 3.6184498 1 P 0 ;0,1=190,2=0.000000
L 0.70891624 3.6184498 0.70968337 3.6137999 1 P 0 ;0,1=190,2=0.000000
L 0.70968337 3.6137999 0.71083317 3.61069961 1 P 0 ;0,1=190,2=0.000000
L 0.71083317 3.61069961 0.71313337 3.60759931 1 P 0 ;0,1=190,2=0.000000
L 0.71313337 3.60759931 0.71581683 3.60553307 1 P 0 ;0,1=190,2=0.000000
L 0.71581683 3.60553307 0.71849961 3.6045 1 P 0 ;0,1=190,2=0.000000
L 0.71849961 3.6045 0.72118307 3.6045 1 P 0 ;0,1=190,2=0.000000
L 0.72118307 3.6045 0.72386654 3.60553307 1 P 0 ;0,1=190,2=0.000000
L 0.72386654 3.60553307 0.72616673 3.60708278 1 P 0 ;0,1=190,2=0.000000
L 0.72616673 3.60708278 0.72808366 3.60914892 1 P 0 ;0,1=190,2=0.000000
L 0.74183317 3.6045 0.74183317 3.6355 1 P 0 ;0,1=190,2=0.000000
L 0.74183317 3.6355 0.75141654 3.6355 1 P 0 ;0,1=190,2=0.000000
L 0.75141654 3.6355 0.75448327 3.63394931 1 P 0 ;0,1=190,2=0.000000
L 0.75448327 3.63394931 0.7564002 3.63188307 1 P 0 ;0,1=190,2=0.000000
L 0.7564002 3.63188307 0.75716673 3.6277497 1 P 0 ;0,1=190,2=0.000000
L 0.75716673 3.6277497 0.7564002 3.62361634 1 P 0 ;0,1=190,2=0.000000
L 0.7564002 3.62361634 0.7541 3.62103356 1 P 0 ;0,1=190,2=0.000000
L 0.7541 3.62103356 0.75141654 3.61948287 1 P 0 ;0,1=190,2=0.000000
L 0.75141654 3.61948287 0.74183317 3.61948287 1 P 0 ;0,1=190,2=0.000000
L 0.75141654 3.61948287 0.75716673 3.6045 1 P 0 ;0,1=190,2=0.000000
L 0.78049961 3.6045 0.78049961 3.6355 1 P 0 ;0,1=190,2=0.000000
L 0.78049961 3.6355 0.7758999 3.6293003 1 P 0 ;0,1=190,2=0.000000
L 0.7758999 3.6045 0.78509931 3.6045 1 P 0 ;0,1=190,2=0.000000
L 0.80421644 3.63033346 0.80651663 3.63343278 1 P 0 ;0,1=190,2=0.000000
L 0.80651663 3.63343278 0.8092001 3.63498337 1 P 0 ;0,1=190,2=0.000000
L 0.8092001 3.63498337 0.81226683 3.6355 1 P 0 ;0,1=190,2=0.000000
L 0.81226683 3.6355 0.8161 3.63446683 1 P 0 ;0,1=190,2=0.000000
L 0.8161 3.63446683 0.81878346 3.63188307 1 P 0 ;0,1=190,2=0.000000
L 0.81878346 3.63188307 0.81955 3.62878376 1 P 0 ;0,1=190,2=0.000000
L 0.81955 3.62878376 0.81916673 3.62568258 1 P 0 ;0,1=190,2=0.000000
L 0.81916673 3.62568258 0.81763307 3.6230998 1 P 0 ;0,1=190,2=0.000000
L 0.81763307 3.6230998 0.80996663 3.61793327 1 P 0 ;0,1=190,2=0.000000
L 0.80996663 3.61793327 0.80651663 3.61431644 1 P 0 ;0,1=190,2=0.000000
L 0.80651663 3.61431644 0.80421644 3.60914892 1 P 0 ;0,1=190,2=0.000000
L 0.80421644 3.60914892 0.8034499 3.6045 1 P 0 ;0,1=190,2=0.000000
L 0.8034499 3.6045 0.81955 3.6045 1 P 0 ;0,1=190,2=0.000000
L 0.67999961 3.6045 0.67999961 3.6355 1 P 0 ;0,1=2,2=0.000000
L 0.67999961 3.6355 0.6753999 3.6293003 1 P 0 ;0,1=2,2=0.000000
L 0.6753999 3.6045 0.68459931 3.6045 1 P 0 ;0,1=2,2=0.000000
L 3.83023996 0.71461004 3.83023996 0.93538996 1 P 0 
L 4.12976004 0.71461004 3.83023996 0.71461004 1 P 0 
L 3.83023996 0.93538996 4.12976004 0.93538996 1 P 0 
L 4.12976004 0.93538996 4.12976004 0.71461004 1 P 0 
L 3.93449961 0.66 3.93449961 0.6739498 1 P 0 ;0,1=191,2=0.000000
L 3.93449961 0.6739498 3.92683317 0.691 1 P 0 ;0,1=191,2=0.000000
L 3.94216673 0.691 3.93449961 0.6739498 1 P 0 ;0,1=191,2=0.000000
L 3.9701 0.66 3.9701 0.691 1 P 0 ;0,1=191,2=0.000000
L 3.9701 0.691 3.95591624 0.66878327 1 P 0 ;0,1=191,2=0.000000
L 3.95591624 0.66878327 3.97508366 0.66878327 1 P 0 ;0,1=191,2=0.000000
L 3.88716998 0.68796959 3.85616998 0.68796959 1 P 0 ;0,1=2,2=270.000000
L 3.85616998 0.68796959 3.86236969 0.68336988 1 P 0 ;0,1=2,2=270.000000
L 3.88716998 0.68336988 3.88716998 0.69256929 1 P 0 ;0,1=2,2=270.000000
L 4.08430039 0.67545659 4.08791722 0.6777561 1 P 0 ;0,1=10,2=270.000000
L 4.08791722 0.6777561 4.08998346 0.68082283 1 P 0 ;0,1=10,2=270.000000
L 4.08998346 0.68082283 4.0905 0.68427352 1 P 0 ;0,1=10,2=270.000000
L 4.0905 0.68427352 4.08998346 0.68734026 1 P 0 ;0,1=10,2=270.000000
L 4.08998346 0.68734026 4.08740069 0.69040699 1 P 0 ;0,1=10,2=270.000000
L 4.08740069 0.69040699 4.08430039 0.69232323 1 P 0 ;0,1=10,2=270.000000
L 4.08430039 0.69232323 4.0812001 0.6927065 1 P 0 ;0,1=10,2=270.000000
L 4.0812001 0.6927065 4.07758425 0.69193996 1 P 0 ;0,1=10,2=270.000000
L 4.07758425 0.69193996 4.07500049 0.6892565 1 P 0 ;0,1=10,2=270.000000
L 4.07500049 0.6892565 4.07396644 0.68657303 1 P 0 ;0,1=10,2=270.000000
L 4.07396644 0.68657303 4.07396644 0.68312303 1 P 0 ;0,1=10,2=270.000000
L 4.07396644 0.68657303 4.07241683 0.68887323 1 P 0 ;0,1=10,2=270.000000
L 4.07241683 0.68887323 4.06983406 0.69079016 1 P 0 ;0,1=10,2=270.000000
L 4.06983406 0.69079016 4.06673376 0.69155669 1 P 0 ;0,1=10,2=270.000000
L 4.06673376 0.69155669 4.06363346 0.69079016 1 P 0 ;0,1=10,2=270.000000
L 4.06363346 0.69079016 4.06105069 0.68887323 1 P 0 ;0,1=10,2=270.000000
L 4.06105069 0.68887323 4.0595 0.68542323 1 P 0 ;0,1=10,2=270.000000
L 4.0595 0.68542323 4.06001663 0.68197333 1 P 0 ;0,1=10,2=270.000000
L 4.06001663 0.68197333 4.06208376 0.67852333 1 P 0 ;0,1=10,2=270.000000
L 4.47438996 0.93996004 4.47438996 0.79003996 1 P 0 
L 4.25361004 0.93996004 4.47438996 0.93996004 1 P 0 
L 4.47438996 0.79003996 4.25361004 0.79003996 1 P 0 
L 4.25361004 0.79003996 4.25361004 0.93996004 1 P 0 
L 4.48656663 0.79569961 4.48886614 0.79208278 1 P 0 ;0,1=10,2=0.000000
L 4.48886614 0.79208278 4.49193287 0.79001654 1 P 0 ;0,1=10,2=0.000000
L 4.49193287 0.79001654 4.49538356 0.7895 1 P 0 ;0,1=10,2=0.000000
L 4.49538356 0.7895 4.4984503 0.79001654 1 P 0 ;0,1=10,2=0.000000
L 4.4984503 0.79001654 4.50151703 0.79259931 1 P 0 ;0,1=10,2=0.000000
L 4.50151703 0.79259931 4.50343327 0.79569961 1 P 0 ;0,1=10,2=0.000000
L 4.50343327 0.79569961 4.50381654 0.7987999 1 P 0 ;0,1=10,2=0.000000
L 4.50381654 0.7987999 4.50305 0.80241575 1 P 0 ;0,1=10,2=0.000000
L 4.50305 0.80241575 4.50036654 0.80499951 1 P 0 ;0,1=10,2=0.000000
L 4.50036654 0.80499951 4.49768307 0.80603356 1 P 0 ;0,1=10,2=0.000000
L 4.49768307 0.80603356 4.49423307 0.80603356 1 P 0 ;0,1=10,2=0.000000
L 4.49768307 0.80603356 4.49998327 0.80758317 1 P 0 ;0,1=10,2=0.000000
L 4.49998327 0.80758317 4.5019002 0.81016594 1 P 0 ;0,1=10,2=0.000000
L 4.5019002 0.81016594 4.50266673 0.81326624 1 P 0 ;0,1=10,2=0.000000
L 4.50266673 0.81326624 4.5019002 0.81636654 1 P 0 ;0,1=10,2=0.000000
L 4.5019002 0.81636654 4.49998327 0.81894931 1 P 0 ;0,1=10,2=0.000000
L 4.49998327 0.81894931 4.49653327 0.8205 1 P 0 ;0,1=10,2=0.000000
L 4.49653327 0.8205 4.49308337 0.81998337 1 P 0 ;0,1=10,2=0.000000
L 4.49308337 0.81998337 4.48963337 0.81791624 1 P 0 ;0,1=10,2=0.000000
L 4.23999961 0.7845 4.23999961 0.8155 1 P 0 ;0,1=2,2=0.000000
L 4.23999961 0.8155 4.2353999 0.8093003 1 P 0 ;0,1=2,2=0.000000
L 4.2353999 0.7845 4.24459931 0.7845 1 P 0 ;0,1=2,2=0.000000
L 4.34949961 0.5745 4.34949961 0.5884498 1 P 0 ;0,1=192,2=0.000000
L 4.34949961 0.5884498 4.34183317 0.6055 1 P 0 ;0,1=192,2=0.000000
L 4.35716673 0.6055 4.34949961 0.5884498 1 P 0 ;0,1=192,2=0.000000
L 4.37206663 0.58069961 4.37436614 0.57708278 1 P 0 ;0,1=192,2=0.000000
L 4.37436614 0.57708278 4.37743287 0.57501654 1 P 0 ;0,1=192,2=0.000000
L 4.37743287 0.57501654 4.38088356 0.5745 1 P 0 ;0,1=192,2=0.000000
L 4.38088356 0.5745 4.3839503 0.57501654 1 P 0 ;0,1=192,2=0.000000
L 4.3839503 0.57501654 4.38701703 0.57759931 1 P 0 ;0,1=192,2=0.000000
L 4.38701703 0.57759931 4.38893327 0.58069961 1 P 0 ;0,1=192,2=0.000000
L 4.38893327 0.58069961 4.38931654 0.5837999 1 P 0 ;0,1=192,2=0.000000
L 4.38931654 0.5837999 4.38855 0.58741575 1 P 0 ;0,1=192,2=0.000000
L 4.38855 0.58741575 4.38586654 0.58999951 1 P 0 ;0,1=192,2=0.000000
L 4.38586654 0.58999951 4.38318307 0.59103356 1 P 0 ;0,1=192,2=0.000000
L 4.38318307 0.59103356 4.37973307 0.59103356 1 P 0 ;0,1=192,2=0.000000
L 4.38318307 0.59103356 4.38548327 0.59258317 1 P 0 ;0,1=192,2=0.000000
L 4.38548327 0.59258317 4.3874002 0.59516594 1 P 0 ;0,1=192,2=0.000000
L 4.3874002 0.59516594 4.38816673 0.59826624 1 P 0 ;0,1=192,2=0.000000
L 4.38816673 0.59826624 4.3874002 0.60136654 1 P 0 ;0,1=192,2=0.000000
L 4.3874002 0.60136654 4.38548327 0.60394931 1 P 0 ;0,1=192,2=0.000000
L 4.38548327 0.60394931 4.38203327 0.6055 1 P 0 ;0,1=192,2=0.000000
L 4.38203327 0.6055 4.37858337 0.60498337 1 P 0 ;0,1=192,2=0.000000
L 4.37858337 0.60498337 4.37513337 0.60291624 1 P 0 ;0,1=192,2=0.000000
L 4.96948996 3.96841004 4.96948996 3.61191004 1 P 0 
L 4.73256004 3.96841004 4.96948996 3.96841004 1 P 0 
L 4.73256004 3.61191004 4.73256004 3.96841004 1 P 0 
L 4.96948996 3.61191004 4.73256004 3.61191004 1 P 0 
L 4.99499961 3.8945 4.99499961 3.9255 1 P 0 ;0,1=2,2=0.000000
L 4.99499961 3.9255 4.9903999 3.9193003 1 P 0 ;0,1=2,2=0.000000
L 4.9903999 3.8945 4.99959931 3.8945 1 P 0 ;0,1=2,2=0.000000
L 5.00923307 3.6845 5.00999961 3.69121614 1 P 0 ;0,1=138,2=0.000000
L 5.00999961 3.69121614 5.0111501 3.69689921 1 P 0 ;0,1=138,2=0.000000
L 5.0111501 3.69689921 5.01268307 3.70206663 1 P 0 ;0,1=138,2=0.000000
L 5.01268307 3.70206663 5.0146 3.7077497 1 P 0 ;0,1=138,2=0.000000
L 5.0146 3.7077497 5.01766673 3.7155 1 P 0 ;0,1=138,2=0.000000
L 5.01766673 3.7155 5.00233317 3.7155 1 P 0 ;0,1=138,2=0.000000
L 4.70271644 3.88533346 4.70501663 3.88843278 1 P 0 ;0,1=4,2=0.000000
L 4.70501663 3.88843278 4.7077001 3.88998337 1 P 0 ;0,1=4,2=0.000000
L 4.7077001 3.88998337 4.71076683 3.8905 1 P 0 ;0,1=4,2=0.000000
L 4.71076683 3.8905 4.7146 3.88946683 1 P 0 ;0,1=4,2=0.000000
L 4.7146 3.88946683 4.71728346 3.88688307 1 P 0 ;0,1=4,2=0.000000
L 4.71728346 3.88688307 4.71805 3.88378376 1 P 0 ;0,1=4,2=0.000000
L 4.71805 3.88378376 4.71766673 3.88068258 1 P 0 ;0,1=4,2=0.000000
L 4.71766673 3.88068258 4.71613307 3.8780998 1 P 0 ;0,1=4,2=0.000000
L 4.71613307 3.8780998 4.70846663 3.87293327 1 P 0 ;0,1=4,2=0.000000
L 4.70846663 3.87293327 4.70501663 3.86931644 1 P 0 ;0,1=4,2=0.000000
L 4.70501663 3.86931644 4.70271644 3.86414892 1 P 0 ;0,1=4,2=0.000000
L 4.70271644 3.86414892 4.7019499 3.8595 1 P 0 ;0,1=4,2=0.000000
L 4.7019499 3.8595 4.71805 3.8595 1 P 0 ;0,1=4,2=0.000000
L 4.69499961 3.6495 4.69768307 3.65001654 1 P 0 ;0,1=16,2=0.000000
L 4.69768307 3.65001654 4.7007498 3.65156614 1 P 0 ;0,1=16,2=0.000000
L 4.7007498 3.65156614 4.70266673 3.65414892 1 P 0 ;0,1=16,2=0.000000
L 4.70266673 3.65414892 4.70343327 3.65776673 1 P 0 ;0,1=16,2=0.000000
L 4.70343327 3.65776673 4.70266673 3.66138268 1 P 0 ;0,1=16,2=0.000000
L 4.70266673 3.66138268 4.70036654 3.66448287 1 P 0 ;0,1=16,2=0.000000
L 4.70036654 3.66448287 4.69691654 3.66603356 1 P 0 ;0,1=16,2=0.000000
L 4.69691654 3.66603356 4.69308337 3.66603356 1 P 0 ;0,1=16,2=0.000000
L 4.69308337 3.66603356 4.69078317 3.66706663 1 P 0 ;0,1=16,2=0.000000
L 4.69078317 3.66706663 4.68886614 3.66964941 1 P 0 ;0,1=16,2=0.000000
L 4.68886614 3.66964941 4.6880997 3.67326624 1 P 0 ;0,1=16,2=0.000000
L 4.6880997 3.67326624 4.6892501 3.67688307 1 P 0 ;0,1=16,2=0.000000
L 4.6892501 3.67688307 4.69193287 3.67946683 1 P 0 ;0,1=16,2=0.000000
L 4.69193287 3.67946683 4.69499961 3.6805 1 P 0 ;0,1=16,2=0.000000
L 4.69499961 3.6805 4.69806634 3.67946683 1 P 0 ;0,1=16,2=0.000000
L 4.69806634 3.67946683 4.7007498 3.67688307 1 P 0 ;0,1=16,2=0.000000
L 4.7007498 3.67688307 4.7019002 3.67326624 1 P 0 ;0,1=16,2=0.000000
L 4.7019002 3.67326624 4.70113307 3.66964941 1 P 0 ;0,1=16,2=0.000000
L 4.70113307 3.66964941 4.69921673 3.66706663 1 P 0 ;0,1=16,2=0.000000
L 4.69921673 3.66706663 4.69691654 3.66603356 1 P 0 ;0,1=16,2=0.000000
L 4.69691654 3.66603356 4.69308337 3.66603356 1 P 0 ;0,1=16,2=0.000000
L 4.69308337 3.66603356 4.68963337 3.66448287 1 P 0 ;0,1=16,2=0.000000
L 4.68963337 3.66448287 4.68733317 3.66138268 1 P 0 ;0,1=16,2=0.000000
L 4.68733317 3.66138268 4.68656663 3.65776673 1 P 0 ;0,1=16,2=0.000000
L 4.68656663 3.65776673 4.68733317 3.65414892 1 P 0 ;0,1=16,2=0.000000
L 4.68733317 3.65414892 4.6892501 3.65156614 1 P 0 ;0,1=16,2=0.000000
L 4.6892501 3.65156614 4.69231683 3.65001654 1 P 0 ;0,1=16,2=0.000000
L 4.69231683 3.65001654 4.69499961 3.6495 1 P 0 ;0,1=16,2=0.000000
L 4.66683317 3.7395 4.66683317 3.7705 1 P 0 ;0,1=193,2=0.000000
L 4.66683317 3.7705 4.67603327 3.7705 1 P 0 ;0,1=193,2=0.000000
L 4.67603327 3.7705 4.6791 3.76894931 1 P 0 ;0,1=193,2=0.000000
L 4.6791 3.76894931 4.6814002 3.76533346 1 P 0 ;0,1=193,2=0.000000
L 4.6814002 3.76533346 4.68216673 3.7612 1 P 0 ;0,1=193,2=0.000000
L 4.68216673 3.7612 4.6814002 3.75706663 1 P 0 ;0,1=193,2=0.000000
L 4.6814002 3.75706663 4.67948327 3.75396634 1 P 0 ;0,1=193,2=0.000000
L 4.67948327 3.75396634 4.67603327 3.75241575 1 P 0 ;0,1=193,2=0.000000
L 4.67603327 3.75241575 4.66683317 3.75241575 1 P 0 ;0,1=193,2=0.000000
L 4.69821644 3.76533346 4.70051663 3.76843278 1 P 0 ;0,1=193,2=0.000000
L 4.70051663 3.76843278 4.7032001 3.76998337 1 P 0 ;0,1=193,2=0.000000
L 4.7032001 3.76998337 4.70626683 3.7705 1 P 0 ;0,1=193,2=0.000000
L 4.70626683 3.7705 4.7101 3.76946683 1 P 0 ;0,1=193,2=0.000000
L 4.7101 3.76946683 4.71278346 3.76688307 1 P 0 ;0,1=193,2=0.000000
L 4.71278346 3.76688307 4.71355 3.76378376 1 P 0 ;0,1=193,2=0.000000
L 4.71355 3.76378376 4.71316673 3.76068258 1 P 0 ;0,1=193,2=0.000000
L 4.71316673 3.76068258 4.71163307 3.7580998 1 P 0 ;0,1=193,2=0.000000
L 4.71163307 3.7580998 4.70396663 3.75293327 1 P 0 ;0,1=193,2=0.000000
L 4.70396663 3.75293327 4.70051663 3.74931644 1 P 0 ;0,1=193,2=0.000000
L 4.70051663 3.74931644 4.69821644 3.74414892 1 P 0 ;0,1=193,2=0.000000
L 4.69821644 3.74414892 4.6974499 3.7395 1 P 0 ;0,1=193,2=0.000000
L 4.6974499 3.7395 4.71355 3.7395 1 P 0 ;0,1=193,2=0.000000
L 3.815 3.19193002 3.815 3.42806998 1 P 0 
L 3.815 3.42806998 3.435 3.42806998 1 P 0 
L 3.435 3.42806998 3.435 3.19193002 1 P 0 
L 3.435 3.19193002 3.815 3.19193002 1 P 0 
S P 0
OB 3.86 3.175 I
OC 3.86 3.175 3.845 3.175 Y
OE
SE
L 3.8392 3.3715 3.8392 3.3965 1 P 0 ;0,1=11,2=0.000000
L 3.8392 3.3965 3.82933297 3.37858327 1 P 0 ;0,1=11,2=0.000000
L 3.82933297 3.37858327 3.84266693 3.37858327 1 P 0 ;0,1=11,2=0.000000
L 3.60656663 3.1775 3.60656663 3.15528327 1 P 0 ;0,1=194,2=0.000000
L 3.60656663 3.15528327 3.6080997 3.15063238 1 P 0 ;0,1=194,2=0.000000
L 3.6080997 3.15063238 3.61116634 3.14753307 1 P 0 ;0,1=194,2=0.000000
L 3.61116634 3.14753307 3.61499961 3.1465 1 P 0 ;0,1=194,2=0.000000
L 3.61499961 3.1465 3.61883356 3.14753307 1 P 0 ;0,1=194,2=0.000000
L 3.61883356 3.14753307 3.6219002 3.15063238 1 P 0 ;0,1=194,2=0.000000
L 3.6219002 3.15063238 3.62343327 3.15528327 1 P 0 ;0,1=194,2=0.000000
L 3.62343327 3.15528327 3.62343327 3.1775 1 P 0 ;0,1=194,2=0.000000
L 3.63871644 3.17233346 3.64101663 3.17543278 1 P 0 ;0,1=194,2=0.000000
L 3.64101663 3.17543278 3.6437001 3.17698337 1 P 0 ;0,1=194,2=0.000000
L 3.6437001 3.17698337 3.64676683 3.1775 1 P 0 ;0,1=194,2=0.000000
L 3.64676683 3.1775 3.6506 3.17646683 1 P 0 ;0,1=194,2=0.000000
L 3.6506 3.17646683 3.65328346 3.17388307 1 P 0 ;0,1=194,2=0.000000
L 3.65328346 3.17388307 3.65405 3.17078376 1 P 0 ;0,1=194,2=0.000000
L 3.65405 3.17078376 3.65366673 3.16768258 1 P 0 ;0,1=194,2=0.000000
L 3.65366673 3.16768258 3.65213307 3.1650998 1 P 0 ;0,1=194,2=0.000000
L 3.65213307 3.1650998 3.64446663 3.15993327 1 P 0 ;0,1=194,2=0.000000
L 3.64446663 3.15993327 3.64101663 3.15631644 1 P 0 ;0,1=194,2=0.000000
L 3.64101663 3.15631644 3.63871644 3.15114892 1 P 0 ;0,1=194,2=0.000000
L 3.63871644 3.15114892 3.6379499 3.1465 1 P 0 ;0,1=194,2=0.000000
L 3.6379499 3.1465 3.65405 3.1465 1 P 0 ;0,1=194,2=0.000000
L 3.66856663 3.15269961 3.67086614 3.14908278 1 P 0 ;0,1=194,2=0.000000
L 3.67086614 3.14908278 3.67393287 3.14701654 1 P 0 ;0,1=194,2=0.000000
L 3.67393287 3.14701654 3.67738356 3.1465 1 P 0 ;0,1=194,2=0.000000
L 3.67738356 3.1465 3.6804503 3.14701654 1 P 0 ;0,1=194,2=0.000000
L 3.6804503 3.14701654 3.68351703 3.14959931 1 P 0 ;0,1=194,2=0.000000
L 3.68351703 3.14959931 3.68543327 3.15269961 1 P 0 ;0,1=194,2=0.000000
L 3.68543327 3.15269961 3.68581654 3.1557999 1 P 0 ;0,1=194,2=0.000000
L 3.68581654 3.1557999 3.68505 3.15941575 1 P 0 ;0,1=194,2=0.000000
L 3.68505 3.15941575 3.68236654 3.16199951 1 P 0 ;0,1=194,2=0.000000
L 3.68236654 3.16199951 3.67968307 3.16303356 1 P 0 ;0,1=194,2=0.000000
L 3.67968307 3.16303356 3.67623307 3.16303356 1 P 0 ;0,1=194,2=0.000000
L 3.67968307 3.16303356 3.68198327 3.16458317 1 P 0 ;0,1=194,2=0.000000
L 3.68198327 3.16458317 3.6839002 3.16716594 1 P 0 ;0,1=194,2=0.000000
L 3.6839002 3.16716594 3.68466673 3.17026624 1 P 0 ;0,1=194,2=0.000000
L 3.68466673 3.17026624 3.6839002 3.17336654 1 P 0 ;0,1=194,2=0.000000
L 3.6839002 3.17336654 3.68198327 3.17594931 1 P 0 ;0,1=194,2=0.000000
L 3.68198327 3.17594931 3.67853327 3.1775 1 P 0 ;0,1=194,2=0.000000
L 3.67853327 3.1775 3.67508337 3.17698337 1 P 0 ;0,1=194,2=0.000000
L 3.67508337 3.17698337 3.67163337 3.17491624 1 P 0 ;0,1=194,2=0.000000
L 3.45256663 3.45114892 3.45486614 3.44856614 1 P 0 ;0,1=20,2=0.000000
L 3.45486614 3.44856614 3.45754961 3.44701654 1 P 0 ;0,1=20,2=0.000000
L 3.45754961 3.44701654 3.46099961 3.4465 1 P 0 ;0,1=20,2=0.000000
L 3.46099961 3.4465 3.4644503 3.44753307 1 P 0 ;0,1=20,2=0.000000
L 3.4644503 3.44753307 3.46713307 3.44959931 1 P 0 ;0,1=20,2=0.000000
L 3.46713307 3.44959931 3.46905 3.45321614 1 P 0 ;0,1=20,2=0.000000
L 3.46905 3.45321614 3.46943327 3.45734951 1 P 0 ;0,1=20,2=0.000000
L 3.46943327 3.45734951 3.46866673 3.46148287 1 P 0 ;0,1=20,2=0.000000
L 3.46866673 3.46148287 3.4667498 3.46406663 1 P 0 ;0,1=20,2=0.000000
L 3.4667498 3.46406663 3.46406634 3.46613287 1 P 0 ;0,1=20,2=0.000000
L 3.46406634 3.46613287 3.46138356 3.46664941 1 P 0 ;0,1=20,2=0.000000
L 3.46138356 3.46664941 3.4587001 3.46613287 1 P 0 ;0,1=20,2=0.000000
L 3.4587001 3.46613287 3.4552501 3.46406663 1 P 0 ;0,1=20,2=0.000000
L 3.4552501 3.46406663 3.4563999 3.4775 1 P 0 ;0,1=20,2=0.000000
L 3.4563999 3.4775 3.4667498 3.4775 1 P 0 ;0,1=20,2=0.000000
L 3.47099961 3.1415 3.47368307 3.14201654 1 P 0 ;0,1=16,2=0.000000
L 3.47368307 3.14201654 3.4767498 3.14356614 1 P 0 ;0,1=16,2=0.000000
L 3.4767498 3.14356614 3.47866673 3.14614892 1 P 0 ;0,1=16,2=0.000000
L 3.47866673 3.14614892 3.47943327 3.14976673 1 P 0 ;0,1=16,2=0.000000
L 3.47943327 3.14976673 3.47866673 3.15338268 1 P 0 ;0,1=16,2=0.000000
L 3.47866673 3.15338268 3.47636654 3.15648287 1 P 0 ;0,1=16,2=0.000000
L 3.47636654 3.15648287 3.47291654 3.15803356 1 P 0 ;0,1=16,2=0.000000
L 3.47291654 3.15803356 3.46908337 3.15803356 1 P 0 ;0,1=16,2=0.000000
L 3.46908337 3.15803356 3.46678317 3.15906663 1 P 0 ;0,1=16,2=0.000000
L 3.46678317 3.15906663 3.46486614 3.16164941 1 P 0 ;0,1=16,2=0.000000
L 3.46486614 3.16164941 3.4640997 3.16526624 1 P 0 ;0,1=16,2=0.000000
L 3.4640997 3.16526624 3.4652501 3.16888307 1 P 0 ;0,1=16,2=0.000000
L 3.4652501 3.16888307 3.46793287 3.17146683 1 P 0 ;0,1=16,2=0.000000
L 3.46793287 3.17146683 3.47099961 3.1725 1 P 0 ;0,1=16,2=0.000000
L 3.47099961 3.1725 3.47406634 3.17146683 1 P 0 ;0,1=16,2=0.000000
L 3.47406634 3.17146683 3.4767498 3.16888307 1 P 0 ;0,1=16,2=0.000000
L 3.4767498 3.16888307 3.4779002 3.16526624 1 P 0 ;0,1=16,2=0.000000
L 3.4779002 3.16526624 3.47713307 3.16164941 1 P 0 ;0,1=16,2=0.000000
L 3.47713307 3.16164941 3.47521673 3.15906663 1 P 0 ;0,1=16,2=0.000000
L 3.47521673 3.15906663 3.47291654 3.15803356 1 P 0 ;0,1=16,2=0.000000
L 3.47291654 3.15803356 3.46908337 3.15803356 1 P 0 ;0,1=16,2=0.000000
L 3.46908337 3.15803356 3.46563337 3.15648287 1 P 0 ;0,1=16,2=0.000000
L 3.46563337 3.15648287 3.46333317 3.15338268 1 P 0 ;0,1=16,2=0.000000
L 3.46333317 3.15338268 3.46256663 3.14976673 1 P 0 ;0,1=16,2=0.000000
L 3.46256663 3.14976673 3.46333317 3.14614892 1 P 0 ;0,1=16,2=0.000000
L 3.46333317 3.14614892 3.4652501 3.14356614 1 P 0 ;0,1=16,2=0.000000
L 3.4652501 3.14356614 3.46831683 3.14201654 1 P 0 ;0,1=16,2=0.000000
L 3.46831683 3.14201654 3.47099961 3.1415 1 P 0 ;0,1=16,2=0.000000
L 2.97283996 1.65325 2.97283996 2.02758996 1 P 0 
L 2.75333002 2.02758996 2.72436004 1.99861998 1 P 0 
L 2.97283996 2.02758996 2.75333002 2.02758996 1 P 0 
L 2.72436004 1.65325 2.97283996 1.65325 1 P 0 
L 2.72436004 1.99861998 2.72436004 1.65325 1 P 0 
L 2.98993317 1.95333337 2.99153327 1.95583287 1 P 0 ;0,1=4,2=0.000000
L 2.99153327 1.95583287 2.9934 1.95708337 1 P 0 ;0,1=4,2=0.000000
L 2.9934 1.95708337 2.99553337 1.9575 1 P 0 ;0,1=4,2=0.000000
L 2.99553337 1.9575 2.9982 1.95666683 1 P 0 ;0,1=4,2=0.000000
L 2.9982 1.95666683 3.00006673 1.95458317 1 P 0 ;0,1=4,2=0.000000
L 3.00006673 1.95458317 3.0006 1.95208366 1 P 0 ;0,1=4,2=0.000000
L 3.0006 1.95208366 3.00033337 1.94958268 1 P 0 ;0,1=4,2=0.000000
L 3.00033337 1.94958268 2.99926644 1.9474998 1 P 0 ;0,1=4,2=0.000000
L 2.99926644 1.9474998 2.99393327 1.94333327 1 P 0 ;0,1=4,2=0.000000
L 2.99393327 1.94333327 2.99153327 1.94041644 1 P 0 ;0,1=4,2=0.000000
L 2.99153327 1.94041644 2.98993317 1.93624911 1 P 0 ;0,1=4,2=0.000000
L 2.98993317 1.93624911 2.9893999 1.9325 1 P 0 ;0,1=4,2=0.000000
L 2.9893999 1.9325 3.0006 1.9325 1 P 0 ;0,1=4,2=0.000000
L 2.99393317 1.78333337 2.99553327 1.78583287 1 P 0 ;0,1=174,2=0.000000
L 2.99553327 1.78583287 2.9974 1.78708337 1 P 0 ;0,1=174,2=0.000000
L 2.9974 1.78708337 2.99953337 1.7875 1 P 0 ;0,1=174,2=0.000000
L 2.99953337 1.7875 3.0022 1.78666683 1 P 0 ;0,1=174,2=0.000000
L 3.0022 1.78666683 3.00406673 1.78458317 1 P 0 ;0,1=174,2=0.000000
L 3.00406673 1.78458317 3.0046 1.78208366 1 P 0 ;0,1=174,2=0.000000
L 3.0046 1.78208366 3.00433337 1.77958268 1 P 0 ;0,1=174,2=0.000000
L 3.00433337 1.77958268 3.00326644 1.7774998 1 P 0 ;0,1=174,2=0.000000
L 3.00326644 1.7774998 2.99793327 1.77333327 1 P 0 ;0,1=174,2=0.000000
L 2.99793327 1.77333327 2.99553327 1.77041644 1 P 0 ;0,1=174,2=0.000000
L 2.99553327 1.77041644 2.99393317 1.76624911 1 P 0 ;0,1=174,2=0.000000
L 2.99393317 1.76624911 2.9933999 1.7625 1 P 0 ;0,1=174,2=0.000000
L 2.9933999 1.7625 3.0046 1.7625 1 P 0 ;0,1=174,2=0.000000
L 3.0209997 1.7875 3.01886634 1.78666683 1 P 0 ;0,1=174,2=0.000000
L 3.01886634 1.78666683 3.01726663 1.78458317 1 P 0 ;0,1=174,2=0.000000
L 3.01726663 1.78458317 3.0161998 1.78208366 1 P 0 ;0,1=174,2=0.000000
L 3.0161998 1.78208366 3.0153999 1.77874951 1 P 0 ;0,1=174,2=0.000000
L 3.0153999 1.77874951 3.01513327 1.77499961 1 P 0 ;0,1=174,2=0.000000
L 3.01513327 1.77499961 3.0153999 1.77124961 1 P 0 ;0,1=174,2=0.000000
L 3.0153999 1.77124961 3.0161998 1.76791624 1 P 0 ;0,1=174,2=0.000000
L 3.0161998 1.76791624 3.01726663 1.76541604 1 P 0 ;0,1=174,2=0.000000
L 3.01726663 1.76541604 3.01886634 1.76333307 1 P 0 ;0,1=174,2=0.000000
L 3.01886634 1.76333307 3.0209997 1.7625 1 P 0 ;0,1=174,2=0.000000
L 3.0209997 1.7625 3.02313307 1.76333307 1 P 0 ;0,1=174,2=0.000000
L 3.02313307 1.76333307 3.02473327 1.76541604 1 P 0 ;0,1=174,2=0.000000
L 3.02473327 1.76541604 3.0258001 1.76791624 1 P 0 ;0,1=174,2=0.000000
L 3.0258001 1.76791624 3.0266 1.77124961 1 P 0 ;0,1=174,2=0.000000
L 3.0266 1.77124961 3.02686663 1.77499961 1 P 0 ;0,1=174,2=0.000000
L 3.02686663 1.77499961 3.0266 1.77874951 1 P 0 ;0,1=174,2=0.000000
L 3.0266 1.77874951 3.0258001 1.78208366 1 P 0 ;0,1=174,2=0.000000
L 3.0258001 1.78208366 3.02473327 1.78458317 1 P 0 ;0,1=174,2=0.000000
L 3.02473327 1.78458317 3.02313307 1.78666683 1 P 0 ;0,1=174,2=0.000000
L 3.02313307 1.78666683 3.0209997 1.7875 1 P 0 ;0,1=174,2=0.000000
L 3.00683317 1.8045 3.00683317 1.8355 1 P 0 ;0,1=195,2=0.000000
L 3.00683317 1.8355 3.01603327 1.8355 1 P 0 ;0,1=195,2=0.000000
L 3.01603327 1.8355 3.0191 1.83394931 1 P 0 ;0,1=195,2=0.000000
L 3.0191 1.83394931 3.0214002 1.83033346 1 P 0 ;0,1=195,2=0.000000
L 3.0214002 1.83033346 3.02216673 1.8262 1 P 0 ;0,1=195,2=0.000000
L 3.02216673 1.8262 3.0214002 1.82206663 1 P 0 ;0,1=195,2=0.000000
L 3.0214002 1.82206663 3.01948327 1.81896634 1 P 0 ;0,1=195,2=0.000000
L 3.01948327 1.81896634 3.01603327 1.81741575 1 P 0 ;0,1=195,2=0.000000
L 3.01603327 1.81741575 3.00683317 1.81741575 1 P 0 ;0,1=195,2=0.000000
L 3.04549961 1.8045 3.04549961 1.8355 1 P 0 ;0,1=195,2=0.000000
L 3.04549961 1.8355 3.0408999 1.8293003 1 P 0 ;0,1=195,2=0.000000
L 3.0408999 1.8045 3.05009931 1.8045 1 P 0 ;0,1=195,2=0.000000
L 2.6999997 1.9325 2.6999997 1.9575 1 P 0 ;0,1=2,2=0.000000
L 2.6999997 1.9575 2.6967999 1.9525003 1 P 0 ;0,1=2,2=0.000000
L 2.6967999 1.9325 2.70319951 1.9325 1 P 0 ;0,1=2,2=0.000000
L 2.6889997 1.7325 2.6889997 1.7575 1 P 0 ;0,1=196,2=0.000000
L 2.6889997 1.7575 2.6857999 1.7525003 1 P 0 ;0,1=196,2=0.000000
L 2.6857999 1.7325 2.69219951 1.7325 1 P 0 ;0,1=196,2=0.000000
L 2.70646634 1.73541604 2.70833317 1.73333307 1 P 0 ;0,1=196,2=0.000000
L 2.70833317 1.73333307 2.71046654 1.7325 1 P 0 ;0,1=196,2=0.000000
L 2.71046654 1.7325 2.7125999 1.73333307 1 P 0 ;0,1=196,2=0.000000
L 2.7125999 1.73333307 2.71446663 1.73583258 1 P 0 ;0,1=196,2=0.000000
L 2.71446663 1.73583258 2.7158001 1.73958327 1 P 0 ;0,1=196,2=0.000000
L 2.7158001 1.73958327 2.71633337 1.74333327 1 P 0 ;0,1=196,2=0.000000
L 2.71633337 1.74333327 2.71633337 1.74791634 1 P 0 ;0,1=196,2=0.000000
L 2.71633337 1.74791634 2.7158001 1.75166634 1 P 0 ;0,1=196,2=0.000000
L 2.7158001 1.75166634 2.71446663 1.7549997 1 P 0 ;0,1=196,2=0.000000
L 2.71446663 1.7549997 2.71286644 1.75666683 1 P 0 ;0,1=196,2=0.000000
L 2.71286644 1.75666683 2.7109997 1.7575 1 P 0 ;0,1=196,2=0.000000
L 2.7109997 1.7575 2.70886634 1.75666683 1 P 0 ;0,1=196,2=0.000000
L 2.70886634 1.75666683 2.70726663 1.7549997 1 P 0 ;0,1=196,2=0.000000
L 2.70726663 1.7549997 2.7061998 1.7525003 1 P 0 ;0,1=196,2=0.000000
L 2.7061998 1.7525003 2.70566654 1.74916614 1 P 0 ;0,1=196,2=0.000000
L 2.70566654 1.74916614 2.7061998 1.7462501 1 P 0 ;0,1=196,2=0.000000
L 2.7061998 1.7462501 2.70753327 1.74333327 1 P 0 ;0,1=196,2=0.000000
L 2.70753327 1.74333327 2.70913346 1.74166614 1 P 0 ;0,1=196,2=0.000000
L 2.70913346 1.74166614 2.7109997 1.74124961 1 P 0 ;0,1=196,2=0.000000
L 2.7109997 1.74124961 2.71313307 1.74208278 1 P 0 ;0,1=196,2=0.000000
L 2.71313307 1.74208278 2.71473327 1.74416644 1 P 0 ;0,1=196,2=0.000000
L 2.71473327 1.74416644 2.71633337 1.74791634 1 P 0 ;0,1=196,2=0.000000
L 4.76776004 2.20776004 4.76776004 1.28223996 1 P 0 
L 3.84223996 2.20776004 4.76776004 2.20776004 1 P 0 
L 4.76776004 1.28223996 3.84223996 1.28223996 1 P 0 
L 3.84223996 1.28223996 3.84223996 2.20776004 1 P 0 
S P 0
OB 3.835 1.24 I
OC 3.835 1.24 3.81 1.24 Y
OE
SE
L 4.73523002 1.21913297 4.71023002 1.2257997 1 P 0 ;0,1=197,2=270.000000
L 4.71023002 1.2257997 4.73523002 1.23246693 1 P 0 ;0,1=197,2=270.000000
L 4.72648041 1.23006644 4.72648041 1.22153297 1 P 0 ;0,1=197,2=270.000000
L 4.72189656 1.24993307 4.72064675 1.251 1 P 0 ;0,1=197,2=270.000000
L 4.72064675 1.251 4.71856388 1.2517998 1 P 0 ;0,1=197,2=270.000000
L 4.71856388 1.2517998 4.71564636 1.25233356 1 P 0 ;0,1=197,2=270.000000
L 4.71564636 1.25233356 4.71314685 1.2517998 1 P 0 ;0,1=197,2=270.000000
L 4.71314685 1.2517998 4.71148061 1.25073337 1 P 0 ;0,1=197,2=270.000000
L 4.71148061 1.25073337 4.71023002 1.24886663 1 P 0 ;0,1=197,2=270.000000
L 4.71023002 1.24886663 4.71023002 1.24166673 1 P 0 ;0,1=197,2=270.000000
L 4.71023002 1.24166673 4.73523002 1.24166673 1 P 0 ;0,1=197,2=270.000000
L 4.73523002 1.24166673 4.73523002 1.25046673 1 P 0 ;0,1=197,2=270.000000
L 4.73523002 1.25046673 4.73356378 1.25233356 1 P 0 ;0,1=197,2=270.000000
L 4.73356378 1.25233356 4.73106348 1.2534 1 P 0 ;0,1=197,2=270.000000
L 4.73106348 1.2534 4.72814675 1.25393317 1 P 0 ;0,1=197,2=270.000000
L 4.72814675 1.25393317 4.72523071 1.2534 1 P 0 ;0,1=197,2=270.000000
L 4.72523071 1.2534 4.72273041 1.2517998 1 P 0 ;0,1=197,2=270.000000
L 4.72273041 1.2517998 4.72189656 1.24993307 1 P 0 ;0,1=197,2=270.000000
L 4.72189656 1.24993307 4.72189656 1.24166673 1 P 0 ;0,1=197,2=270.000000
L 4.68533002 1.21241624 4.65433002 1.22199961 1 P 0 ;0,1=198,2=270.000000
L 4.65433002 1.22199961 4.68533002 1.23158366 1 P 0 ;0,1=198,2=270.000000
L 4.67448051 1.22813307 4.67448051 1.21586614 1 P 0 ;0,1=198,2=270.000000
L 4.68533002 1.24341624 4.65433002 1.25299961 1 P 0 ;0,1=198,2=270.000000
L 4.65433002 1.25299961 4.68533002 1.26258366 1 P 0 ;0,1=198,2=270.000000
L 4.67448051 1.25913307 4.67448051 1.24686614 1 P 0 ;0,1=198,2=270.000000
L 4.54033002 1.22083297 4.56533002 1.2274997 1 P 0 ;0,1=199,2=270.000000
L 4.56533002 1.2274997 4.54033002 1.23416693 1 P 0 ;0,1=199,2=270.000000
L 4.58033002 1.2445 4.60533002 1.24823297 1 P 0 ;0,1=200,2=270.000000
L 4.60533002 1.24823297 4.58033002 1.2524997 1 P 0 ;0,1=200,2=270.000000
L 4.58033002 1.2524997 4.60533002 1.25676644 1 P 0 ;0,1=200,2=270.000000
L 4.60533002 1.25676644 4.58033002 1.2605 1 P 0 ;0,1=200,2=270.000000
L 4.63533002 1.2274997 4.62408022 1.2274997 1 P 0 ;0,1=201,2=270.000000
L 4.62408022 1.2274997 4.61033002 1.22216654 1 P 0 ;0,1=201,2=270.000000
L 4.61033002 1.23283337 4.62408022 1.2274997 1 P 0 ;0,1=201,2=270.000000
L 4.41056663 2.2455 4.41056663 2.22328327 1 P 0 ;0,1=202,2=0.000000
L 4.41056663 2.22328327 4.4120997 2.21863238 1 P 0 ;0,1=202,2=0.000000
L 4.4120997 2.21863238 4.41516634 2.21553307 1 P 0 ;0,1=202,2=0.000000
L 4.41516634 2.21553307 4.41899961 2.2145 1 P 0 ;0,1=202,2=0.000000
L 4.41899961 2.2145 4.42283356 2.21553307 1 P 0 ;0,1=202,2=0.000000
L 4.42283356 2.21553307 4.4259002 2.21863238 1 P 0 ;0,1=202,2=0.000000
L 4.4259002 2.21863238 4.42743327 2.22328327 1 P 0 ;0,1=202,2=0.000000
L 4.42743327 2.22328327 4.42743327 2.2455 1 P 0 ;0,1=202,2=0.000000
L 4.44271644 2.24033346 4.44501663 2.24343278 1 P 0 ;0,1=202,2=0.000000
L 4.44501663 2.24343278 4.4477001 2.24498337 1 P 0 ;0,1=202,2=0.000000
L 4.4477001 2.24498337 4.45076683 2.2455 1 P 0 ;0,1=202,2=0.000000
L 4.45076683 2.2455 4.4546 2.24446683 1 P 0 ;0,1=202,2=0.000000
L 4.4546 2.24446683 4.45728346 2.24188307 1 P 0 ;0,1=202,2=0.000000
L 4.45728346 2.24188307 4.45805 2.23878376 1 P 0 ;0,1=202,2=0.000000
L 4.45805 2.23878376 4.45766673 2.23568258 1 P 0 ;0,1=202,2=0.000000
L 4.45766673 2.23568258 4.45613307 2.2330998 1 P 0 ;0,1=202,2=0.000000
L 4.45613307 2.2330998 4.44846663 2.22793327 1 P 0 ;0,1=202,2=0.000000
L 4.44846663 2.22793327 4.44501663 2.22431644 1 P 0 ;0,1=202,2=0.000000
L 4.44501663 2.22431644 4.44271644 2.21914892 1 P 0 ;0,1=202,2=0.000000
L 4.44271644 2.21914892 4.4419499 2.2145 1 P 0 ;0,1=202,2=0.000000
L 4.4419499 2.2145 4.45805 2.2145 1 P 0 ;0,1=202,2=0.000000
L 4.4856 2.2145 4.4856 2.2455 1 P 0 ;0,1=202,2=0.000000
L 4.4856 2.2455 4.47141624 2.22328327 1 P 0 ;0,1=202,2=0.000000
L 4.47141624 2.22328327 4.49058366 2.22328327 1 P 0 ;0,1=202,2=0.000000
L 4.46533002 1.2274997 4.49033002 1.2274997 1 P 0 ;0,1=203,2=270.000000
L 4.46533002 1.22136673 4.46533002 1.23363317 1 P 0 ;0,1=203,2=270.000000
L 4.46033002 1.24716654 4.43533002 1.24716654 1 P 0 ;0,1=204,2=270.000000
L 4.43533002 1.24716654 4.43533002 1.25383327 1 P 0 ;0,1=204,2=270.000000
L 4.43533002 1.25383327 4.43658061 1.25596663 1 P 0 ;0,1=204,2=270.000000
L 4.43658061 1.25596663 4.43824685 1.2573001 1 P 0 ;0,1=204,2=270.000000
L 4.43824685 1.2573001 4.44158022 1.25783337 1 P 0 ;0,1=204,2=270.000000
L 4.44158022 1.25783337 4.44491368 1.2573001 1 P 0 ;0,1=204,2=270.000000
L 4.44491368 1.2573001 4.44699656 1.2557 1 P 0 ;0,1=204,2=270.000000
L 4.44699656 1.2557 4.44824705 1.25383327 1 P 0 ;0,1=204,2=270.000000
L 4.44824705 1.25383327 4.44824705 1.24716654 1 P 0 ;0,1=204,2=270.000000
L 4.44824705 1.25383327 4.46033002 1.25783337 1 P 0 ;0,1=204,2=270.000000
L 4.41533002 1.22216654 4.39033002 1.22216654 1 P 0 ;0,1=205,2=270.000000
L 4.39033002 1.22216654 4.39033002 1.22856663 1 P 0 ;0,1=205,2=270.000000
L 4.39033002 1.22856663 4.39158061 1.2307 1 P 0 ;0,1=205,2=270.000000
L 4.39158061 1.2307 4.39449665 1.2323001 1 P 0 ;0,1=205,2=270.000000
L 4.39449665 1.2323001 4.39783002 1.23283337 1 P 0 ;0,1=205,2=270.000000
L 4.39783002 1.23283337 4.40116339 1.2323001 1 P 0 ;0,1=205,2=270.000000
L 4.40116339 1.2323001 4.40366358 1.23096663 1 P 0 ;0,1=205,2=270.000000
L 4.40366358 1.23096663 4.40491407 1.22856663 1 P 0 ;0,1=205,2=270.000000
L 4.40491407 1.22856663 4.40491407 1.22216654 1 P 0 ;0,1=205,2=270.000000
L 4.39033002 1.24636673 4.36533002 1.24636673 1 P 0 ;0,1=206,2=270.000000
L 4.36533002 1.24636673 4.39033002 1.25863317 1 P 0 ;0,1=206,2=270.000000
L 4.39033002 1.25863317 4.36533002 1.25863317 1 P 0 ;0,1=206,2=270.000000
L 4.50033002 1.24663327 4.51824675 1.24663327 1 P 0 ;0,1=207,2=270.000000
L 4.51824675 1.24663327 4.52199744 1.2476998 1 P 0 ;0,1=207,2=270.000000
L 4.52199744 1.2476998 4.52449695 1.24983317 1 P 0 ;0,1=207,2=270.000000
L 4.52449695 1.24983317 4.52533002 1.2524997 1 P 0 ;0,1=207,2=270.000000
L 4.52533002 1.2524997 4.52449695 1.25516673 1 P 0 ;0,1=207,2=270.000000
L 4.52449695 1.25516673 4.52199744 1.2573001 1 P 0 ;0,1=207,2=270.000000
L 4.52199744 1.2573001 4.51824675 1.25836663 1 P 0 ;0,1=207,2=270.000000
L 4.51824675 1.25836663 4.50033002 1.25836663 1 P 0 ;0,1=207,2=270.000000
L 4.21533002 1.2218999 4.19033002 1.2218999 1 P 0 ;0,1=208,2=270.000000
L 4.19033002 1.2331 4.21533002 1.2331 1 P 0 ;0,1=208,2=270.000000
L 4.20283041 1.2331 4.20283041 1.2218999 1 P 0 ;0,1=208,2=270.000000
L 4.34533002 1.22056644 4.32033002 1.22056644 1 P 0 ;0,1=209,2=270.000000
L 4.32033002 1.22056644 4.34116348 1.2274997 1 P 0 ;0,1=209,2=270.000000
L 4.34116348 1.2274997 4.32033002 1.23443346 1 P 0 ;0,1=209,2=270.000000
L 4.32033002 1.23443346 4.34533002 1.23443346 1 P 0 ;0,1=209,2=270.000000
L 4.29033002 1.24716654 4.31533002 1.24716654 1 P 0 ;0,1=210,2=270.000000
L 4.31533002 1.24716654 4.31533002 1.25783337 1 P 0 ;0,1=210,2=270.000000
L 4.28033002 1.22163327 4.25533002 1.22163327 1 P 0 ;0,1=211,2=270.000000
L 4.25533002 1.23176644 4.27074724 1.22163327 1 P 0 ;0,1=211,2=270.000000
L 4.28033002 1.23336663 4.26366388 1.22616663 1 P 0 ;0,1=211,2=270.000000
L 4.24533041 1.24716654 4.24783061 1.2485001 1 P 0 ;0,1=212,2=270.000000
L 4.24783061 1.2485001 4.24949695 1.2500997 1 P 0 ;0,1=212,2=270.000000
L 4.24949695 1.2500997 4.25033002 1.25196654 1 P 0 ;0,1=212,2=270.000000
L 4.25033002 1.25196654 4.24949695 1.2540999 1 P 0 ;0,1=212,2=270.000000
L 4.24949695 1.2540999 4.24783061 1.2557 1 P 0 ;0,1=212,2=270.000000
L 4.24783061 1.2557 4.24533041 1.2573001 1 P 0 ;0,1=212,2=270.000000
L 4.24533041 1.2573001 4.24199695 1.25783337 1 P 0 ;0,1=212,2=270.000000
L 4.24199695 1.25783337 4.22533002 1.25783337 1 P 0 ;0,1=212,2=270.000000
L 4.09533002 1.25783337 4.09533002 1.24716654 1 P 0 ;0,1=213,2=270.000000
L 4.09533002 1.24716654 4.07033002 1.24716654 1 P 0 ;0,1=213,2=270.000000
L 4.07033002 1.24716654 4.07033002 1.25783337 1 P 0 ;0,1=213,2=270.000000
L 4.08241309 1.25356663 4.08241309 1.24716654 1 P 0 ;0,1=213,2=270.000000
L 4.05033002 1.22163327 4.02533002 1.22163327 1 P 0 ;0,1=214,2=270.000000
L 4.02533002 1.22163327 4.02533002 1.22696654 1 P 0 ;0,1=214,2=270.000000
L 4.02533002 1.22696654 4.02658061 1.2290999 1 P 0 ;0,1=214,2=270.000000
L 4.02658061 1.2290999 4.02824685 1.2307 1 P 0 ;0,1=214,2=270.000000
L 4.02824685 1.2307 4.03074636 1.23203356 1 P 0 ;0,1=214,2=270.000000
L 4.03074636 1.23203356 4.03366388 1.2331 1 P 0 ;0,1=214,2=270.000000
L 4.03366388 1.2331 4.03783041 1.23336663 1 P 0 ;0,1=214,2=270.000000
L 4.03783041 1.23336663 4.04199695 1.2331 1 P 0 ;0,1=214,2=270.000000
L 4.04199695 1.2331 4.04491378 1.23203356 1 P 0 ;0,1=214,2=270.000000
L 4.04491378 1.23203356 4.04741398 1.2307 1 P 0 ;0,1=214,2=270.000000
L 4.04741398 1.2307 4.04908032 1.2290999 1 P 0 ;0,1=214,2=270.000000
L 4.04908032 1.2290999 4.05033002 1.22696654 1 P 0 ;0,1=214,2=270.000000
L 4.05033002 1.22696654 4.05033002 1.22163327 1 P 0 ;0,1=214,2=270.000000
L 4.16283041 1.2540999 4.16283041 1.25943346 1 P 0 ;0,1=215,2=270.000000
L 4.16283041 1.25943346 4.17033041 1.25943346 1 P 0 ;0,1=215,2=270.000000
L 4.17033041 1.25943346 4.17283061 1.25783337 1 P 0 ;0,1=215,2=270.000000
L 4.17283061 1.25783337 4.17449695 1.25596663 1 P 0 ;0,1=215,2=270.000000
L 4.17449695 1.25596663 4.17533002 1.2533 1 P 0 ;0,1=215,2=270.000000
L 4.17533002 1.2533 4.17449695 1.25063346 1 P 0 ;0,1=215,2=270.000000
L 4.17449695 1.25063346 4.17283061 1.24876663 1 P 0 ;0,1=215,2=270.000000
L 4.17283061 1.24876663 4.17033041 1.24716654 1 P 0 ;0,1=215,2=270.000000
L 4.17033041 1.24716654 4.16741358 1.24609961 1 P 0 ;0,1=215,2=270.000000
L 4.16741358 1.24609961 4.16408022 1.24556644 1 P 0 ;0,1=215,2=270.000000
L 4.16408022 1.24556644 4.16116339 1.24556644 1 P 0 ;0,1=215,2=270.000000
L 4.16116339 1.24556644 4.15866388 1.24609961 1 P 0 ;0,1=215,2=270.000000
L 4.15866388 1.24609961 4.15574636 1.24716654 1 P 0 ;0,1=215,2=270.000000
L 4.15574636 1.24716654 4.15324685 1.24876663 1 P 0 ;0,1=215,2=270.000000
L 4.15324685 1.24876663 4.15158061 1.25036634 1 P 0 ;0,1=215,2=270.000000
L 4.15158061 1.25036634 4.15033002 1.2524997 1 P 0 ;0,1=215,2=270.000000
L 4.15033002 1.2524997 4.15033002 1.25436644 1 P 0 ;0,1=215,2=270.000000
L 4.15033002 1.25436644 4.15116319 1.2564998 1 P 0 ;0,1=215,2=270.000000
L 4.15116319 1.2564998 4.15283032 1.2581 1 P 0 ;0,1=215,2=270.000000
L 4.1325 1.21993317 4.1075 1.21993317 1 P 0 ;0,1=216,2=270.000000
L 4.1075 1.21993317 4.1075 1.23006673 1 P 0 ;0,1=216,2=270.000000
L 4.11958307 1.22633327 4.11958307 1.21993317 1 P 0 ;0,1=216,2=270.000000
L 3.93699656 1.22963307 3.93574675 1.2307 1 P 0 ;0,1=0,2=270.000000
L 3.93574675 1.2307 3.93366388 1.2314998 1 P 0 ;0,1=0,2=270.000000
L 3.93366388 1.2314998 3.93074636 1.23203356 1 P 0 ;0,1=0,2=270.000000
L 3.93074636 1.23203356 3.92824685 1.2314998 1 P 0 ;0,1=0,2=270.000000
L 3.92824685 1.2314998 3.92658061 1.23043337 1 P 0 ;0,1=0,2=270.000000
L 3.92658061 1.23043337 3.92533002 1.22856663 1 P 0 ;0,1=0,2=270.000000
L 3.92533002 1.22856663 3.92533002 1.22136673 1 P 0 ;0,1=0,2=270.000000
L 3.92533002 1.22136673 3.95033002 1.22136673 1 P 0 ;0,1=0,2=270.000000
L 3.95033002 1.22136673 3.95033002 1.23016673 1 P 0 ;0,1=0,2=270.000000
L 3.95033002 1.23016673 3.94866378 1.23203356 1 P 0 ;0,1=0,2=270.000000
L 3.94866378 1.23203356 3.94616348 1.2331 1 P 0 ;0,1=0,2=270.000000
L 3.94616348 1.2331 3.94324675 1.23363317 1 P 0 ;0,1=0,2=270.000000
L 3.94324675 1.23363317 3.94033071 1.2331 1 P 0 ;0,1=0,2=270.000000
L 3.94033071 1.2331 3.93783041 1.2314998 1 P 0 ;0,1=0,2=270.000000
L 3.93783041 1.2314998 3.93699656 1.22963307 1 P 0 ;0,1=0,2=270.000000
L 3.93699656 1.22963307 3.93699656 1.22136673 1 P 0 ;0,1=0,2=270.000000
L 3.97741368 1.25836663 3.97616319 1.25676644 1 P 0 ;0,1=22,2=270.000000
L 3.97616319 1.25676644 3.97533002 1.2549002 1 P 0 ;0,1=22,2=270.000000
L 3.97533002 1.2549002 3.97533002 1.25276683 1 P 0 ;0,1=22,2=270.000000
L 3.97533002 1.25276683 3.97658061 1.25036634 1 P 0 ;0,1=22,2=270.000000
L 3.97658061 1.25036634 3.97866348 1.2485001 1 P 0 ;0,1=22,2=270.000000
L 3.97866348 1.2485001 3.98116368 1.24716654 1 P 0 ;0,1=22,2=270.000000
L 3.98116368 1.24716654 3.98533022 1.24609961 1 P 0 ;0,1=22,2=270.000000
L 3.98533022 1.24609961 3.98908022 1.24583297 1 P 0 ;0,1=22,2=270.000000
L 3.98908022 1.24583297 3.99283012 1.24636673 1 P 0 ;0,1=22,2=270.000000
L 3.99283012 1.24636673 3.99533041 1.24716654 1 P 0 ;0,1=22,2=270.000000
L 3.99533041 1.24716654 3.99783061 1.24876663 1 P 0 ;0,1=22,2=270.000000
L 3.99783061 1.24876663 3.99949695 1.25063346 1 P 0 ;0,1=22,2=270.000000
L 3.99949695 1.25063346 4.00033002 1.2524997 1 P 0 ;0,1=22,2=270.000000
L 4.00033002 1.2524997 4.00033002 1.25436644 1 P 0 ;0,1=22,2=270.000000
L 4.00033002 1.25436644 3.99949695 1.25623327 1 P 0 ;0,1=22,2=270.000000
L 3.99949695 1.25623327 3.99824715 1.25783337 1 P 0 ;0,1=22,2=270.000000
L 3.99824715 1.25783337 3.99658091 1.25916693 1 P 0 ;0,1=22,2=270.000000
L 3.9305 1.25833297 3.9055 1.2649997 1 P 0 ;0,1=1,2=270.000000
L 3.9055 1.2649997 3.9305 1.27166693 1 P 0 ;0,1=1,2=270.000000
L 3.92175039 1.26926644 3.92175039 1.26073297 1 P 0 ;0,1=1,2=270.000000
L 3.76339665 2.05383317 3.76089715 2.05543327 1 P 0 ;0,1=174,2=270.000000
L 3.76089715 2.05543327 3.75964665 2.0573 1 P 0 ;0,1=174,2=270.000000
L 3.75964665 2.0573 3.75923002 2.05943337 1 P 0 ;0,1=174,2=270.000000
L 3.75923002 2.05943337 3.76006319 2.0621 1 P 0 ;0,1=174,2=270.000000
L 3.76006319 2.0621 3.76214685 2.06396673 1 P 0 ;0,1=174,2=270.000000
L 3.76214685 2.06396673 3.76464636 2.0645 1 P 0 ;0,1=174,2=270.000000
L 3.76464636 2.0645 3.76714734 2.06423337 1 P 0 ;0,1=174,2=270.000000
L 3.76714734 2.06423337 3.76923022 2.06316644 1 P 0 ;0,1=174,2=270.000000
L 3.76923022 2.06316644 3.77339675 2.05783327 1 P 0 ;0,1=174,2=270.000000
L 3.77339675 2.05783327 3.77631358 2.05543327 1 P 0 ;0,1=174,2=270.000000
L 3.77631358 2.05543327 3.78048091 2.05383317 1 P 0 ;0,1=174,2=270.000000
L 3.78048091 2.05383317 3.78423002 2.0532999 1 P 0 ;0,1=174,2=270.000000
L 3.78423002 2.0532999 3.78423002 2.0645 1 P 0 ;0,1=174,2=270.000000
L 3.75923002 2.0808997 3.76006319 2.07876634 1 P 0 ;0,1=174,2=270.000000
L 3.76006319 2.07876634 3.76214685 2.07716663 1 P 0 ;0,1=174,2=270.000000
L 3.76214685 2.07716663 3.76464636 2.0760998 1 P 0 ;0,1=174,2=270.000000
L 3.76464636 2.0760998 3.76798051 2.0752999 1 P 0 ;0,1=174,2=270.000000
L 3.76798051 2.0752999 3.77173041 2.07503327 1 P 0 ;0,1=174,2=270.000000
L 3.77173041 2.07503327 3.77548041 2.0752999 1 P 0 ;0,1=174,2=270.000000
L 3.77548041 2.0752999 3.77881378 2.0760998 1 P 0 ;0,1=174,2=270.000000
L 3.77881378 2.0760998 3.78131398 2.07716663 1 P 0 ;0,1=174,2=270.000000
L 3.78131398 2.07716663 3.78339695 2.07876634 1 P 0 ;0,1=174,2=270.000000
L 3.78339695 2.07876634 3.78423002 2.0808997 1 P 0 ;0,1=174,2=270.000000
L 3.78423002 2.0808997 3.78339695 2.08303307 1 P 0 ;0,1=174,2=270.000000
L 3.78339695 2.08303307 3.78131398 2.08463327 1 P 0 ;0,1=174,2=270.000000
L 3.78131398 2.08463327 3.77881378 2.0857001 1 P 0 ;0,1=174,2=270.000000
L 3.77881378 2.0857001 3.77548041 2.0865 1 P 0 ;0,1=174,2=270.000000
L 3.77548041 2.0865 3.77173041 2.08676663 1 P 0 ;0,1=174,2=270.000000
L 3.77173041 2.08676663 3.76798051 2.0865 1 P 0 ;0,1=174,2=270.000000
L 3.76798051 2.0865 3.76464636 2.0857001 1 P 0 ;0,1=174,2=270.000000
L 3.76464636 2.0857001 3.76214685 2.08463327 1 P 0 ;0,1=174,2=270.000000
L 3.76214685 2.08463327 3.76006319 2.08303307 1 P 0 ;0,1=174,2=270.000000
L 3.76006319 2.08303307 3.75923002 2.0808997 1 P 0 ;0,1=174,2=270.000000
L 3.8225 2.0039997 3.7975 2.0039997 1 P 0 ;0,1=196,2=270.000000
L 3.7975 2.0039997 3.8024997 2.0007999 1 P 0 ;0,1=196,2=270.000000
L 3.8225 2.0007999 3.8225 2.00719951 1 P 0 ;0,1=196,2=270.000000
L 3.81958396 2.02146634 3.82166693 2.02333317 1 P 0 ;0,1=196,2=270.000000
L 3.82166693 2.02333317 3.8225 2.02546654 1 P 0 ;0,1=196,2=270.000000
L 3.8225 2.02546654 3.82166693 2.0275999 1 P 0 ;0,1=196,2=270.000000
L 3.82166693 2.0275999 3.81916742 2.02946663 1 P 0 ;0,1=196,2=270.000000
L 3.81916742 2.02946663 3.81541673 2.0308001 1 P 0 ;0,1=196,2=270.000000
L 3.81541673 2.0308001 3.81166673 2.03133337 1 P 0 ;0,1=196,2=270.000000
L 3.81166673 2.03133337 3.80708366 2.03133337 1 P 0 ;0,1=196,2=270.000000
L 3.80708366 2.03133337 3.80333366 2.0308001 1 P 0 ;0,1=196,2=270.000000
L 3.80333366 2.0308001 3.8000003 2.02946663 1 P 0 ;0,1=196,2=270.000000
L 3.8000003 2.02946663 3.79833317 2.02786644 1 P 0 ;0,1=196,2=270.000000
L 3.79833317 2.02786644 3.7975 2.0259997 1 P 0 ;0,1=196,2=270.000000
L 3.7975 2.0259997 3.79833317 2.02386634 1 P 0 ;0,1=196,2=270.000000
L 3.79833317 2.02386634 3.8000003 2.02226663 1 P 0 ;0,1=196,2=270.000000
L 3.8000003 2.02226663 3.8024997 2.0211998 1 P 0 ;0,1=196,2=270.000000
L 3.8024997 2.0211998 3.80583386 2.02066654 1 P 0 ;0,1=196,2=270.000000
L 3.80583386 2.02066654 3.8087499 2.0211998 1 P 0 ;0,1=196,2=270.000000
L 3.8087499 2.0211998 3.81166673 2.02253327 1 P 0 ;0,1=196,2=270.000000
L 3.81166673 2.02253327 3.81333386 2.02413346 1 P 0 ;0,1=196,2=270.000000
L 3.81333386 2.02413346 3.81375039 2.0259997 1 P 0 ;0,1=196,2=270.000000
L 3.81375039 2.0259997 3.81291722 2.02813307 1 P 0 ;0,1=196,2=270.000000
L 3.81291722 2.02813307 3.81083356 2.02973327 1 P 0 ;0,1=196,2=270.000000
L 3.81083356 2.02973327 3.80708366 2.03133337 1 P 0 ;0,1=196,2=270.000000
L 3.76339665 2.13383317 3.76089715 2.13543327 1 P 0 ;0,1=143,2=270.000000
L 3.76089715 2.13543327 3.75964665 2.1373 1 P 0 ;0,1=143,2=270.000000
L 3.75964665 2.1373 3.75923002 2.13943337 1 P 0 ;0,1=143,2=270.000000
L 3.75923002 2.13943337 3.76006319 2.1421 1 P 0 ;0,1=143,2=270.000000
L 3.76006319 2.1421 3.76214685 2.14396673 1 P 0 ;0,1=143,2=270.000000
L 3.76214685 2.14396673 3.76464636 2.1445 1 P 0 ;0,1=143,2=270.000000
L 3.76464636 2.1445 3.76714734 2.14423337 1 P 0 ;0,1=143,2=270.000000
L 3.76714734 2.14423337 3.76923022 2.14316644 1 P 0 ;0,1=143,2=270.000000
L 3.76923022 2.14316644 3.77339675 2.13783327 1 P 0 ;0,1=143,2=270.000000
L 3.77339675 2.13783327 3.77631358 2.13543327 1 P 0 ;0,1=143,2=270.000000
L 3.77631358 2.13543327 3.78048091 2.13383317 1 P 0 ;0,1=143,2=270.000000
L 3.78048091 2.13383317 3.78423002 2.1332999 1 P 0 ;0,1=143,2=270.000000
L 3.78423002 2.1332999 3.78423002 2.1445 1 P 0 ;0,1=143,2=270.000000
L 3.76339665 2.15583317 3.76089715 2.15743327 1 P 0 ;0,1=143,2=270.000000
L 3.76089715 2.15743327 3.75964665 2.1593 1 P 0 ;0,1=143,2=270.000000
L 3.75964665 2.1593 3.75923002 2.16143337 1 P 0 ;0,1=143,2=270.000000
L 3.75923002 2.16143337 3.76006319 2.1641 1 P 0 ;0,1=143,2=270.000000
L 3.76006319 2.1641 3.76214685 2.16596673 1 P 0 ;0,1=143,2=270.000000
L 3.76214685 2.16596673 3.76464636 2.1665 1 P 0 ;0,1=143,2=270.000000
L 3.76464636 2.1665 3.76714734 2.16623337 1 P 0 ;0,1=143,2=270.000000
L 3.76714734 2.16623337 3.76923022 2.16516644 1 P 0 ;0,1=143,2=270.000000
L 3.76923022 2.16516644 3.77339675 2.15983327 1 P 0 ;0,1=143,2=270.000000
L 3.77339675 2.15983327 3.77631358 2.15743327 1 P 0 ;0,1=143,2=270.000000
L 3.77631358 2.15743327 3.78048091 2.15583317 1 P 0 ;0,1=143,2=270.000000
L 3.78048091 2.15583317 3.78423002 2.1552999 1 P 0 ;0,1=143,2=270.000000
L 3.78423002 2.1552999 3.78423002 2.1665 1 P 0 ;0,1=143,2=270.000000
L 3.80666663 2.11393317 3.80416713 2.11553327 1 P 0 ;0,1=145,2=270.000000
L 3.80416713 2.11553327 3.80291663 2.1174 1 P 0 ;0,1=145,2=270.000000
L 3.80291663 2.1174 3.8025 2.11953337 1 P 0 ;0,1=145,2=270.000000
L 3.8025 2.11953337 3.80333317 2.1222 1 P 0 ;0,1=145,2=270.000000
L 3.80333317 2.1222 3.80541683 2.12406673 1 P 0 ;0,1=145,2=270.000000
L 3.80541683 2.12406673 3.80791634 2.1246 1 P 0 ;0,1=145,2=270.000000
L 3.80791634 2.1246 3.81041732 2.12433337 1 P 0 ;0,1=145,2=270.000000
L 3.81041732 2.12433337 3.8125002 2.12326644 1 P 0 ;0,1=145,2=270.000000
L 3.8125002 2.12326644 3.81666673 2.11793327 1 P 0 ;0,1=145,2=270.000000
L 3.81666673 2.11793327 3.81958356 2.11553327 1 P 0 ;0,1=145,2=270.000000
L 3.81958356 2.11553327 3.82375089 2.11393317 1 P 0 ;0,1=145,2=270.000000
L 3.82375089 2.11393317 3.8275 2.1133999 1 P 0 ;0,1=145,2=270.000000
L 3.8275 2.1133999 3.8275 2.1246 1 P 0 ;0,1=145,2=270.000000
L 3.8275 2.1409997 3.8025 2.1409997 1 P 0 ;0,1=145,2=270.000000
L 3.8025 2.1409997 3.8074997 2.1377999 1 P 0 ;0,1=145,2=270.000000
L 3.8275 2.1377999 3.8275 2.14419951 1 P 0 ;0,1=145,2=270.000000
L 3.78423002 1.8188997 3.75923002 1.8188997 1 P 0 ;0,1=141,2=270.000000
L 3.75923002 1.8188997 3.76422972 1.8156999 1 P 0 ;0,1=141,2=270.000000
L 3.78423002 1.8156999 3.78423002 1.82209951 1 P 0 ;0,1=141,2=270.000000
L 3.78423002 1.8441 3.75923002 1.8441 1 P 0 ;0,1=141,2=270.000000
L 3.75923002 1.8441 3.77714675 1.83423297 1 P 0 ;0,1=141,2=270.000000
L 3.77714675 1.83423297 3.77714675 1.84756693 1 P 0 ;0,1=141,2=270.000000
L 3.81923002 1.9388997 3.79423002 1.9388997 1 P 0 ;0,1=32,2=270.000000
L 3.79423002 1.9388997 3.79922972 1.9356999 1 P 0 ;0,1=32,2=270.000000
L 3.81923002 1.9356999 3.81923002 1.94209951 1 P 0 ;0,1=32,2=270.000000
L 3.81923002 1.96036654 3.81381378 1.9608997 1 P 0 ;0,1=32,2=270.000000
L 3.81381378 1.9608997 3.80923071 1.9617 1 P 0 ;0,1=32,2=270.000000
L 3.80923071 1.9617 3.80506339 1.96276644 1 P 0 ;0,1=32,2=270.000000
L 3.80506339 1.96276644 3.80048022 1.9641 1 P 0 ;0,1=32,2=270.000000
L 3.80048022 1.9641 3.79423002 1.96623337 1 P 0 ;0,1=32,2=270.000000
L 3.79423002 1.96623337 3.79423002 1.95556654 1 P 0 ;0,1=32,2=270.000000
L 3.78423002 1.8988997 3.75923002 1.8988997 1 P 0 ;0,1=13,2=270.000000
L 3.75923002 1.8988997 3.76422972 1.8956999 1 P 0 ;0,1=13,2=270.000000
L 3.78423002 1.8956999 3.78423002 1.90209951 1 P 0 ;0,1=13,2=270.000000
L 3.77381407 1.91583317 3.77089656 1.9176999 1 P 0 ;0,1=13,2=270.000000
L 3.77089656 1.9176999 3.76923022 1.9193 1 P 0 ;0,1=13,2=270.000000
L 3.76923022 1.9193 3.76839705 1.92143337 1 P 0 ;0,1=13,2=270.000000
L 3.76839705 1.92143337 3.76923022 1.9233002 1 P 0 ;0,1=13,2=270.000000
L 3.76923022 1.9233002 3.77089656 1.92463327 1 P 0 ;0,1=13,2=270.000000
L 3.77089656 1.92463327 3.77339675 1.9257001 1 P 0 ;0,1=13,2=270.000000
L 3.77339675 1.9257001 3.77631358 1.92596673 1 P 0 ;0,1=13,2=270.000000
L 3.77631358 1.92596673 3.77881378 1.9257001 1 P 0 ;0,1=13,2=270.000000
L 3.77881378 1.9257001 3.78131398 1.92463327 1 P 0 ;0,1=13,2=270.000000
L 3.78131398 1.92463327 3.78339695 1.92303307 1 P 0 ;0,1=13,2=270.000000
L 3.78339695 1.92303307 3.78423002 1.92116683 1 P 0 ;0,1=13,2=270.000000
L 3.78423002 1.92116683 3.78339695 1.91903346 1 P 0 ;0,1=13,2=270.000000
L 3.78339695 1.91903346 3.78089744 1.91716663 1 P 0 ;0,1=13,2=270.000000
L 3.78089744 1.91716663 3.77714675 1.9160998 1 P 0 ;0,1=13,2=270.000000
L 3.77714675 1.9160998 3.77298022 1.91583317 1 P 0 ;0,1=13,2=270.000000
L 3.77298022 1.91583317 3.76756388 1.91636634 1 P 0 ;0,1=13,2=270.000000
L 3.76756388 1.91636634 3.76464636 1.91716663 1 P 0 ;0,1=13,2=270.000000
L 3.76464636 1.91716663 3.76173032 1.9184997 1 P 0 ;0,1=13,2=270.000000
L 3.76173032 1.9184997 3.75964665 1.92036654 1 P 0 ;0,1=13,2=270.000000
L 3.75964665 1.92036654 3.75923002 1.92223327 1 P 0 ;0,1=13,2=270.000000
L 3.75923002 1.92223327 3.76006319 1.9241 1 P 0 ;0,1=13,2=270.000000
L 3.76006319 1.9241 3.76214685 1.92543356 1 P 0 ;0,1=13,2=270.000000
L 3.78423002 1.9738997 3.75923002 1.9738997 1 P 0 ;0,1=217,2=270.000000
L 3.75923002 1.9738997 3.76422972 1.9706999 1 P 0 ;0,1=217,2=270.000000
L 3.78423002 1.9706999 3.78423002 1.97709951 1 P 0 ;0,1=217,2=270.000000
L 3.78423002 1.9958997 3.78381348 1.99776644 1 P 0 ;0,1=217,2=270.000000
L 3.78381348 1.99776644 3.78256378 1.9998998 1 P 0 ;0,1=217,2=270.000000
L 3.78256378 1.9998998 3.78048091 2.00123337 1 P 0 ;0,1=217,2=270.000000
L 3.78048091 2.00123337 3.77756329 2.00176663 1 P 0 ;0,1=217,2=270.000000
L 3.77756329 2.00176663 3.77464724 2.00123337 1 P 0 ;0,1=217,2=270.000000
L 3.77464724 2.00123337 3.77214705 1.99963327 1 P 0 ;0,1=217,2=270.000000
L 3.77214705 1.99963327 3.77089656 1.99723327 1 P 0 ;0,1=217,2=270.000000
L 3.77089656 1.99723327 3.77089656 1.99456663 1 P 0 ;0,1=217,2=270.000000
L 3.77089656 1.99456663 3.77006339 1.99296654 1 P 0 ;0,1=217,2=270.000000
L 3.77006339 1.99296654 3.76798051 1.99163297 1 P 0 ;0,1=217,2=270.000000
L 3.76798051 1.99163297 3.76506368 1.9910998 1 P 0 ;0,1=217,2=270.000000
L 3.76506368 1.9910998 3.76214685 1.9919001 1 P 0 ;0,1=217,2=270.000000
L 3.76214685 1.9919001 3.76006319 1.99376634 1 P 0 ;0,1=217,2=270.000000
L 3.76006319 1.99376634 3.75923002 1.9958997 1 P 0 ;0,1=217,2=270.000000
L 3.75923002 1.9958997 3.76006319 1.99803307 1 P 0 ;0,1=217,2=270.000000
L 3.76006319 1.99803307 3.76214685 1.9998998 1 P 0 ;0,1=217,2=270.000000
L 3.76214685 1.9998998 3.76506368 2.0007001 1 P 0 ;0,1=217,2=270.000000
L 3.76506368 2.0007001 3.76798051 2.00016644 1 P 0 ;0,1=217,2=270.000000
L 3.76798051 2.00016644 3.77006339 1.99883337 1 P 0 ;0,1=217,2=270.000000
L 3.77006339 1.99883337 3.77089656 1.99723327 1 P 0 ;0,1=217,2=270.000000
L 3.77089656 1.99723327 3.77089656 1.99456663 1 P 0 ;0,1=217,2=270.000000
L 3.77089656 1.99456663 3.77214705 1.99216663 1 P 0 ;0,1=217,2=270.000000
L 3.77214705 1.99216663 3.77464724 1.99056654 1 P 0 ;0,1=217,2=270.000000
L 3.77464724 1.99056654 3.77756329 1.99003327 1 P 0 ;0,1=217,2=270.000000
L 3.77756329 1.99003327 3.78048091 1.99056654 1 P 0 ;0,1=217,2=270.000000
L 3.78048091 1.99056654 3.78256378 1.9919001 1 P 0 ;0,1=217,2=270.000000
L 3.78256378 1.9919001 3.78381348 1.99403346 1 P 0 ;0,1=217,2=270.000000
L 3.78381348 1.99403346 3.78423002 1.9958997 1 P 0 ;0,1=217,2=270.000000
L 3.81923002 1.6988997 3.79423002 1.6988997 1 P 0 ;0,1=3,2=270.000000
L 3.79423002 1.6988997 3.79922972 1.6956999 1 P 0 ;0,1=3,2=270.000000
L 3.81923002 1.6956999 3.81923002 1.70209951 1 P 0 ;0,1=3,2=270.000000
L 3.81923002 1.7208997 3.79423002 1.7208997 1 P 0 ;0,1=3,2=270.000000
L 3.79423002 1.7208997 3.79922972 1.7176999 1 P 0 ;0,1=3,2=270.000000
L 3.81923002 1.7176999 3.81923002 1.72409951 1 P 0 ;0,1=3,2=270.000000
L 3.81631398 1.64536634 3.81839695 1.64723317 1 P 0 ;0,1=14,2=270.000000
L 3.81839695 1.64723317 3.81923002 1.64936654 1 P 0 ;0,1=14,2=270.000000
L 3.81923002 1.64936654 3.81839695 1.6514999 1 P 0 ;0,1=14,2=270.000000
L 3.81839695 1.6514999 3.81589744 1.65336663 1 P 0 ;0,1=14,2=270.000000
L 3.81589744 1.65336663 3.81214675 1.6547001 1 P 0 ;0,1=14,2=270.000000
L 3.81214675 1.6547001 3.80839675 1.65523337 1 P 0 ;0,1=14,2=270.000000
L 3.80839675 1.65523337 3.80381368 1.65523337 1 P 0 ;0,1=14,2=270.000000
L 3.80381368 1.65523337 3.80006368 1.6547001 1 P 0 ;0,1=14,2=270.000000
L 3.80006368 1.6547001 3.79673032 1.65336663 1 P 0 ;0,1=14,2=270.000000
L 3.79673032 1.65336663 3.79506319 1.65176644 1 P 0 ;0,1=14,2=270.000000
L 3.79506319 1.65176644 3.79423002 1.6498997 1 P 0 ;0,1=14,2=270.000000
L 3.79423002 1.6498997 3.79506319 1.64776634 1 P 0 ;0,1=14,2=270.000000
L 3.79506319 1.64776634 3.79673032 1.64616663 1 P 0 ;0,1=14,2=270.000000
L 3.79673032 1.64616663 3.79922972 1.6450998 1 P 0 ;0,1=14,2=270.000000
L 3.79922972 1.6450998 3.80256388 1.64456654 1 P 0 ;0,1=14,2=270.000000
L 3.80256388 1.64456654 3.80547992 1.6450998 1 P 0 ;0,1=14,2=270.000000
L 3.80547992 1.6450998 3.80839675 1.64643327 1 P 0 ;0,1=14,2=270.000000
L 3.80839675 1.64643327 3.81006388 1.64803346 1 P 0 ;0,1=14,2=270.000000
L 3.81006388 1.64803346 3.81048041 1.6498997 1 P 0 ;0,1=14,2=270.000000
L 3.81048041 1.6498997 3.80964724 1.65203307 1 P 0 ;0,1=14,2=270.000000
L 3.80964724 1.65203307 3.80756358 1.65363327 1 P 0 ;0,1=14,2=270.000000
L 3.80756358 1.65363327 3.80381368 1.65523337 1 P 0 ;0,1=14,2=270.000000
L 3.78423002 1.6688997 3.75923002 1.6688997 1 P 0 ;0,1=133,2=270.000000
L 3.75923002 1.6688997 3.76422972 1.6656999 1 P 0 ;0,1=133,2=270.000000
L 3.78423002 1.6656999 3.78423002 1.67209951 1 P 0 ;0,1=133,2=270.000000
L 3.75923002 1.6908997 3.76006319 1.68876634 1 P 0 ;0,1=133,2=270.000000
L 3.76006319 1.68876634 3.76214685 1.68716663 1 P 0 ;0,1=133,2=270.000000
L 3.76214685 1.68716663 3.76464636 1.6860998 1 P 0 ;0,1=133,2=270.000000
L 3.76464636 1.6860998 3.76798051 1.6852999 1 P 0 ;0,1=133,2=270.000000
L 3.76798051 1.6852999 3.77173041 1.68503327 1 P 0 ;0,1=133,2=270.000000
L 3.77173041 1.68503327 3.77548041 1.6852999 1 P 0 ;0,1=133,2=270.000000
L 3.77548041 1.6852999 3.77881378 1.6860998 1 P 0 ;0,1=133,2=270.000000
L 3.77881378 1.6860998 3.78131398 1.68716663 1 P 0 ;0,1=133,2=270.000000
L 3.78131398 1.68716663 3.78339695 1.68876634 1 P 0 ;0,1=133,2=270.000000
L 3.78339695 1.68876634 3.78423002 1.6908997 1 P 0 ;0,1=133,2=270.000000
L 3.78423002 1.6908997 3.78339695 1.69303307 1 P 0 ;0,1=133,2=270.000000
L 3.78339695 1.69303307 3.78131398 1.69463327 1 P 0 ;0,1=133,2=270.000000
L 3.78131398 1.69463327 3.77881378 1.6957001 1 P 0 ;0,1=133,2=270.000000
L 3.77881378 1.6957001 3.77548041 1.6965 1 P 0 ;0,1=133,2=270.000000
L 3.77548041 1.6965 3.77173041 1.69676663 1 P 0 ;0,1=133,2=270.000000
L 3.77173041 1.69676663 3.76798051 1.6965 1 P 0 ;0,1=133,2=270.000000
L 3.76798051 1.6965 3.76464636 1.6957001 1 P 0 ;0,1=133,2=270.000000
L 3.76464636 1.6957001 3.76214685 1.69463327 1 P 0 ;0,1=133,2=270.000000
L 3.76214685 1.69463327 3.76006319 1.69303307 1 P 0 ;0,1=133,2=270.000000
L 3.76006319 1.69303307 3.75923002 1.6908997 1 P 0 ;0,1=133,2=270.000000
L 3.7875 1.7239997 3.7625 1.7239997 1 P 0 ;0,1=6,2=270.000000
L 3.7625 1.7239997 3.7674997 1.7207999 1 P 0 ;0,1=6,2=270.000000
L 3.7875 1.7207999 3.7875 1.72719951 1 P 0 ;0,1=6,2=270.000000
L 3.76666663 1.74093317 3.76416713 1.74253327 1 P 0 ;0,1=6,2=270.000000
L 3.76416713 1.74253327 3.76291663 1.7444 1 P 0 ;0,1=6,2=270.000000
L 3.76291663 1.7444 3.7625 1.74653337 1 P 0 ;0,1=6,2=270.000000
L 3.7625 1.74653337 3.76333317 1.7492 1 P 0 ;0,1=6,2=270.000000
L 3.76333317 1.7492 3.76541683 1.75106673 1 P 0 ;0,1=6,2=270.000000
L 3.76541683 1.75106673 3.76791634 1.7516 1 P 0 ;0,1=6,2=270.000000
L 3.76791634 1.7516 3.77041732 1.75133337 1 P 0 ;0,1=6,2=270.000000
L 3.77041732 1.75133337 3.7725002 1.75026644 1 P 0 ;0,1=6,2=270.000000
L 3.7725002 1.75026644 3.77666673 1.74493327 1 P 0 ;0,1=6,2=270.000000
L 3.77666673 1.74493327 3.77958356 1.74253327 1 P 0 ;0,1=6,2=270.000000
L 3.77958356 1.74253327 3.78375089 1.74093317 1 P 0 ;0,1=6,2=270.000000
L 3.78375089 1.74093317 3.7875 1.7403999 1 P 0 ;0,1=6,2=270.000000
L 3.7875 1.7403999 3.7875 1.7516 1 P 0 ;0,1=6,2=270.000000
L 3.8225 1.7939997 3.7975 1.7939997 1 P 0 ;0,1=218,2=270.000000
L 3.7975 1.7939997 3.8024997 1.7907999 1 P 0 ;0,1=218,2=270.000000
L 3.8225 1.7907999 3.8225 1.79719951 1 P 0 ;0,1=218,2=270.000000
L 3.81750039 1.81013327 3.82041713 1.81173297 1 P 0 ;0,1=218,2=270.000000
L 3.82041713 1.81173297 3.82208346 1.81386634 1 P 0 ;0,1=218,2=270.000000
L 3.82208346 1.81386634 3.8225 1.81626683 1 P 0 ;0,1=218,2=270.000000
L 3.8225 1.81626683 3.82208346 1.8184002 1 P 0 ;0,1=218,2=270.000000
L 3.82208346 1.8184002 3.82000059 1.82053356 1 P 0 ;0,1=218,2=270.000000
L 3.82000059 1.82053356 3.81750039 1.82186663 1 P 0 ;0,1=218,2=270.000000
L 3.81750039 1.82186663 3.8150001 1.82213317 1 P 0 ;0,1=218,2=270.000000
L 3.8150001 1.82213317 3.81208406 1.8216 1 P 0 ;0,1=218,2=270.000000
L 3.81208406 1.8216 3.81000039 1.81973327 1 P 0 ;0,1=218,2=270.000000
L 3.81000039 1.81973327 3.80916654 1.81786644 1 P 0 ;0,1=218,2=270.000000
L 3.80916654 1.81786644 3.80916654 1.81546654 1 P 0 ;0,1=218,2=270.000000
L 3.80916654 1.81786644 3.80791673 1.81946663 1 P 0 ;0,1=218,2=270.000000
L 3.80791673 1.81946663 3.80583386 1.8208001 1 P 0 ;0,1=218,2=270.000000
L 3.80583386 1.8208001 3.80333366 1.82133337 1 P 0 ;0,1=218,2=270.000000
L 3.80333366 1.82133337 3.80083346 1.8208001 1 P 0 ;0,1=218,2=270.000000
L 3.80083346 1.8208001 3.79875059 1.81946663 1 P 0 ;0,1=218,2=270.000000
L 3.79875059 1.81946663 3.7975 1.81706663 1 P 0 ;0,1=218,2=270.000000
L 3.7975 1.81706663 3.79791663 1.81466663 1 P 0 ;0,1=218,2=270.000000
L 3.79791663 1.81466663 3.79958366 1.81226663 1 P 0 ;0,1=218,2=270.000000
L 3.78423002 1.6098997 3.78381348 1.61176644 1 P 0 ;0,1=16,2=270.000000
L 3.78381348 1.61176644 3.78256378 1.6138998 1 P 0 ;0,1=16,2=270.000000
L 3.78256378 1.6138998 3.78048091 1.61523337 1 P 0 ;0,1=16,2=270.000000
L 3.78048091 1.61523337 3.77756329 1.61576663 1 P 0 ;0,1=16,2=270.000000
L 3.77756329 1.61576663 3.77464724 1.61523337 1 P 0 ;0,1=16,2=270.000000
L 3.77464724 1.61523337 3.77214705 1.61363327 1 P 0 ;0,1=16,2=270.000000
L 3.77214705 1.61363327 3.77089656 1.61123327 1 P 0 ;0,1=16,2=270.000000
L 3.77089656 1.61123327 3.77089656 1.60856663 1 P 0 ;0,1=16,2=270.000000
L 3.77089656 1.60856663 3.77006339 1.60696654 1 P 0 ;0,1=16,2=270.000000
L 3.77006339 1.60696654 3.76798051 1.60563297 1 P 0 ;0,1=16,2=270.000000
L 3.76798051 1.60563297 3.76506368 1.6050998 1 P 0 ;0,1=16,2=270.000000
L 3.76506368 1.6050998 3.76214685 1.6059001 1 P 0 ;0,1=16,2=270.000000
L 3.76214685 1.6059001 3.76006319 1.60776634 1 P 0 ;0,1=16,2=270.000000
L 3.76006319 1.60776634 3.75923002 1.6098997 1 P 0 ;0,1=16,2=270.000000
L 3.75923002 1.6098997 3.76006319 1.61203307 1 P 0 ;0,1=16,2=270.000000
L 3.76006319 1.61203307 3.76214685 1.6138998 1 P 0 ;0,1=16,2=270.000000
L 3.76214685 1.6138998 3.76506368 1.6147001 1 P 0 ;0,1=16,2=270.000000
L 3.76506368 1.6147001 3.76798051 1.61416644 1 P 0 ;0,1=16,2=270.000000
L 3.76798051 1.61416644 3.77006339 1.61283337 1 P 0 ;0,1=16,2=270.000000
L 3.77006339 1.61283337 3.77089656 1.61123327 1 P 0 ;0,1=16,2=270.000000
L 3.77089656 1.61123327 3.77089656 1.60856663 1 P 0 ;0,1=16,2=270.000000
L 3.77089656 1.60856663 3.77214705 1.60616663 1 P 0 ;0,1=16,2=270.000000
L 3.77214705 1.60616663 3.77464724 1.60456654 1 P 0 ;0,1=16,2=270.000000
L 3.77464724 1.60456654 3.77756329 1.60403327 1 P 0 ;0,1=16,2=270.000000
L 3.77756329 1.60403327 3.78048091 1.60456654 1 P 0 ;0,1=16,2=270.000000
L 3.78048091 1.60456654 3.78256378 1.6059001 1 P 0 ;0,1=16,2=270.000000
L 3.78256378 1.6059001 3.78381348 1.60803346 1 P 0 ;0,1=16,2=270.000000
L 3.78381348 1.60803346 3.78423002 1.6098997 1 P 0 ;0,1=16,2=270.000000
L 3.81548091 1.48903327 3.81756378 1.49063297 1 P 0 ;0,1=20,2=270.000000
L 3.81756378 1.49063297 3.81881348 1.4924997 1 P 0 ;0,1=20,2=270.000000
L 3.81881348 1.4924997 3.81923002 1.4948997 1 P 0 ;0,1=20,2=270.000000
L 3.81923002 1.4948997 3.81839695 1.4973002 1 P 0 ;0,1=20,2=270.000000
L 3.81839695 1.4973002 3.81673061 1.49916644 1 P 0 ;0,1=20,2=270.000000
L 3.81673061 1.49916644 3.81381378 1.5005 1 P 0 ;0,1=20,2=270.000000
L 3.81381378 1.5005 3.81048041 1.50076663 1 P 0 ;0,1=20,2=270.000000
L 3.81048041 1.50076663 3.80714705 1.50023337 1 P 0 ;0,1=20,2=270.000000
L 3.80714705 1.50023337 3.80506339 1.4988998 1 P 0 ;0,1=20,2=270.000000
L 3.80506339 1.4988998 3.80339705 1.49703307 1 P 0 ;0,1=20,2=270.000000
L 3.80339705 1.49703307 3.80298051 1.49516683 1 P 0 ;0,1=20,2=270.000000
L 3.80298051 1.49516683 3.80339705 1.4933 1 P 0 ;0,1=20,2=270.000000
L 3.80339705 1.4933 3.80506339 1.4909001 1 P 0 ;0,1=20,2=270.000000
L 3.80506339 1.4909001 3.79423002 1.4916999 1 P 0 ;0,1=20,2=270.000000
L 3.79423002 1.4916999 3.79423002 1.4988998 1 P 0 ;0,1=20,2=270.000000
L 3.81923002 1.57436654 3.81381378 1.5748997 1 P 0 ;0,1=138,2=270.000000
L 3.81381378 1.5748997 3.80923071 1.5757 1 P 0 ;0,1=138,2=270.000000
L 3.80923071 1.5757 3.80506339 1.57676644 1 P 0 ;0,1=138,2=270.000000
L 3.80506339 1.57676644 3.80048022 1.5781 1 P 0 ;0,1=138,2=270.000000
L 3.80048022 1.5781 3.79423002 1.58023337 1 P 0 ;0,1=138,2=270.000000
L 3.79423002 1.58023337 3.79423002 1.56956654 1 P 0 ;0,1=138,2=270.000000
L 3.78208406 1.51993317 3.77916654 1.5217999 1 P 0 ;0,1=8,2=270.000000
L 3.77916654 1.5217999 3.7775002 1.5234 1 P 0 ;0,1=8,2=270.000000
L 3.7775002 1.5234 3.77666703 1.52553337 1 P 0 ;0,1=8,2=270.000000
L 3.77666703 1.52553337 3.7775002 1.5274002 1 P 0 ;0,1=8,2=270.000000
L 3.7775002 1.5274002 3.77916654 1.52873327 1 P 0 ;0,1=8,2=270.000000
L 3.77916654 1.52873327 3.78166673 1.5298001 1 P 0 ;0,1=8,2=270.000000
L 3.78166673 1.5298001 3.78458356 1.53006673 1 P 0 ;0,1=8,2=270.000000
L 3.78458356 1.53006673 3.78708376 1.5298001 1 P 0 ;0,1=8,2=270.000000
L 3.78708376 1.5298001 3.78958396 1.52873327 1 P 0 ;0,1=8,2=270.000000
L 3.78958396 1.52873327 3.79166693 1.52713307 1 P 0 ;0,1=8,2=270.000000
L 3.79166693 1.52713307 3.7925 1.52526683 1 P 0 ;0,1=8,2=270.000000
L 3.7925 1.52526683 3.79166693 1.52313346 1 P 0 ;0,1=8,2=270.000000
L 3.79166693 1.52313346 3.78916742 1.52126663 1 P 0 ;0,1=8,2=270.000000
L 3.78916742 1.52126663 3.78541673 1.5201998 1 P 0 ;0,1=8,2=270.000000
L 3.78541673 1.5201998 3.7812502 1.51993317 1 P 0 ;0,1=8,2=270.000000
L 3.7812502 1.51993317 3.77583386 1.52046634 1 P 0 ;0,1=8,2=270.000000
L 3.77583386 1.52046634 3.77291634 1.52126663 1 P 0 ;0,1=8,2=270.000000
L 3.77291634 1.52126663 3.7700003 1.5225997 1 P 0 ;0,1=8,2=270.000000
L 3.7700003 1.5225997 3.76791663 1.52446654 1 P 0 ;0,1=8,2=270.000000
L 3.76791663 1.52446654 3.7675 1.52633327 1 P 0 ;0,1=8,2=270.000000
L 3.7675 1.52633327 3.76833317 1.5282 1 P 0 ;0,1=8,2=270.000000
L 3.76833317 1.5282 3.77041683 1.52953356 1 P 0 ;0,1=8,2=270.000000
L 3.78423002 1.4531 3.75923002 1.4531 1 P 0 ;0,1=11,2=270.000000
L 3.75923002 1.4531 3.77714675 1.44323297 1 P 0 ;0,1=11,2=270.000000
L 3.77714675 1.44323297 3.77714675 1.45656693 1 P 0 ;0,1=11,2=270.000000
L 3.76339665 1.36983317 3.76089715 1.37143327 1 P 0 ;0,1=4,2=270.000000
L 3.76089715 1.37143327 3.75964665 1.3733 1 P 0 ;0,1=4,2=270.000000
L 3.75964665 1.3733 3.75923002 1.37543337 1 P 0 ;0,1=4,2=270.000000
L 3.75923002 1.37543337 3.76006319 1.3781 1 P 0 ;0,1=4,2=270.000000
L 3.76006319 1.3781 3.76214685 1.37996673 1 P 0 ;0,1=4,2=270.000000
L 3.76214685 1.37996673 3.76464636 1.3805 1 P 0 ;0,1=4,2=270.000000
L 3.76464636 1.3805 3.76714734 1.38023337 1 P 0 ;0,1=4,2=270.000000
L 3.76714734 1.38023337 3.76923022 1.37916644 1 P 0 ;0,1=4,2=270.000000
L 3.76923022 1.37916644 3.77339675 1.37383327 1 P 0 ;0,1=4,2=270.000000
L 3.77339675 1.37383327 3.77631358 1.37143327 1 P 0 ;0,1=4,2=270.000000
L 3.77631358 1.37143327 3.78048091 1.36983317 1 P 0 ;0,1=4,2=270.000000
L 3.78048091 1.36983317 3.78423002 1.3692999 1 P 0 ;0,1=4,2=270.000000
L 3.78423002 1.3692999 3.78423002 1.3805 1 P 0 ;0,1=4,2=270.000000
L 3.8375 1.3449997 3.8125 1.3449997 1 P 0 ;0,1=2,2=270.000000
L 3.8125 1.3449997 3.8174997 1.3417999 1 P 0 ;0,1=2,2=270.000000
L 3.8375 1.3417999 3.8375 1.34819951 1 P 0 ;0,1=2,2=270.000000
L 3.82750039 1.39413327 3.83041713 1.39573297 1 P 0 ;0,1=10,2=270.000000
L 3.83041713 1.39573297 3.83208346 1.39786634 1 P 0 ;0,1=10,2=270.000000
L 3.83208346 1.39786634 3.8325 1.40026683 1 P 0 ;0,1=10,2=270.000000
L 3.8325 1.40026683 3.83208346 1.4024002 1 P 0 ;0,1=10,2=270.000000
L 3.83208346 1.4024002 3.83000059 1.40453356 1 P 0 ;0,1=10,2=270.000000
L 3.83000059 1.40453356 3.82750039 1.40586663 1 P 0 ;0,1=10,2=270.000000
L 3.82750039 1.40586663 3.8250001 1.40613317 1 P 0 ;0,1=10,2=270.000000
L 3.8250001 1.40613317 3.82208406 1.4056 1 P 0 ;0,1=10,2=270.000000
L 3.82208406 1.4056 3.82000039 1.40373327 1 P 0 ;0,1=10,2=270.000000
L 3.82000039 1.40373327 3.81916654 1.40186644 1 P 0 ;0,1=10,2=270.000000
L 3.81916654 1.40186644 3.81916654 1.39946654 1 P 0 ;0,1=10,2=270.000000
L 3.81916654 1.40186644 3.81791673 1.40346663 1 P 0 ;0,1=10,2=270.000000
L 3.81791673 1.40346663 3.81583386 1.4048001 1 P 0 ;0,1=10,2=270.000000
L 3.81583386 1.4048001 3.81333366 1.40533337 1 P 0 ;0,1=10,2=270.000000
L 3.81333366 1.40533337 3.81083346 1.4048001 1 P 0 ;0,1=10,2=270.000000
L 3.81083346 1.4048001 3.80875059 1.40346663 1 P 0 ;0,1=10,2=270.000000
L 3.80875059 1.40346663 3.8075 1.40106663 1 P 0 ;0,1=10,2=270.000000
L 3.8075 1.40106663 3.80791663 1.39866663 1 P 0 ;0,1=10,2=270.000000
L 3.80791663 1.39866663 3.80958366 1.39626663 1 P 0 ;0,1=10,2=270.000000
L 5.33 1.657 5.33 1.533 1 P 0 
L 5.16 1.657 5.33 1.657 1 P 0 
L 5.16 1.533 5.16 1.657 1 P 0 
L 5.33 1.533 5.16 1.533 1 P 0 
L 5.38193327 1.36791624 5.37963307 1.36946683 1 P 0 ;0,1=219,2=0.000000
L 5.37963307 1.36946683 5.3769503 1.3705 1 P 0 ;0,1=219,2=0.000000
L 5.3769503 1.3705 5.37388356 1.3705 1 P 0 ;0,1=219,2=0.000000
L 5.37388356 1.3705 5.37043287 1.36894931 1 P 0 ;0,1=219,2=0.000000
L 5.37043287 1.36894931 5.3677501 1.36636654 1 P 0 ;0,1=219,2=0.000000
L 5.3677501 1.36636654 5.36583317 1.36326624 1 P 0 ;0,1=219,2=0.000000
L 5.36583317 1.36326624 5.36429951 1.3580998 1 P 0 ;0,1=219,2=0.000000
L 5.36429951 1.3580998 5.36391624 1.3534498 1 P 0 ;0,1=219,2=0.000000
L 5.36391624 1.3534498 5.36468337 1.3487999 1 P 0 ;0,1=219,2=0.000000
L 5.36468337 1.3487999 5.36583317 1.34569961 1 P 0 ;0,1=219,2=0.000000
L 5.36583317 1.34569961 5.36813337 1.34259931 1 P 0 ;0,1=219,2=0.000000
L 5.36813337 1.34259931 5.37081683 1.34053307 1 P 0 ;0,1=219,2=0.000000
L 5.37081683 1.34053307 5.37349961 1.3395 1 P 0 ;0,1=219,2=0.000000
L 5.37349961 1.3395 5.37618307 1.3395 1 P 0 ;0,1=219,2=0.000000
L 5.37618307 1.3395 5.37886654 1.34053307 1 P 0 ;0,1=219,2=0.000000
L 5.37886654 1.34053307 5.38116673 1.34208278 1 P 0 ;0,1=219,2=0.000000
L 5.38116673 1.34208278 5.38308366 1.34414892 1 P 0 ;0,1=219,2=0.000000
L 5.40449961 1.3395 5.40449961 1.3705 1 P 0 ;0,1=219,2=0.000000
L 5.40449961 1.3705 5.3998999 1.3643003 1 P 0 ;0,1=219,2=0.000000
L 5.3998999 1.3395 5.40909931 1.3395 1 P 0 ;0,1=219,2=0.000000
L 5.43473307 1.3395 5.43549961 1.34621614 1 P 0 ;0,1=219,2=0.000000
L 5.43549961 1.34621614 5.4366501 1.35189921 1 P 0 ;0,1=219,2=0.000000
L 5.4366501 1.35189921 5.43818307 1.35706663 1 P 0 ;0,1=219,2=0.000000
L 5.43818307 1.35706663 5.4401 1.3627497 1 P 0 ;0,1=219,2=0.000000
L 5.4401 1.3627497 5.44316673 1.3705 1 P 0 ;0,1=219,2=0.000000
L 5.44316673 1.3705 5.42783317 1.3705 1 P 0 ;0,1=219,2=0.000000
L 5.45806663 1.34414892 5.46036614 1.34156614 1 P 0 ;0,1=219,2=0.000000
L 5.46036614 1.34156614 5.46304961 1.34001654 1 P 0 ;0,1=219,2=0.000000
L 5.46304961 1.34001654 5.46649961 1.3395 1 P 0 ;0,1=219,2=0.000000
L 5.46649961 1.3395 5.4699503 1.34053307 1 P 0 ;0,1=219,2=0.000000
L 5.4699503 1.34053307 5.47263307 1.34259931 1 P 0 ;0,1=219,2=0.000000
L 5.47263307 1.34259931 5.47455 1.34621614 1 P 0 ;0,1=219,2=0.000000
L 5.47455 1.34621614 5.47493327 1.35034951 1 P 0 ;0,1=219,2=0.000000
L 5.47493327 1.35034951 5.47416673 1.35448287 1 P 0 ;0,1=219,2=0.000000
L 5.47416673 1.35448287 5.4722498 1.35706663 1 P 0 ;0,1=219,2=0.000000
L 5.4722498 1.35706663 5.46956634 1.35913287 1 P 0 ;0,1=219,2=0.000000
L 5.46956634 1.35913287 5.46688356 1.35964941 1 P 0 ;0,1=219,2=0.000000
L 5.46688356 1.35964941 5.4642001 1.35913287 1 P 0 ;0,1=219,2=0.000000
L 5.4642001 1.35913287 5.4607501 1.35706663 1 P 0 ;0,1=219,2=0.000000
L 5.4607501 1.35706663 5.4618999 1.3705 1 P 0 ;0,1=219,2=0.000000
L 5.4618999 1.3705 5.4722498 1.3705 1 P 0 ;0,1=219,2=0.000000
L 5.33 1.407 5.33 1.283 1 P 0 
L 5.16 1.283 5.16 1.407 1 P 0 
L 5.16 1.407 5.33 1.407 1 P 0 
L 5.33 1.283 5.16 1.283 1 P 0 
L 5.38193327 1.28291624 5.37963307 1.28446683 1 P 0 ;0,1=220,2=0.000000
L 5.37963307 1.28446683 5.3769503 1.2855 1 P 0 ;0,1=220,2=0.000000
L 5.3769503 1.2855 5.37388356 1.2855 1 P 0 ;0,1=220,2=0.000000
L 5.37388356 1.2855 5.37043287 1.28394931 1 P 0 ;0,1=220,2=0.000000
L 5.37043287 1.28394931 5.3677501 1.28136654 1 P 0 ;0,1=220,2=0.000000
L 5.3677501 1.28136654 5.36583317 1.27826624 1 P 0 ;0,1=220,2=0.000000
L 5.36583317 1.27826624 5.36429951 1.2730998 1 P 0 ;0,1=220,2=0.000000
L 5.36429951 1.2730998 5.36391624 1.2684498 1 P 0 ;0,1=220,2=0.000000
L 5.36391624 1.2684498 5.36468337 1.2637999 1 P 0 ;0,1=220,2=0.000000
L 5.36468337 1.2637999 5.36583317 1.26069961 1 P 0 ;0,1=220,2=0.000000
L 5.36583317 1.26069961 5.36813337 1.25759931 1 P 0 ;0,1=220,2=0.000000
L 5.36813337 1.25759931 5.37081683 1.25553307 1 P 0 ;0,1=220,2=0.000000
L 5.37081683 1.25553307 5.37349961 1.2545 1 P 0 ;0,1=220,2=0.000000
L 5.37349961 1.2545 5.37618307 1.2545 1 P 0 ;0,1=220,2=0.000000
L 5.37618307 1.2545 5.37886654 1.25553307 1 P 0 ;0,1=220,2=0.000000
L 5.37886654 1.25553307 5.38116673 1.25708278 1 P 0 ;0,1=220,2=0.000000
L 5.38116673 1.25708278 5.38308366 1.25914892 1 P 0 ;0,1=220,2=0.000000
L 5.40449961 1.2545 5.40449961 1.2855 1 P 0 ;0,1=220,2=0.000000
L 5.40449961 1.2855 5.3998999 1.2793003 1 P 0 ;0,1=220,2=0.000000
L 5.3998999 1.2545 5.40909931 1.2545 1 P 0 ;0,1=220,2=0.000000
L 5.43473307 1.2545 5.43549961 1.26121614 1 P 0 ;0,1=220,2=0.000000
L 5.43549961 1.26121614 5.4366501 1.26689921 1 P 0 ;0,1=220,2=0.000000
L 5.4366501 1.26689921 5.43818307 1.27206663 1 P 0 ;0,1=220,2=0.000000
L 5.43818307 1.27206663 5.4401 1.2777497 1 P 0 ;0,1=220,2=0.000000
L 5.4401 1.2777497 5.44316673 1.2855 1 P 0 ;0,1=220,2=0.000000
L 5.44316673 1.2855 5.42783317 1.2855 1 P 0 ;0,1=220,2=0.000000
L 5.45921644 1.26741575 5.4618999 1.27103356 1 P 0 ;0,1=220,2=0.000000
L 5.4618999 1.27103356 5.4642001 1.2730998 1 P 0 ;0,1=220,2=0.000000
L 5.4642001 1.2730998 5.46726683 1.27413287 1 P 0 ;0,1=220,2=0.000000
L 5.46726683 1.27413287 5.4699503 1.2730998 1 P 0 ;0,1=220,2=0.000000
L 5.4699503 1.2730998 5.47186654 1.27103356 1 P 0 ;0,1=220,2=0.000000
L 5.47186654 1.27103356 5.4734002 1.26793327 1 P 0 ;0,1=220,2=0.000000
L 5.4734002 1.26793327 5.47378346 1.26431644 1 P 0 ;0,1=220,2=0.000000
L 5.47378346 1.26431644 5.4734002 1.26121614 1 P 0 ;0,1=220,2=0.000000
L 5.4734002 1.26121614 5.47186654 1.25811585 1 P 0 ;0,1=220,2=0.000000
L 5.47186654 1.25811585 5.46956634 1.25553307 1 P 0 ;0,1=220,2=0.000000
L 5.46956634 1.25553307 5.46688356 1.2545 1 P 0 ;0,1=220,2=0.000000
L 5.46688356 1.2545 5.46381683 1.25553307 1 P 0 ;0,1=220,2=0.000000
L 5.46381683 1.25553307 5.46113337 1.25863238 1 P 0 ;0,1=220,2=0.000000
L 5.46113337 1.25863238 5.4595997 1.26328327 1 P 0 ;0,1=220,2=0.000000
L 5.4595997 1.26328327 5.45921644 1.2684498 1 P 0 ;0,1=220,2=0.000000
L 5.45921644 1.2684498 5.45998287 1.27516594 1 P 0 ;0,1=220,2=0.000000
L 5.45998287 1.27516594 5.46113337 1.27878376 1 P 0 ;0,1=220,2=0.000000
L 5.46113337 1.27878376 5.46304961 1.2823997 1 P 0 ;0,1=220,2=0.000000
L 5.46304961 1.2823997 5.46573307 1.28498337 1 P 0 ;0,1=220,2=0.000000
L 5.46573307 1.28498337 5.46841654 1.2855 1 P 0 ;0,1=220,2=0.000000
L 5.46841654 1.2855 5.4711 1.28446683 1 P 0 ;0,1=220,2=0.000000
L 5.4711 1.28446683 5.47301703 1.28188307 1 P 0 ;0,1=220,2=0.000000
L 5.33 1.532 5.33 1.408 1 P 0 
L 5.16 1.532 5.33 1.532 1 P 0 
L 5.16 1.408 5.16 1.532 1 P 0 
L 5.33 1.408 5.16 1.408 1 P 0 
L 5.38193327 1.32791624 5.37963307 1.32946683 1 P 0 ;0,1=221,2=0.000000
L 5.37963307 1.32946683 5.3769503 1.3305 1 P 0 ;0,1=221,2=0.000000
L 5.3769503 1.3305 5.37388356 1.3305 1 P 0 ;0,1=221,2=0.000000
L 5.37388356 1.3305 5.37043287 1.32894931 1 P 0 ;0,1=221,2=0.000000
L 5.37043287 1.32894931 5.3677501 1.32636654 1 P 0 ;0,1=221,2=0.000000
L 5.3677501 1.32636654 5.36583317 1.32326624 1 P 0 ;0,1=221,2=0.000000
L 5.36583317 1.32326624 5.36429951 1.3180998 1 P 0 ;0,1=221,2=0.000000
L 5.36429951 1.3180998 5.36391624 1.3134498 1 P 0 ;0,1=221,2=0.000000
L 5.36391624 1.3134498 5.36468337 1.3087999 1 P 0 ;0,1=221,2=0.000000
L 5.36468337 1.3087999 5.36583317 1.30569961 1 P 0 ;0,1=221,2=0.000000
L 5.36583317 1.30569961 5.36813337 1.30259931 1 P 0 ;0,1=221,2=0.000000
L 5.36813337 1.30259931 5.37081683 1.30053307 1 P 0 ;0,1=221,2=0.000000
L 5.37081683 1.30053307 5.37349961 1.2995 1 P 0 ;0,1=221,2=0.000000
L 5.37349961 1.2995 5.37618307 1.2995 1 P 0 ;0,1=221,2=0.000000
L 5.37618307 1.2995 5.37886654 1.30053307 1 P 0 ;0,1=221,2=0.000000
L 5.37886654 1.30053307 5.38116673 1.30208278 1 P 0 ;0,1=221,2=0.000000
L 5.38116673 1.30208278 5.38308366 1.30414892 1 P 0 ;0,1=221,2=0.000000
L 5.40449961 1.2995 5.40449961 1.3305 1 P 0 ;0,1=221,2=0.000000
L 5.40449961 1.3305 5.3998999 1.3243003 1 P 0 ;0,1=221,2=0.000000
L 5.3998999 1.2995 5.40909931 1.2995 1 P 0 ;0,1=221,2=0.000000
L 5.43473307 1.2995 5.43549961 1.30621614 1 P 0 ;0,1=221,2=0.000000
L 5.43549961 1.30621614 5.4366501 1.31189921 1 P 0 ;0,1=221,2=0.000000
L 5.4366501 1.31189921 5.43818307 1.31706663 1 P 0 ;0,1=221,2=0.000000
L 5.43818307 1.31706663 5.4401 1.3227497 1 P 0 ;0,1=221,2=0.000000
L 5.4401 1.3227497 5.44316673 1.3305 1 P 0 ;0,1=221,2=0.000000
L 5.44316673 1.3305 5.42783317 1.3305 1 P 0 ;0,1=221,2=0.000000
L 5.46573307 1.2995 5.46649961 1.30621614 1 P 0 ;0,1=221,2=0.000000
L 5.46649961 1.30621614 5.4676501 1.31189921 1 P 0 ;0,1=221,2=0.000000
L 5.4676501 1.31189921 5.46918307 1.31706663 1 P 0 ;0,1=221,2=0.000000
L 5.46918307 1.31706663 5.4711 1.3227497 1 P 0 ;0,1=221,2=0.000000
L 5.4711 1.3227497 5.47416673 1.3305 1 P 0 ;0,1=221,2=0.000000
L 5.47416673 1.3305 5.45883317 1.3305 1 P 0 ;0,1=221,2=0.000000
L 4.802 2.574 4.802 2.404 1 P 0 
L 4.678 2.574 4.802 2.574 1 P 0 
L 4.802 2.404 4.678 2.404 1 P 0 
L 4.678 2.404 4.678 2.574 1 P 0 
L 4.73208376 2.60193327 4.73053317 2.59963307 1 P 0 ;0,1=222,2=270.000000
L 4.73053317 2.59963307 4.7295 2.5969503 1 P 0 ;0,1=222,2=270.000000
L 4.7295 2.5969503 4.7295 2.59388356 1 P 0 ;0,1=222,2=270.000000
L 4.7295 2.59388356 4.73105069 2.59043287 1 P 0 ;0,1=222,2=270.000000
L 4.73105069 2.59043287 4.73363346 2.5877501 1 P 0 ;0,1=222,2=270.000000
L 4.73363346 2.5877501 4.73673376 2.58583317 1 P 0 ;0,1=222,2=270.000000
L 4.73673376 2.58583317 4.7419002 2.58429951 1 P 0 ;0,1=222,2=270.000000
L 4.7419002 2.58429951 4.7465502 2.58391624 1 P 0 ;0,1=222,2=270.000000
L 4.7465502 2.58391624 4.7512001 2.58468337 1 P 0 ;0,1=222,2=270.000000
L 4.7512001 2.58468337 4.75430039 2.58583317 1 P 0 ;0,1=222,2=270.000000
L 4.75430039 2.58583317 4.75740069 2.58813337 1 P 0 ;0,1=222,2=270.000000
L 4.75740069 2.58813337 4.75946693 2.59081683 1 P 0 ;0,1=222,2=270.000000
L 4.75946693 2.59081683 4.7605 2.59349961 1 P 0 ;0,1=222,2=270.000000
L 4.7605 2.59349961 4.7605 2.59618307 1 P 0 ;0,1=222,2=270.000000
L 4.7605 2.59618307 4.75946693 2.59886654 1 P 0 ;0,1=222,2=270.000000
L 4.75946693 2.59886654 4.75791722 2.60116673 1 P 0 ;0,1=222,2=270.000000
L 4.75791722 2.60116673 4.75585108 2.60308366 1 P 0 ;0,1=222,2=270.000000
L 4.7605 2.62449961 4.7295 2.62449961 1 P 0 ;0,1=222,2=270.000000
L 4.7295 2.62449961 4.7356997 2.6198999 1 P 0 ;0,1=222,2=270.000000
L 4.7605 2.6198999 4.7605 2.62909931 1 P 0 ;0,1=222,2=270.000000
L 4.7605 2.65473307 4.75378386 2.65549961 1 P 0 ;0,1=222,2=270.000000
L 4.75378386 2.65549961 4.74810079 2.6566501 1 P 0 ;0,1=222,2=270.000000
L 4.74810079 2.6566501 4.74293337 2.65818307 1 P 0 ;0,1=222,2=270.000000
L 4.74293337 2.65818307 4.7372503 2.6601 1 P 0 ;0,1=222,2=270.000000
L 4.7372503 2.6601 4.7295 2.66316673 1 P 0 ;0,1=222,2=270.000000
L 4.7295 2.66316673 4.7295 2.64783317 1 P 0 ;0,1=222,2=270.000000
L 4.7605 2.6911 4.7295 2.6911 1 P 0 ;0,1=222,2=270.000000
L 4.7295 2.6911 4.75171673 2.67691624 1 P 0 ;0,1=222,2=270.000000
L 4.75171673 2.67691624 4.75171673 2.69608366 1 P 0 ;0,1=222,2=270.000000
L 3.56 2.827 3.56 2.737 1 P 0 
L 3.56 2.737 3.604 2.737 1 P 0 
L 3.604 2.737 3.604 2.827 1 P 0 
L 3.604 2.827 3.56 2.827 1 P 0 
L 2.48708376 3.47693327 2.48553317 3.47463307 1 P 0 ;0,1=223,2=270.000000
L 2.48553317 3.47463307 2.4845 3.4719503 1 P 0 ;0,1=223,2=270.000000
L 2.4845 3.4719503 2.4845 3.46888356 1 P 0 ;0,1=223,2=270.000000
L 2.4845 3.46888356 2.48605069 3.46543287 1 P 0 ;0,1=223,2=270.000000
L 2.48605069 3.46543287 2.48863346 3.4627501 1 P 0 ;0,1=223,2=270.000000
L 2.48863346 3.4627501 2.49173376 3.46083317 1 P 0 ;0,1=223,2=270.000000
L 2.49173376 3.46083317 2.4969002 3.45929951 1 P 0 ;0,1=223,2=270.000000
L 2.4969002 3.45929951 2.5015502 3.45891624 1 P 0 ;0,1=223,2=270.000000
L 2.5015502 3.45891624 2.5062001 3.45968337 1 P 0 ;0,1=223,2=270.000000
L 2.5062001 3.45968337 2.50930039 3.46083317 1 P 0 ;0,1=223,2=270.000000
L 2.50930039 3.46083317 2.51240069 3.46313337 1 P 0 ;0,1=223,2=270.000000
L 2.51240069 3.46313337 2.51446693 3.46581683 1 P 0 ;0,1=223,2=270.000000
L 2.51446693 3.46581683 2.5155 3.46849961 1 P 0 ;0,1=223,2=270.000000
L 2.5155 3.46849961 2.5155 3.47118307 1 P 0 ;0,1=223,2=270.000000
L 2.5155 3.47118307 2.51446693 3.47386654 1 P 0 ;0,1=223,2=270.000000
L 2.51446693 3.47386654 2.51291722 3.47616673 1 P 0 ;0,1=223,2=270.000000
L 2.51291722 3.47616673 2.51085108 3.47808366 1 P 0 ;0,1=223,2=270.000000
L 2.5155 3.49949961 2.4845 3.49949961 1 P 0 ;0,1=223,2=270.000000
L 2.4845 3.49949961 2.4906997 3.4948999 1 P 0 ;0,1=223,2=270.000000
L 2.5155 3.4948999 2.5155 3.50409931 1 P 0 ;0,1=223,2=270.000000
L 2.51188415 3.52398287 2.51446693 3.52666634 1 P 0 ;0,1=223,2=270.000000
L 2.51446693 3.52666634 2.5155 3.52973307 1 P 0 ;0,1=223,2=270.000000
L 2.5155 3.52973307 2.51446693 3.5327998 1 P 0 ;0,1=223,2=270.000000
L 2.51446693 3.5327998 2.51136762 3.53548327 1 P 0 ;0,1=223,2=270.000000
L 2.51136762 3.53548327 2.50671673 3.5374002 1 P 0 ;0,1=223,2=270.000000
L 2.50671673 3.5374002 2.50206673 3.53816673 1 P 0 ;0,1=223,2=270.000000
L 2.50206673 3.53816673 2.49638366 3.53816673 1 P 0 ;0,1=223,2=270.000000
L 2.49638366 3.53816673 2.49173376 3.5374002 1 P 0 ;0,1=223,2=270.000000
L 2.49173376 3.5374002 2.4876003 3.53548327 1 P 0 ;0,1=223,2=270.000000
L 2.4876003 3.53548327 2.48553317 3.53318307 1 P 0 ;0,1=223,2=270.000000
L 2.48553317 3.53318307 2.4845 3.53049961 1 P 0 ;0,1=223,2=270.000000
L 2.4845 3.53049961 2.48553317 3.52743287 1 P 0 ;0,1=223,2=270.000000
L 2.48553317 3.52743287 2.4876003 3.52513337 1 P 0 ;0,1=223,2=270.000000
L 2.4876003 3.52513337 2.4906997 3.5235997 1 P 0 ;0,1=223,2=270.000000
L 2.4906997 3.5235997 2.49483406 3.52283317 1 P 0 ;0,1=223,2=270.000000
L 2.49483406 3.52283317 2.4984499 3.5235997 1 P 0 ;0,1=223,2=270.000000
L 2.4984499 3.5235997 2.50206673 3.52551663 1 P 0 ;0,1=223,2=270.000000
L 2.50206673 3.52551663 2.50413396 3.52781683 1 P 0 ;0,1=223,2=270.000000
L 2.50413396 3.52781683 2.50465049 3.53049961 1 P 0 ;0,1=223,2=270.000000
L 2.50465049 3.53049961 2.50361732 3.53356634 1 P 0 ;0,1=223,2=270.000000
L 2.50361732 3.53356634 2.50103366 3.53586654 1 P 0 ;0,1=223,2=270.000000
L 2.50103366 3.53586654 2.49638366 3.53816673 1 P 0 ;0,1=223,2=270.000000
L 2.5155 3.56149961 2.51498346 3.56418307 1 P 0 ;0,1=223,2=270.000000
L 2.51498346 3.56418307 2.51343386 3.5672498 1 P 0 ;0,1=223,2=270.000000
L 2.51343386 3.5672498 2.51085108 3.56916673 1 P 0 ;0,1=223,2=270.000000
L 2.51085108 3.56916673 2.50723327 3.56993327 1 P 0 ;0,1=223,2=270.000000
L 2.50723327 3.56993327 2.50361732 3.56916673 1 P 0 ;0,1=223,2=270.000000
L 2.50361732 3.56916673 2.50051713 3.56686654 1 P 0 ;0,1=223,2=270.000000
L 2.50051713 3.56686654 2.49896644 3.56341654 1 P 0 ;0,1=223,2=270.000000
L 2.49896644 3.56341654 2.49896644 3.55958337 1 P 0 ;0,1=223,2=270.000000
L 2.49896644 3.55958337 2.49793337 3.55728317 1 P 0 ;0,1=223,2=270.000000
L 2.49793337 3.55728317 2.49535059 3.55536614 1 P 0 ;0,1=223,2=270.000000
L 2.49535059 3.55536614 2.49173376 3.5545997 1 P 0 ;0,1=223,2=270.000000
L 2.49173376 3.5545997 2.48811693 3.5557501 1 P 0 ;0,1=223,2=270.000000
L 2.48811693 3.5557501 2.48553317 3.55843287 1 P 0 ;0,1=223,2=270.000000
L 2.48553317 3.55843287 2.4845 3.56149961 1 P 0 ;0,1=223,2=270.000000
L 2.4845 3.56149961 2.48553317 3.56456634 1 P 0 ;0,1=223,2=270.000000
L 2.48553317 3.56456634 2.48811693 3.5672498 1 P 0 ;0,1=223,2=270.000000
L 2.48811693 3.5672498 2.49173376 3.5684002 1 P 0 ;0,1=223,2=270.000000
L 2.49173376 3.5684002 2.49535059 3.56763307 1 P 0 ;0,1=223,2=270.000000
L 2.49535059 3.56763307 2.49793337 3.56571673 1 P 0 ;0,1=223,2=270.000000
L 2.49793337 3.56571673 2.49896644 3.56341654 1 P 0 ;0,1=223,2=270.000000
L 2.49896644 3.56341654 2.49896644 3.55958337 1 P 0 ;0,1=223,2=270.000000
L 2.49896644 3.55958337 2.50051713 3.55613337 1 P 0 ;0,1=223,2=270.000000
L 2.50051713 3.55613337 2.50361732 3.55383317 1 P 0 ;0,1=223,2=270.000000
L 2.50361732 3.55383317 2.50723327 3.55306663 1 P 0 ;0,1=223,2=270.000000
L 2.50723327 3.55306663 2.51085108 3.55383317 1 P 0 ;0,1=223,2=270.000000
L 2.51085108 3.55383317 2.51343386 3.5557501 1 P 0 ;0,1=223,2=270.000000
L 2.51343386 3.5557501 2.51498346 3.55881683 1 P 0 ;0,1=223,2=270.000000
L 2.51498346 3.55881683 2.5155 3.56149961 1 P 0 ;0,1=223,2=270.000000
L 5.454 3.597 5.558 3.597 1 P 0 
L 5.558 3.541 5.454 3.541 1 P 0 
L 5.454 3.541 5.454 3.597 1 P 0 
L 5.558 3.597 5.558 3.541 1 P 0 
L 5.37171644 3.5395 5.37171644 3.5705 1 P 0 ;0,1=224,2=0.000000
L 5.37171644 3.5705 5.38628346 3.5705 1 P 0 ;0,1=224,2=0.000000
L 5.38091654 3.55551703 5.37171644 3.55551703 1 P 0 ;0,1=224,2=0.000000
L 5.40156663 3.5705 5.40156663 3.54828327 1 P 0 ;0,1=224,2=0.000000
L 5.40156663 3.54828327 5.4030997 3.54363238 1 P 0 ;0,1=224,2=0.000000
L 5.4030997 3.54363238 5.40616634 3.54053307 1 P 0 ;0,1=224,2=0.000000
L 5.40616634 3.54053307 5.40999961 3.5395 1 P 0 ;0,1=224,2=0.000000
L 5.40999961 3.5395 5.41383356 3.54053307 1 P 0 ;0,1=224,2=0.000000
L 5.41383356 3.54053307 5.4169002 3.54363238 1 P 0 ;0,1=224,2=0.000000
L 5.4169002 3.54363238 5.41843327 3.54828327 1 P 0 ;0,1=224,2=0.000000
L 5.41843327 3.54828327 5.41843327 3.5705 1 P 0 ;0,1=224,2=0.000000
L 5.44099961 3.5395 5.44099961 3.5705 1 P 0 ;0,1=224,2=0.000000
L 5.44099961 3.5705 5.4363999 3.5643003 1 P 0 ;0,1=224,2=0.000000
L 5.4363999 3.5395 5.44559931 3.5395 1 P 0 ;0,1=224,2=0.000000
L 5.289 3.93 5.393 3.93 1 P 0 
L 5.393 3.93 5.393 3.874 1 P 0 
L 5.393 3.874 5.289 3.874 1 P 0 
L 5.289 3.874 5.289 3.93 1 P 0 
L 5.21683317 3.8995 5.21683317 3.9305 1 P 0 ;0,1=225,2=0.000000
L 5.21683317 3.9305 5.22641654 3.9305 1 P 0 ;0,1=225,2=0.000000
L 5.22641654 3.9305 5.22948327 3.92894931 1 P 0 ;0,1=225,2=0.000000
L 5.22948327 3.92894931 5.2314002 3.92688307 1 P 0 ;0,1=225,2=0.000000
L 5.2314002 3.92688307 5.23216673 3.9227497 1 P 0 ;0,1=225,2=0.000000
L 5.23216673 3.9227497 5.2314002 3.91861634 1 P 0 ;0,1=225,2=0.000000
L 5.2314002 3.91861634 5.2291 3.91603356 1 P 0 ;0,1=225,2=0.000000
L 5.2291 3.91603356 5.22641654 3.91448287 1 P 0 ;0,1=225,2=0.000000
L 5.22641654 3.91448287 5.21683317 3.91448287 1 P 0 ;0,1=225,2=0.000000
L 5.22641654 3.91448287 5.23216673 3.8995 1 P 0 ;0,1=225,2=0.000000
L 5.24898287 3.90311585 5.25166634 3.90053307 1 P 0 ;0,1=225,2=0.000000
L 5.25166634 3.90053307 5.25473307 3.8995 1 P 0 ;0,1=225,2=0.000000
L 5.25473307 3.8995 5.2577998 3.90053307 1 P 0 ;0,1=225,2=0.000000
L 5.2577998 3.90053307 5.26048327 3.90363238 1 P 0 ;0,1=225,2=0.000000
L 5.26048327 3.90363238 5.2624002 3.90828327 1 P 0 ;0,1=225,2=0.000000
L 5.2624002 3.90828327 5.26316673 3.91293327 1 P 0 ;0,1=225,2=0.000000
L 5.26316673 3.91293327 5.26316673 3.91861634 1 P 0 ;0,1=225,2=0.000000
L 5.26316673 3.91861634 5.2624002 3.92326624 1 P 0 ;0,1=225,2=0.000000
L 5.2624002 3.92326624 5.26048327 3.9273997 1 P 0 ;0,1=225,2=0.000000
L 5.26048327 3.9273997 5.25818307 3.92946683 1 P 0 ;0,1=225,2=0.000000
L 5.25818307 3.92946683 5.25549961 3.9305 1 P 0 ;0,1=225,2=0.000000
L 5.25549961 3.9305 5.25243287 3.92946683 1 P 0 ;0,1=225,2=0.000000
L 5.25243287 3.92946683 5.25013337 3.9273997 1 P 0 ;0,1=225,2=0.000000
L 5.25013337 3.9273997 5.2485997 3.9243003 1 P 0 ;0,1=225,2=0.000000
L 5.2485997 3.9243003 5.24783317 3.92016594 1 P 0 ;0,1=225,2=0.000000
L 5.24783317 3.92016594 5.2485997 3.9165501 1 P 0 ;0,1=225,2=0.000000
L 5.2485997 3.9165501 5.25051663 3.91293327 1 P 0 ;0,1=225,2=0.000000
L 5.25051663 3.91293327 5.25281683 3.91086604 1 P 0 ;0,1=225,2=0.000000
L 5.25281683 3.91086604 5.25549961 3.91034951 1 P 0 ;0,1=225,2=0.000000
L 5.25549961 3.91034951 5.25856634 3.91138268 1 P 0 ;0,1=225,2=0.000000
L 5.25856634 3.91138268 5.26086654 3.91396634 1 P 0 ;0,1=225,2=0.000000
L 5.26086654 3.91396634 5.26316673 3.91861634 1 P 0 ;0,1=225,2=0.000000
L 5.60791998 3.43843996 5.60791998 3.17356004 1 P 0 
L 5.23408002 3.43843996 5.60791998 3.43843996 1 P 0 
L 5.23408002 3.17356004 5.23408002 3.43843996 1 P 0 
L 5.60791998 3.17356004 5.23408002 3.17356004 1 P 0 
L 5.17251998 3.38068002 5.22251998 3.38068002 1 P 0 
L 5.19751998 3.35568002 5.19751998 3.40568002 1 P 0 
L 5.66343327 3.34791624 5.66113307 3.34946683 1 P 0 ;0,1=22,2=0.000000
L 5.66113307 3.34946683 5.6584503 3.3505 1 P 0 ;0,1=22,2=0.000000
L 5.6584503 3.3505 5.65538356 3.3505 1 P 0 ;0,1=22,2=0.000000
L 5.65538356 3.3505 5.65193287 3.34894931 1 P 0 ;0,1=22,2=0.000000
L 5.65193287 3.34894931 5.6492501 3.34636654 1 P 0 ;0,1=22,2=0.000000
L 5.6492501 3.34636654 5.64733317 3.34326624 1 P 0 ;0,1=22,2=0.000000
L 5.64733317 3.34326624 5.64579951 3.3380998 1 P 0 ;0,1=22,2=0.000000
L 5.64579951 3.3380998 5.64541624 3.3334498 1 P 0 ;0,1=22,2=0.000000
L 5.64541624 3.3334498 5.64618337 3.3287999 1 P 0 ;0,1=22,2=0.000000
L 5.64618337 3.3287999 5.64733317 3.32569961 1 P 0 ;0,1=22,2=0.000000
L 5.64733317 3.32569961 5.64963337 3.32259931 1 P 0 ;0,1=22,2=0.000000
L 5.64963337 3.32259931 5.65231683 3.32053307 1 P 0 ;0,1=22,2=0.000000
L 5.65231683 3.32053307 5.65499961 3.3195 1 P 0 ;0,1=22,2=0.000000
L 5.65499961 3.3195 5.65768307 3.3195 1 P 0 ;0,1=22,2=0.000000
L 5.65768307 3.3195 5.66036654 3.32053307 1 P 0 ;0,1=22,2=0.000000
L 5.66036654 3.32053307 5.66266673 3.32208278 1 P 0 ;0,1=22,2=0.000000
L 5.66266673 3.32208278 5.66458366 3.32414892 1 P 0 ;0,1=22,2=0.000000
L 5.34793327 3.50391624 5.34563307 3.50546683 1 P 0 ;0,1=226,2=0.000000
L 5.34563307 3.50546683 5.3429503 3.5065 1 P 0 ;0,1=226,2=0.000000
L 5.3429503 3.5065 5.33988356 3.5065 1 P 0 ;0,1=226,2=0.000000
L 5.33988356 3.5065 5.33643287 3.50494931 1 P 0 ;0,1=226,2=0.000000
L 5.33643287 3.50494931 5.3337501 3.50236654 1 P 0 ;0,1=226,2=0.000000
L 5.3337501 3.50236654 5.33183317 3.49926624 1 P 0 ;0,1=226,2=0.000000
L 5.33183317 3.49926624 5.33029951 3.4940998 1 P 0 ;0,1=226,2=0.000000
L 5.33029951 3.4940998 5.32991624 3.4894498 1 P 0 ;0,1=226,2=0.000000
L 5.32991624 3.4894498 5.33068337 3.4847999 1 P 0 ;0,1=226,2=0.000000
L 5.33068337 3.4847999 5.33183317 3.48169961 1 P 0 ;0,1=226,2=0.000000
L 5.33183317 3.48169961 5.33413337 3.47859931 1 P 0 ;0,1=226,2=0.000000
L 5.33413337 3.47859931 5.33681683 3.47653307 1 P 0 ;0,1=226,2=0.000000
L 5.33681683 3.47653307 5.33949961 3.4755 1 P 0 ;0,1=226,2=0.000000
L 5.33949961 3.4755 5.34218307 3.4755 1 P 0 ;0,1=226,2=0.000000
L 5.34218307 3.4755 5.34486654 3.47653307 1 P 0 ;0,1=226,2=0.000000
L 5.34486654 3.47653307 5.34716673 3.47808278 1 P 0 ;0,1=226,2=0.000000
L 5.34716673 3.47808278 5.34908366 3.48014892 1 P 0 ;0,1=226,2=0.000000
L 5.36283317 3.4755 5.36283317 3.5065 1 P 0 ;0,1=226,2=0.000000
L 5.36283317 3.5065 5.37241654 3.5065 1 P 0 ;0,1=226,2=0.000000
L 5.37241654 3.5065 5.37548327 3.50494931 1 P 0 ;0,1=226,2=0.000000
L 5.37548327 3.50494931 5.3774002 3.50288307 1 P 0 ;0,1=226,2=0.000000
L 5.3774002 3.50288307 5.37816673 3.4987497 1 P 0 ;0,1=226,2=0.000000
L 5.37816673 3.4987497 5.3774002 3.49461634 1 P 0 ;0,1=226,2=0.000000
L 5.3774002 3.49461634 5.3751 3.49203356 1 P 0 ;0,1=226,2=0.000000
L 5.3751 3.49203356 5.37241654 3.49048287 1 P 0 ;0,1=226,2=0.000000
L 5.37241654 3.49048287 5.36283317 3.49048287 1 P 0 ;0,1=226,2=0.000000
L 5.37241654 3.49048287 5.37816673 3.4755 1 P 0 ;0,1=226,2=0.000000
L 5.40149961 3.4755 5.40149961 3.5065 1 P 0 ;0,1=226,2=0.000000
L 5.40149961 3.5065 5.3968999 3.5003003 1 P 0 ;0,1=226,2=0.000000
L 5.3968999 3.4755 5.40609931 3.4755 1 P 0 ;0,1=226,2=0.000000
L 5.43249961 3.5065 5.42943287 3.50546683 1 P 0 ;0,1=226,2=0.000000
L 5.42943287 3.50546683 5.42713337 3.50288307 1 P 0 ;0,1=226,2=0.000000
L 5.42713337 3.50288307 5.4255997 3.49978376 1 P 0 ;0,1=226,2=0.000000
L 5.4255997 3.49978376 5.4244499 3.49564941 1 P 0 ;0,1=226,2=0.000000
L 5.4244499 3.49564941 5.42406663 3.49099951 1 P 0 ;0,1=226,2=0.000000
L 5.42406663 3.49099951 5.4244499 3.48634951 1 P 0 ;0,1=226,2=0.000000
L 5.4244499 3.48634951 5.4255997 3.48221614 1 P 0 ;0,1=226,2=0.000000
L 5.4255997 3.48221614 5.42713337 3.47911585 1 P 0 ;0,1=226,2=0.000000
L 5.42713337 3.47911585 5.42943287 3.47653307 1 P 0 ;0,1=226,2=0.000000
L 5.42943287 3.47653307 5.43249961 3.4755 1 P 0 ;0,1=226,2=0.000000
L 5.43249961 3.4755 5.43556634 3.47653307 1 P 0 ;0,1=226,2=0.000000
L 5.43556634 3.47653307 5.43786654 3.47911585 1 P 0 ;0,1=226,2=0.000000
L 5.43786654 3.47911585 5.4394002 3.48221614 1 P 0 ;0,1=226,2=0.000000
L 5.4394002 3.48221614 5.44055 3.48634951 1 P 0 ;0,1=226,2=0.000000
L 5.44055 3.48634951 5.44093327 3.49099951 1 P 0 ;0,1=226,2=0.000000
L 5.44093327 3.49099951 5.44055 3.49564941 1 P 0 ;0,1=226,2=0.000000
L 5.44055 3.49564941 5.4394002 3.49978376 1 P 0 ;0,1=226,2=0.000000
L 5.4394002 3.49978376 5.43786654 3.50288307 1 P 0 ;0,1=226,2=0.000000
L 5.43786654 3.50288307 5.43556634 3.50546683 1 P 0 ;0,1=226,2=0.000000
L 5.43556634 3.50546683 5.43249961 3.5065 1 P 0 ;0,1=226,2=0.000000
L 5.18541624 3.2995 5.19499961 3.3305 1 P 0 ;0,1=1,2=0.000000
L 5.19499961 3.3305 5.20458366 3.2995 1 P 0 ;0,1=1,2=0.000000
L 5.20113307 3.31034951 5.18886614 3.31034951 1 P 0 ;0,1=1,2=0.000000
L 3.61056998 1.98205 3.47745 1.98205 1 P 0 
L 3.61056998 1.84893002 3.61056998 1.98205 1 P 0 
L 3.47745 1.98205 3.47745 1.84893002 1 P 0 
L 3.47745 1.84893002 3.61056998 1.84893002 1 P 0 
S P 0
OB 3.53673996063 1.82225 I
OC 3.53673996063 1.82225 3.521737992126 1.822248425197 Y
OE
SE
L 3.64556663 2.041 3.64556663 2.01878327 1 P 0 ;0,1=227,2=0.000000
L 3.64556663 2.01878327 3.6470997 2.01413238 1 P 0 ;0,1=227,2=0.000000
L 3.6470997 2.01413238 3.65016634 2.01103307 1 P 0 ;0,1=227,2=0.000000
L 3.65016634 2.01103307 3.65399961 2.01 1 P 0 ;0,1=227,2=0.000000
L 3.65399961 2.01 3.65783356 2.01103307 1 P 0 ;0,1=227,2=0.000000
L 3.65783356 2.01103307 3.6609002 2.01413238 1 P 0 ;0,1=227,2=0.000000
L 3.6609002 2.01413238 3.66243327 2.01878327 1 P 0 ;0,1=227,2=0.000000
L 3.66243327 2.01878327 3.66243327 2.041 1 P 0 ;0,1=227,2=0.000000
L 3.68499961 2.01 3.68499961 2.041 1 P 0 ;0,1=227,2=0.000000
L 3.68499961 2.041 3.6803999 2.0348003 1 P 0 ;0,1=227,2=0.000000
L 3.6803999 2.01 3.68959931 2.01 1 P 0 ;0,1=227,2=0.000000
L 3.71599961 2.01 3.71599961 2.041 1 P 0 ;0,1=227,2=0.000000
L 3.71599961 2.041 3.7113999 2.0348003 1 P 0 ;0,1=227,2=0.000000
L 3.7113999 2.01 3.72059931 2.01 1 P 0 ;0,1=227,2=0.000000
L 3.57646004 2.00184656 3.5710438 2.00237972 1 P 0 ;0,1=138,2=270.000000
L 3.5710438 2.00237972 3.56646073 2.00318002 1 P 0 ;0,1=138,2=270.000000
L 3.56646073 2.00318002 3.56229341 2.00424646 1 P 0 ;0,1=138,2=270.000000
L 3.56229341 2.00424646 3.55771024 2.00558002 1 P 0 ;0,1=138,2=270.000000
L 3.55771024 2.00558002 3.55146004 2.00771339 1 P 0 ;0,1=138,2=270.000000
L 3.55146004 2.00771339 3.55146004 1.99704656 1 P 0 ;0,1=138,2=270.000000
L 3.53733996 2.00148967 3.53692343 2.0033564 1 P 0 ;0,1=16,2=270.000000
L 3.53692343 2.0033564 3.53567372 2.00548976 1 P 0 ;0,1=16,2=270.000000
L 3.53567372 2.00548976 3.53359085 2.00682333 1 P 0 ;0,1=16,2=270.000000
L 3.53359085 2.00682333 3.53067323 2.00735659 1 P 0 ;0,1=16,2=270.000000
L 3.53067323 2.00735659 3.52775719 2.00682333 1 P 0 ;0,1=16,2=270.000000
L 3.52775719 2.00682333 3.52525699 2.00522323 1 P 0 ;0,1=16,2=270.000000
L 3.52525699 2.00522323 3.5240065 2.00282323 1 P 0 ;0,1=16,2=270.000000
L 3.5240065 2.00282323 3.5240065 2.00015659 1 P 0 ;0,1=16,2=270.000000
L 3.5240065 2.00015659 3.52317333 1.9985565 1 P 0 ;0,1=16,2=270.000000
L 3.52317333 1.9985565 3.52109045 1.99722293 1 P 0 ;0,1=16,2=270.000000
L 3.52109045 1.99722293 3.51817362 1.99668976 1 P 0 ;0,1=16,2=270.000000
L 3.51817362 1.99668976 3.51525679 1.99749006 1 P 0 ;0,1=16,2=270.000000
L 3.51525679 1.99749006 3.51317313 1.9993563 1 P 0 ;0,1=16,2=270.000000
L 3.51317313 1.9993563 3.51233996 2.00148967 1 P 0 ;0,1=16,2=270.000000
L 3.51233996 2.00148967 3.51317313 2.00362303 1 P 0 ;0,1=16,2=270.000000
L 3.51317313 2.00362303 3.51525679 2.00548976 1 P 0 ;0,1=16,2=270.000000
L 3.51525679 2.00548976 3.51817362 2.00629006 1 P 0 ;0,1=16,2=270.000000
L 3.51817362 2.00629006 3.52109045 2.0057564 1 P 0 ;0,1=16,2=270.000000
L 3.52109045 2.0057564 3.52317333 2.00442333 1 P 0 ;0,1=16,2=270.000000
L 3.52317333 2.00442333 3.5240065 2.00282323 1 P 0 ;0,1=16,2=270.000000
L 3.5240065 2.00282323 3.5240065 2.00015659 1 P 0 ;0,1=16,2=270.000000
L 3.5240065 2.00015659 3.52525699 1.99775659 1 P 0 ;0,1=16,2=270.000000
L 3.52525699 1.99775659 3.52775719 1.9961565 1 P 0 ;0,1=16,2=270.000000
L 3.52775719 1.9961565 3.53067323 1.99562323 1 P 0 ;0,1=16,2=270.000000
L 3.53067323 1.99562323 3.53359085 1.9961565 1 P 0 ;0,1=16,2=270.000000
L 3.53359085 1.9961565 3.53567372 1.99749006 1 P 0 ;0,1=16,2=270.000000
L 3.53567372 1.99749006 3.53692343 1.99962343 1 P 0 ;0,1=16,2=270.000000
L 3.53692343 1.99962343 3.53733996 2.00148967 1 P 0 ;0,1=16,2=270.000000
L 3.61913327 1.85449961 3.62073297 1.85158287 1 P 0 ;0,1=10,2=0.000000
L 3.62073297 1.85158287 3.62286634 1.84991654 1 P 0 ;0,1=10,2=0.000000
L 3.62286634 1.84991654 3.62526683 1.8495 1 P 0 ;0,1=10,2=0.000000
L 3.62526683 1.8495 3.6274002 1.84991654 1 P 0 ;0,1=10,2=0.000000
L 3.6274002 1.84991654 3.62953356 1.85199941 1 P 0 ;0,1=10,2=0.000000
L 3.62953356 1.85199941 3.63086663 1.85449961 1 P 0 ;0,1=10,2=0.000000
L 3.63086663 1.85449961 3.63113317 1.8569999 1 P 0 ;0,1=10,2=0.000000
L 3.63113317 1.8569999 3.6306 1.85991594 1 P 0 ;0,1=10,2=0.000000
L 3.6306 1.85991594 3.62873327 1.86199961 1 P 0 ;0,1=10,2=0.000000
L 3.62873327 1.86199961 3.62686644 1.86283346 1 P 0 ;0,1=10,2=0.000000
L 3.62686644 1.86283346 3.62446654 1.86283346 1 P 0 ;0,1=10,2=0.000000
L 3.62686644 1.86283346 3.62846663 1.86408327 1 P 0 ;0,1=10,2=0.000000
L 3.62846663 1.86408327 3.6298001 1.86616614 1 P 0 ;0,1=10,2=0.000000
L 3.6298001 1.86616614 3.63033337 1.86866634 1 P 0 ;0,1=10,2=0.000000
L 3.63033337 1.86866634 3.6298001 1.87116654 1 P 0 ;0,1=10,2=0.000000
L 3.6298001 1.87116654 3.62846663 1.87324941 1 P 0 ;0,1=10,2=0.000000
L 3.62846663 1.87324941 3.62606663 1.8745 1 P 0 ;0,1=10,2=0.000000
L 3.62606663 1.8745 3.62366663 1.87408337 1 P 0 ;0,1=10,2=0.000000
L 3.62366663 1.87408337 3.62126663 1.87241634 1 P 0 ;0,1=10,2=0.000000
L 3.64493317 1.97291594 3.6467999 1.97583346 1 P 0 ;0,1=8,2=0.000000
L 3.6467999 1.97583346 3.6484 1.9774998 1 P 0 ;0,1=8,2=0.000000
L 3.6484 1.9774998 3.65053337 1.97833297 1 P 0 ;0,1=8,2=0.000000
L 3.65053337 1.97833297 3.6524002 1.9774998 1 P 0 ;0,1=8,2=0.000000
L 3.6524002 1.9774998 3.65373327 1.97583346 1 P 0 ;0,1=8,2=0.000000
L 3.65373327 1.97583346 3.6548001 1.97333327 1 P 0 ;0,1=8,2=0.000000
L 3.6548001 1.97333327 3.65506673 1.97041644 1 P 0 ;0,1=8,2=0.000000
L 3.65506673 1.97041644 3.6548001 1.96791624 1 P 0 ;0,1=8,2=0.000000
L 3.6548001 1.96791624 3.65373327 1.96541604 1 P 0 ;0,1=8,2=0.000000
L 3.65373327 1.96541604 3.65213307 1.96333307 1 P 0 ;0,1=8,2=0.000000
L 3.65213307 1.96333307 3.65026683 1.9625 1 P 0 ;0,1=8,2=0.000000
L 3.65026683 1.9625 3.64813346 1.96333307 1 P 0 ;0,1=8,2=0.000000
L 3.64813346 1.96333307 3.64626663 1.96583258 1 P 0 ;0,1=8,2=0.000000
L 3.64626663 1.96583258 3.6451998 1.96958327 1 P 0 ;0,1=8,2=0.000000
L 3.6451998 1.96958327 3.64493317 1.9737498 1 P 0 ;0,1=8,2=0.000000
L 3.64493317 1.9737498 3.64546634 1.97916614 1 P 0 ;0,1=8,2=0.000000
L 3.64546634 1.97916614 3.64626663 1.98208366 1 P 0 ;0,1=8,2=0.000000
L 3.64626663 1.98208366 3.6475997 1.9849997 1 P 0 ;0,1=8,2=0.000000
L 3.6475997 1.9849997 3.64946654 1.98708337 1 P 0 ;0,1=8,2=0.000000
L 3.64946654 1.98708337 3.65133327 1.9875 1 P 0 ;0,1=8,2=0.000000
L 3.65133327 1.9875 3.6532 1.98666683 1 P 0 ;0,1=8,2=0.000000
L 3.6532 1.98666683 3.65453356 1.98458317 1 P 0 ;0,1=8,2=0.000000
L 3.55993317 1.83833337 3.56153327 1.84083287 1 P 0 ;0,1=4,2=0.000000
L 3.56153327 1.84083287 3.5634 1.84208337 1 P 0 ;0,1=4,2=0.000000
L 3.5634 1.84208337 3.56553337 1.8425 1 P 0 ;0,1=4,2=0.000000
L 3.56553337 1.8425 3.5682 1.84166683 1 P 0 ;0,1=4,2=0.000000
L 3.5682 1.84166683 3.57006673 1.83958317 1 P 0 ;0,1=4,2=0.000000
L 3.57006673 1.83958317 3.5706 1.83708366 1 P 0 ;0,1=4,2=0.000000
L 3.5706 1.83708366 3.57033337 1.83458268 1 P 0 ;0,1=4,2=0.000000
L 3.57033337 1.83458268 3.56926644 1.8324998 1 P 0 ;0,1=4,2=0.000000
L 3.56926644 1.8324998 3.56393327 1.82833327 1 P 0 ;0,1=4,2=0.000000
L 3.56393327 1.82833327 3.56153327 1.82541644 1 P 0 ;0,1=4,2=0.000000
L 3.56153327 1.82541644 3.55993317 1.82124911 1 P 0 ;0,1=4,2=0.000000
L 3.55993317 1.82124911 3.5593999 1.8175 1 P 0 ;0,1=4,2=0.000000
L 3.5593999 1.8175 3.5706 1.8175 1 P 0 ;0,1=4,2=0.000000
L 1.73261998 4.05296004 1.73261998 3.87903996 1 P 0 
L 1.55903996 4.05296004 1.73261998 4.05296004 1 P 0 
L 1.73261998 3.87903996 1.55903996 3.87903996 1 P 0 
L 1.55903996 3.87903996 1.55903996 4.05296004 1 P 0 
S P 0
OB 1.6269 3.844580019685 I
OC 1.6269 3.844580019685 1.6069 3.844580019685 Y
OE
SE
L 1.75946654 4.0195 1.7599997 4.02491624 1 P 0 ;0,1=138,2=0.000000
L 1.7599997 4.02491624 1.7608 4.02949931 1 P 0 ;0,1=138,2=0.000000
L 1.7608 4.02949931 1.76186644 4.03366663 1 P 0 ;0,1=138,2=0.000000
L 1.76186644 4.03366663 1.7632 4.0382498 1 P 0 ;0,1=138,2=0.000000
L 1.7632 4.0382498 1.76533337 4.0445 1 P 0 ;0,1=138,2=0.000000
L 1.76533337 4.0445 1.75466654 4.0445 1 P 0 ;0,1=138,2=0.000000
L 1.76493317 3.93291594 1.7667999 3.93583346 1 P 0 ;0,1=8,2=0.000000
L 1.7667999 3.93583346 1.7684 3.9374998 1 P 0 ;0,1=8,2=0.000000
L 1.7684 3.9374998 1.77053337 3.93833297 1 P 0 ;0,1=8,2=0.000000
L 1.77053337 3.93833297 1.7724002 3.9374998 1 P 0 ;0,1=8,2=0.000000
L 1.7724002 3.9374998 1.77373327 3.93583346 1 P 0 ;0,1=8,2=0.000000
L 1.77373327 3.93583346 1.7748001 3.93333327 1 P 0 ;0,1=8,2=0.000000
L 1.7748001 3.93333327 1.77506673 3.93041644 1 P 0 ;0,1=8,2=0.000000
L 1.77506673 3.93041644 1.7748001 3.92791624 1 P 0 ;0,1=8,2=0.000000
L 1.7748001 3.92791624 1.77373327 3.92541604 1 P 0 ;0,1=8,2=0.000000
L 1.77373327 3.92541604 1.77213307 3.92333307 1 P 0 ;0,1=8,2=0.000000
L 1.77213307 3.92333307 1.77026683 3.9225 1 P 0 ;0,1=8,2=0.000000
L 1.77026683 3.9225 1.76813346 3.92333307 1 P 0 ;0,1=8,2=0.000000
L 1.76813346 3.92333307 1.76626663 3.92583258 1 P 0 ;0,1=8,2=0.000000
L 1.76626663 3.92583258 1.7651998 3.92958327 1 P 0 ;0,1=8,2=0.000000
L 1.7651998 3.92958327 1.76493317 3.9337498 1 P 0 ;0,1=8,2=0.000000
L 1.76493317 3.9337498 1.76546634 3.93916614 1 P 0 ;0,1=8,2=0.000000
L 1.76546634 3.93916614 1.76626663 3.94208366 1 P 0 ;0,1=8,2=0.000000
L 1.76626663 3.94208366 1.7675997 3.9449997 1 P 0 ;0,1=8,2=0.000000
L 1.7675997 3.9449997 1.76946654 3.94708337 1 P 0 ;0,1=8,2=0.000000
L 1.76946654 3.94708337 1.77133327 3.9475 1 P 0 ;0,1=8,2=0.000000
L 1.77133327 3.9475 1.7732 3.94666683 1 P 0 ;0,1=8,2=0.000000
L 1.7732 3.94666683 1.77453356 3.94458317 1 P 0 ;0,1=8,2=0.000000
L 1.74613327 3.89324911 1.74773297 3.89116624 1 P 0 ;0,1=20,2=0.000000
L 1.74773297 3.89116624 1.7495997 3.88991654 1 P 0 ;0,1=20,2=0.000000
L 1.7495997 3.88991654 1.7519997 3.8895 1 P 0 ;0,1=20,2=0.000000
L 1.7519997 3.8895 1.7544002 3.89033307 1 P 0 ;0,1=20,2=0.000000
L 1.7544002 3.89033307 1.75626644 3.89199941 1 P 0 ;0,1=20,2=0.000000
L 1.75626644 3.89199941 1.7576 3.89491624 1 P 0 ;0,1=20,2=0.000000
L 1.7576 3.89491624 1.75786663 3.89824961 1 P 0 ;0,1=20,2=0.000000
L 1.75786663 3.89824961 1.75733337 3.90158297 1 P 0 ;0,1=20,2=0.000000
L 1.75733337 3.90158297 1.7559998 3.90366663 1 P 0 ;0,1=20,2=0.000000
L 1.7559998 3.90366663 1.75413307 3.90533297 1 P 0 ;0,1=20,2=0.000000
L 1.75413307 3.90533297 1.75226683 3.90574951 1 P 0 ;0,1=20,2=0.000000
L 1.75226683 3.90574951 1.7504 3.90533297 1 P 0 ;0,1=20,2=0.000000
L 1.7504 3.90533297 1.7480001 3.90366663 1 P 0 ;0,1=20,2=0.000000
L 1.7480001 3.90366663 1.7487999 3.9145 1 P 0 ;0,1=20,2=0.000000
L 1.7487999 3.9145 1.7559998 3.9145 1 P 0 ;0,1=20,2=0.000000
L 1.7299997 4.0575 1.73186644 4.05791654 1 P 0 ;0,1=16,2=0.000000
L 1.73186644 4.05791654 1.7339998 4.05916624 1 P 0 ;0,1=16,2=0.000000
L 1.7339998 4.05916624 1.73533337 4.06124911 1 P 0 ;0,1=16,2=0.000000
L 1.73533337 4.06124911 1.73586663 4.06416673 1 P 0 ;0,1=16,2=0.000000
L 1.73586663 4.06416673 1.73533337 4.06708278 1 P 0 ;0,1=16,2=0.000000
L 1.73533337 4.06708278 1.73373327 4.06958297 1 P 0 ;0,1=16,2=0.000000
L 1.73373327 4.06958297 1.73133327 4.07083346 1 P 0 ;0,1=16,2=0.000000
L 1.73133327 4.07083346 1.72866663 4.07083346 1 P 0 ;0,1=16,2=0.000000
L 1.72866663 4.07083346 1.72706654 4.07166663 1 P 0 ;0,1=16,2=0.000000
L 1.72706654 4.07166663 1.72573297 4.07374951 1 P 0 ;0,1=16,2=0.000000
L 1.72573297 4.07374951 1.7251998 4.07666634 1 P 0 ;0,1=16,2=0.000000
L 1.7251998 4.07666634 1.7260001 4.07958317 1 P 0 ;0,1=16,2=0.000000
L 1.7260001 4.07958317 1.72786634 4.08166683 1 P 0 ;0,1=16,2=0.000000
L 1.72786634 4.08166683 1.7299997 4.0825 1 P 0 ;0,1=16,2=0.000000
L 1.7299997 4.0825 1.73213307 4.08166683 1 P 0 ;0,1=16,2=0.000000
L 1.73213307 4.08166683 1.7339998 4.07958317 1 P 0 ;0,1=16,2=0.000000
L 1.7339998 4.07958317 1.7348001 4.07666634 1 P 0 ;0,1=16,2=0.000000
L 1.7348001 4.07666634 1.73426644 4.07374951 1 P 0 ;0,1=16,2=0.000000
L 1.73426644 4.07374951 1.73293337 4.07166663 1 P 0 ;0,1=16,2=0.000000
L 1.73293337 4.07166663 1.73133327 4.07083346 1 P 0 ;0,1=16,2=0.000000
L 1.73133327 4.07083346 1.72866663 4.07083346 1 P 0 ;0,1=16,2=0.000000
L 1.72866663 4.07083346 1.72626663 4.06958297 1 P 0 ;0,1=16,2=0.000000
L 1.72626663 4.06958297 1.72466654 4.06708278 1 P 0 ;0,1=16,2=0.000000
L 1.72466654 4.06708278 1.72413327 4.06416673 1 P 0 ;0,1=16,2=0.000000
L 1.72413327 4.06416673 1.72466654 4.06124911 1 P 0 ;0,1=16,2=0.000000
L 1.72466654 4.06124911 1.7260001 4.05916624 1 P 0 ;0,1=16,2=0.000000
L 1.7260001 4.05916624 1.72813346 4.05791654 1 P 0 ;0,1=16,2=0.000000
L 1.72813346 4.05791654 1.7299997 4.0575 1 P 0 ;0,1=16,2=0.000000
L 1.5939997 4.0625 1.5939997 4.0875 1 P 0 ;0,1=6,2=0.000000
L 1.5939997 4.0875 1.5907999 4.0825003 1 P 0 ;0,1=6,2=0.000000
L 1.5907999 4.0625 1.59719951 4.0625 1 P 0 ;0,1=6,2=0.000000
L 1.61093317 4.08333337 1.61253327 4.08583287 1 P 0 ;0,1=6,2=0.000000
L 1.61253327 4.08583287 1.6144 4.08708337 1 P 0 ;0,1=6,2=0.000000
L 1.6144 4.08708337 1.61653337 4.0875 1 P 0 ;0,1=6,2=0.000000
L 1.61653337 4.0875 1.6192 4.08666683 1 P 0 ;0,1=6,2=0.000000
L 1.6192 4.08666683 1.62106673 4.08458317 1 P 0 ;0,1=6,2=0.000000
L 1.62106673 4.08458317 1.6216 4.08208366 1 P 0 ;0,1=6,2=0.000000
L 1.6216 4.08208366 1.62133337 4.07958268 1 P 0 ;0,1=6,2=0.000000
L 1.62133337 4.07958268 1.62026644 4.0774998 1 P 0 ;0,1=6,2=0.000000
L 1.62026644 4.0774998 1.61493327 4.07333327 1 P 0 ;0,1=6,2=0.000000
L 1.61493327 4.07333327 1.61253327 4.07041644 1 P 0 ;0,1=6,2=0.000000
L 1.61253327 4.07041644 1.61093317 4.06624911 1 P 0 ;0,1=6,2=0.000000
L 1.61093317 4.06624911 1.6103999 4.0625 1 P 0 ;0,1=6,2=0.000000
L 1.6103999 4.0625 1.6216 4.0625 1 P 0 ;0,1=6,2=0.000000
L 1.68106663 3.7205 1.68106663 3.69828327 1 P 0 ;0,1=228,2=0.000000
L 1.68106663 3.69828327 1.6825997 3.69363238 1 P 0 ;0,1=228,2=0.000000
L 1.6825997 3.69363238 1.68566634 3.69053307 1 P 0 ;0,1=228,2=0.000000
L 1.68566634 3.69053307 1.68949961 3.6895 1 P 0 ;0,1=228,2=0.000000
L 1.68949961 3.6895 1.69333356 3.69053307 1 P 0 ;0,1=228,2=0.000000
L 1.69333356 3.69053307 1.6964002 3.69363238 1 P 0 ;0,1=228,2=0.000000
L 1.6964002 3.69363238 1.69793327 3.69828327 1 P 0 ;0,1=228,2=0.000000
L 1.69793327 3.69828327 1.69793327 3.7205 1 P 0 ;0,1=228,2=0.000000
L 1.71206663 3.69414892 1.71436614 3.69156614 1 P 0 ;0,1=228,2=0.000000
L 1.71436614 3.69156614 1.71704961 3.69001654 1 P 0 ;0,1=228,2=0.000000
L 1.71704961 3.69001654 1.72049961 3.6895 1 P 0 ;0,1=228,2=0.000000
L 1.72049961 3.6895 1.7239503 3.69053307 1 P 0 ;0,1=228,2=0.000000
L 1.7239503 3.69053307 1.72663307 3.69259931 1 P 0 ;0,1=228,2=0.000000
L 1.72663307 3.69259931 1.72855 3.69621614 1 P 0 ;0,1=228,2=0.000000
L 1.72855 3.69621614 1.72893327 3.70034951 1 P 0 ;0,1=228,2=0.000000
L 1.72893327 3.70034951 1.72816673 3.70448287 1 P 0 ;0,1=228,2=0.000000
L 1.72816673 3.70448287 1.7262498 3.70706663 1 P 0 ;0,1=228,2=0.000000
L 1.7262498 3.70706663 1.72356634 3.70913287 1 P 0 ;0,1=228,2=0.000000
L 1.72356634 3.70913287 1.72088356 3.70964941 1 P 0 ;0,1=228,2=0.000000
L 1.72088356 3.70964941 1.7182001 3.70913287 1 P 0 ;0,1=228,2=0.000000
L 1.7182001 3.70913287 1.7147501 3.70706663 1 P 0 ;0,1=228,2=0.000000
L 1.7147501 3.70706663 1.7158999 3.7205 1 P 0 ;0,1=228,2=0.000000
L 1.7158999 3.7205 1.7262498 3.7205 1 P 0 ;0,1=228,2=0.000000
L 1.5475 4.0189997 1.5225 4.0189997 1 P 0 ;0,1=218,2=270.000000
L 1.5225 4.0189997 1.5274997 4.0157999 1 P 0 ;0,1=218,2=270.000000
L 1.5475 4.0157999 1.5475 4.02219951 1 P 0 ;0,1=218,2=270.000000
L 1.54250039 4.03513327 1.54541713 4.03673297 1 P 0 ;0,1=218,2=270.000000
L 1.54541713 4.03673297 1.54708346 4.03886634 1 P 0 ;0,1=218,2=270.000000
L 1.54708346 4.03886634 1.5475 4.04126683 1 P 0 ;0,1=218,2=270.000000
L 1.5475 4.04126683 1.54708346 4.0434002 1 P 0 ;0,1=218,2=270.000000
L 1.54708346 4.0434002 1.54500059 4.04553356 1 P 0 ;0,1=218,2=270.000000
L 1.54500059 4.04553356 1.54250039 4.04686663 1 P 0 ;0,1=218,2=270.000000
L 1.54250039 4.04686663 1.5400001 4.04713317 1 P 0 ;0,1=218,2=270.000000
L 1.5400001 4.04713317 1.53708406 4.0466 1 P 0 ;0,1=218,2=270.000000
L 1.53708406 4.0466 1.53500039 4.04473327 1 P 0 ;0,1=218,2=270.000000
L 1.53500039 4.04473327 1.53416654 4.04286644 1 P 0 ;0,1=218,2=270.000000
L 1.53416654 4.04286644 1.53416654 4.04046654 1 P 0 ;0,1=218,2=270.000000
L 1.53416654 4.04286644 1.53291673 4.04446663 1 P 0 ;0,1=218,2=270.000000
L 1.53291673 4.04446663 1.53083386 4.0458001 1 P 0 ;0,1=218,2=270.000000
L 1.53083386 4.0458001 1.52833366 4.04633337 1 P 0 ;0,1=218,2=270.000000
L 1.52833366 4.04633337 1.52583346 4.0458001 1 P 0 ;0,1=218,2=270.000000
L 1.52583346 4.0458001 1.52375059 4.04446663 1 P 0 ;0,1=218,2=270.000000
L 1.52375059 4.04446663 1.5225 4.04206663 1 P 0 ;0,1=218,2=270.000000
L 1.5225 4.04206663 1.52291663 4.03966663 1 P 0 ;0,1=218,2=270.000000
L 1.52291663 4.03966663 1.52458366 4.03726663 1 P 0 ;0,1=218,2=270.000000
L 1.5525 3.8639997 1.5275 3.8639997 1 P 0 ;0,1=217,2=270.000000
L 1.5275 3.8639997 1.5324997 3.8607999 1 P 0 ;0,1=217,2=270.000000
L 1.5525 3.8607999 1.5525 3.86719951 1 P 0 ;0,1=217,2=270.000000
L 1.5525 3.8859997 1.55208346 3.88786644 1 P 0 ;0,1=217,2=270.000000
L 1.55208346 3.88786644 1.55083376 3.8899998 1 P 0 ;0,1=217,2=270.000000
L 1.55083376 3.8899998 1.54875089 3.89133337 1 P 0 ;0,1=217,2=270.000000
L 1.54875089 3.89133337 1.54583327 3.89186663 1 P 0 ;0,1=217,2=270.000000
L 1.54583327 3.89186663 1.54291722 3.89133337 1 P 0 ;0,1=217,2=270.000000
L 1.54291722 3.89133337 1.54041703 3.88973327 1 P 0 ;0,1=217,2=270.000000
L 1.54041703 3.88973327 1.53916654 3.88733327 1 P 0 ;0,1=217,2=270.000000
L 1.53916654 3.88733327 1.53916654 3.88466663 1 P 0 ;0,1=217,2=270.000000
L 1.53916654 3.88466663 1.53833337 3.88306654 1 P 0 ;0,1=217,2=270.000000
L 1.53833337 3.88306654 1.53625049 3.88173297 1 P 0 ;0,1=217,2=270.000000
L 1.53625049 3.88173297 1.53333366 3.8811998 1 P 0 ;0,1=217,2=270.000000
L 1.53333366 3.8811998 1.53041683 3.8820001 1 P 0 ;0,1=217,2=270.000000
L 1.53041683 3.8820001 1.52833317 3.88386634 1 P 0 ;0,1=217,2=270.000000
L 1.52833317 3.88386634 1.5275 3.8859997 1 P 0 ;0,1=217,2=270.000000
L 1.5275 3.8859997 1.52833317 3.88813307 1 P 0 ;0,1=217,2=270.000000
L 1.52833317 3.88813307 1.53041683 3.8899998 1 P 0 ;0,1=217,2=270.000000
L 1.53041683 3.8899998 1.53333366 3.8908001 1 P 0 ;0,1=217,2=270.000000
L 1.53333366 3.8908001 1.53625049 3.89026644 1 P 0 ;0,1=217,2=270.000000
L 1.53625049 3.89026644 1.53833337 3.88893337 1 P 0 ;0,1=217,2=270.000000
L 1.53833337 3.88893337 1.53916654 3.88733327 1 P 0 ;0,1=217,2=270.000000
L 1.53916654 3.88733327 1.53916654 3.88466663 1 P 0 ;0,1=217,2=270.000000
L 1.53916654 3.88466663 1.54041703 3.88226663 1 P 0 ;0,1=217,2=270.000000
L 1.54041703 3.88226663 1.54291722 3.88066654 1 P 0 ;0,1=217,2=270.000000
L 1.54291722 3.88066654 1.54583327 3.88013327 1 P 0 ;0,1=217,2=270.000000
L 1.54583327 3.88013327 1.54875089 3.88066654 1 P 0 ;0,1=217,2=270.000000
L 1.54875089 3.88066654 1.55083376 3.8820001 1 P 0 ;0,1=217,2=270.000000
L 1.55083376 3.8820001 1.55208346 3.88413346 1 P 0 ;0,1=217,2=270.000000
L 1.55208346 3.88413346 1.5525 3.8859997 1 P 0 ;0,1=217,2=270.000000
L 3.43996004 4.09896004 3.43996004 3.92503996 1 P 0 
L 3.26638002 4.09896004 3.43996004 4.09896004 1 P 0 
L 3.43996004 3.92503996 3.26638002 3.92503996 1 P 0 
L 3.26638002 3.92503996 3.26638002 4.09896004 1 P 0 
S P 0
OB 3.4121 4.133419980315 I
OC 3.4121 4.133419980315 3.3921 4.133419980315 Y
OE
SE
L 3.4775 4.0939997 3.4525 4.0939997 1 P 0 ;0,1=217,2=270.000000
L 3.4525 4.0939997 3.4574997 4.0907999 1 P 0 ;0,1=217,2=270.000000
L 3.4775 4.0907999 3.4775 4.09719951 1 P 0 ;0,1=217,2=270.000000
L 3.4775 4.1159997 3.47708346 4.11786644 1 P 0 ;0,1=217,2=270.000000
L 3.47708346 4.11786644 3.47583376 4.1199998 1 P 0 ;0,1=217,2=270.000000
L 3.47583376 4.1199998 3.47375089 4.12133337 1 P 0 ;0,1=217,2=270.000000
L 3.47375089 4.12133337 3.47083327 4.12186663 1 P 0 ;0,1=217,2=270.000000
L 3.47083327 4.12186663 3.46791722 4.12133337 1 P 0 ;0,1=217,2=270.000000
L 3.46791722 4.12133337 3.46541703 4.11973327 1 P 0 ;0,1=217,2=270.000000
L 3.46541703 4.11973327 3.46416654 4.11733327 1 P 0 ;0,1=217,2=270.000000
L 3.46416654 4.11733327 3.46416654 4.11466663 1 P 0 ;0,1=217,2=270.000000
L 3.46416654 4.11466663 3.46333337 4.11306654 1 P 0 ;0,1=217,2=270.000000
L 3.46333337 4.11306654 3.46125049 4.11173297 1 P 0 ;0,1=217,2=270.000000
L 3.46125049 4.11173297 3.45833366 4.1111998 1 P 0 ;0,1=217,2=270.000000
L 3.45833366 4.1111998 3.45541683 4.1120001 1 P 0 ;0,1=217,2=270.000000
L 3.45541683 4.1120001 3.45333317 4.11386634 1 P 0 ;0,1=217,2=270.000000
L 3.45333317 4.11386634 3.4525 4.1159997 1 P 0 ;0,1=217,2=270.000000
L 3.4525 4.1159997 3.45333317 4.11813307 1 P 0 ;0,1=217,2=270.000000
L 3.45333317 4.11813307 3.45541683 4.1199998 1 P 0 ;0,1=217,2=270.000000
L 3.45541683 4.1199998 3.45833366 4.1208001 1 P 0 ;0,1=217,2=270.000000
L 3.45833366 4.1208001 3.46125049 4.12026644 1 P 0 ;0,1=217,2=270.000000
L 3.46125049 4.12026644 3.46333337 4.11893337 1 P 0 ;0,1=217,2=270.000000
L 3.46333337 4.11893337 3.46416654 4.11733327 1 P 0 ;0,1=217,2=270.000000
L 3.46416654 4.11733327 3.46416654 4.11466663 1 P 0 ;0,1=217,2=270.000000
L 3.46416654 4.11466663 3.46541703 4.11226663 1 P 0 ;0,1=217,2=270.000000
L 3.46541703 4.11226663 3.46791722 4.11066654 1 P 0 ;0,1=217,2=270.000000
L 3.46791722 4.11066654 3.47083327 4.11013327 1 P 0 ;0,1=217,2=270.000000
L 3.47083327 4.11013327 3.47375089 4.11066654 1 P 0 ;0,1=217,2=270.000000
L 3.47375089 4.11066654 3.47583376 4.1120001 1 P 0 ;0,1=217,2=270.000000
L 3.47583376 4.1120001 3.47708346 4.11413346 1 P 0 ;0,1=217,2=270.000000
L 3.47708346 4.11413346 3.4775 4.1159997 1 P 0 ;0,1=217,2=270.000000
L 3.4495 4.00106663 3.47171673 4.00106663 1 P 0 ;0,1=229,2=270.000000
L 3.47171673 4.00106663 3.47636762 4.0025997 1 P 0 ;0,1=229,2=270.000000
L 3.47636762 4.0025997 3.47946693 4.00566634 1 P 0 ;0,1=229,2=270.000000
L 3.47946693 4.00566634 3.4805 4.00949961 1 P 0 ;0,1=229,2=270.000000
L 3.4805 4.00949961 3.47946693 4.01333356 1 P 0 ;0,1=229,2=270.000000
L 3.47946693 4.01333356 3.47636762 4.0164002 1 P 0 ;0,1=229,2=270.000000
L 3.47636762 4.0164002 3.47171673 4.01793327 1 P 0 ;0,1=229,2=270.000000
L 3.47171673 4.01793327 3.4495 4.01793327 1 P 0 ;0,1=229,2=270.000000
L 3.46758425 4.03321644 3.46396644 4.0358999 1 P 0 ;0,1=229,2=270.000000
L 3.46396644 4.0358999 3.4619002 4.0382001 1 P 0 ;0,1=229,2=270.000000
L 3.4619002 4.0382001 3.46086713 4.04126683 1 P 0 ;0,1=229,2=270.000000
L 3.46086713 4.04126683 3.4619002 4.0439503 1 P 0 ;0,1=229,2=270.000000
L 3.4619002 4.0439503 3.46396644 4.04586654 1 P 0 ;0,1=229,2=270.000000
L 3.46396644 4.04586654 3.46706673 4.0474002 1 P 0 ;0,1=229,2=270.000000
L 3.46706673 4.0474002 3.47068356 4.04778346 1 P 0 ;0,1=229,2=270.000000
L 3.47068356 4.04778346 3.47378386 4.0474002 1 P 0 ;0,1=229,2=270.000000
L 3.47378386 4.0474002 3.47688415 4.04586654 1 P 0 ;0,1=229,2=270.000000
L 3.47688415 4.04586654 3.47946693 4.04356634 1 P 0 ;0,1=229,2=270.000000
L 3.47946693 4.04356634 3.4805 4.04088356 1 P 0 ;0,1=229,2=270.000000
L 3.4805 4.04088356 3.47946693 4.03781683 1 P 0 ;0,1=229,2=270.000000
L 3.47946693 4.03781683 3.47636762 4.03513337 1 P 0 ;0,1=229,2=270.000000
L 3.47636762 4.03513337 3.47171673 4.0335997 1 P 0 ;0,1=229,2=270.000000
L 3.47171673 4.0335997 3.4665502 4.03321644 1 P 0 ;0,1=229,2=270.000000
L 3.4665502 4.03321644 3.45983406 4.03398287 1 P 0 ;0,1=229,2=270.000000
L 3.45983406 4.03398287 3.45621624 4.03513337 1 P 0 ;0,1=229,2=270.000000
L 3.45621624 4.03513337 3.4526003 4.03704961 1 P 0 ;0,1=229,2=270.000000
L 3.4526003 4.03704961 3.45001663 4.03973307 1 P 0 ;0,1=229,2=270.000000
L 3.45001663 4.03973307 3.4495 4.04241654 1 P 0 ;0,1=229,2=270.000000
L 3.4495 4.04241654 3.45053317 4.0451 1 P 0 ;0,1=229,2=270.000000
L 3.45053317 4.0451 3.45311693 4.04701703 1 P 0 ;0,1=229,2=270.000000
L 3.4775 3.9389997 3.4525 3.9389997 1 P 0 ;0,1=218,2=270.000000
L 3.4525 3.9389997 3.4574997 3.9357999 1 P 0 ;0,1=218,2=270.000000
L 3.4775 3.9357999 3.4775 3.94219951 1 P 0 ;0,1=218,2=270.000000
L 3.47250039 3.95513327 3.47541713 3.95673297 1 P 0 ;0,1=218,2=270.000000
L 3.47541713 3.95673297 3.47708346 3.95886634 1 P 0 ;0,1=218,2=270.000000
L 3.47708346 3.95886634 3.4775 3.96126683 1 P 0 ;0,1=218,2=270.000000
L 3.4775 3.96126683 3.47708346 3.9634002 1 P 0 ;0,1=218,2=270.000000
L 3.47708346 3.9634002 3.47500059 3.96553356 1 P 0 ;0,1=218,2=270.000000
L 3.47500059 3.96553356 3.47250039 3.96686663 1 P 0 ;0,1=218,2=270.000000
L 3.47250039 3.96686663 3.4700001 3.96713317 1 P 0 ;0,1=218,2=270.000000
L 3.4700001 3.96713317 3.46708406 3.9666 1 P 0 ;0,1=218,2=270.000000
L 3.46708406 3.9666 3.46500039 3.96473327 1 P 0 ;0,1=218,2=270.000000
L 3.46500039 3.96473327 3.46416654 3.96286644 1 P 0 ;0,1=218,2=270.000000
L 3.46416654 3.96286644 3.46416654 3.96046654 1 P 0 ;0,1=218,2=270.000000
L 3.46416654 3.96286644 3.46291673 3.96446663 1 P 0 ;0,1=218,2=270.000000
L 3.46291673 3.96446663 3.46083386 3.9658001 1 P 0 ;0,1=218,2=270.000000
L 3.46083386 3.9658001 3.45833366 3.96633337 1 P 0 ;0,1=218,2=270.000000
L 3.45833366 3.96633337 3.45583346 3.9658001 1 P 0 ;0,1=218,2=270.000000
L 3.45583346 3.9658001 3.45375059 3.96446663 1 P 0 ;0,1=218,2=270.000000
L 3.45375059 3.96446663 3.4525 3.96206663 1 P 0 ;0,1=218,2=270.000000
L 3.4525 3.96206663 3.45291663 3.95966663 1 P 0 ;0,1=218,2=270.000000
L 3.45291663 3.95966663 3.45458366 3.95726663 1 P 0 ;0,1=218,2=270.000000
L 3.4189997 3.8875 3.4189997 3.9125 1 P 0 ;0,1=6,2=0.000000
L 3.4189997 3.9125 3.4157999 3.9075003 1 P 0 ;0,1=6,2=0.000000
L 3.4157999 3.8875 3.42219951 3.8875 1 P 0 ;0,1=6,2=0.000000
L 3.43593317 3.90833337 3.43753327 3.91083287 1 P 0 ;0,1=6,2=0.000000
L 3.43753327 3.91083287 3.4394 3.91208337 1 P 0 ;0,1=6,2=0.000000
L 3.4394 3.91208337 3.44153337 3.9125 1 P 0 ;0,1=6,2=0.000000
L 3.44153337 3.9125 3.4442 3.91166683 1 P 0 ;0,1=6,2=0.000000
L 3.4442 3.91166683 3.44606673 3.90958317 1 P 0 ;0,1=6,2=0.000000
L 3.44606673 3.90958317 3.4466 3.90708366 1 P 0 ;0,1=6,2=0.000000
L 3.4466 3.90708366 3.44633337 3.90458268 1 P 0 ;0,1=6,2=0.000000
L 3.44633337 3.90458268 3.44526644 3.9024998 1 P 0 ;0,1=6,2=0.000000
L 3.44526644 3.9024998 3.43993327 3.89833327 1 P 0 ;0,1=6,2=0.000000
L 3.43993327 3.89833327 3.43753327 3.89541644 1 P 0 ;0,1=6,2=0.000000
L 3.43753327 3.89541644 3.43593317 3.89124911 1 P 0 ;0,1=6,2=0.000000
L 3.43593317 3.89124911 3.4353999 3.8875 1 P 0 ;0,1=6,2=0.000000
L 3.4353999 3.8875 3.4466 3.8875 1 P 0 ;0,1=6,2=0.000000
L 3.24493317 4.02491594 3.2467999 4.02783346 1 P 0 ;0,1=8,2=0.000000
L 3.2467999 4.02783346 3.2484 4.0294998 1 P 0 ;0,1=8,2=0.000000
L 3.2484 4.0294998 3.25053337 4.03033297 1 P 0 ;0,1=8,2=0.000000
L 3.25053337 4.03033297 3.2524002 4.0294998 1 P 0 ;0,1=8,2=0.000000
L 3.2524002 4.0294998 3.25373327 4.02783346 1 P 0 ;0,1=8,2=0.000000
L 3.25373327 4.02783346 3.2548001 4.02533327 1 P 0 ;0,1=8,2=0.000000
L 3.2548001 4.02533327 3.25506673 4.02241644 1 P 0 ;0,1=8,2=0.000000
L 3.25506673 4.02241644 3.2548001 4.01991624 1 P 0 ;0,1=8,2=0.000000
L 3.2548001 4.01991624 3.25373327 4.01741604 1 P 0 ;0,1=8,2=0.000000
L 3.25373327 4.01741604 3.25213307 4.01533307 1 P 0 ;0,1=8,2=0.000000
L 3.25213307 4.01533307 3.25026683 4.0145 1 P 0 ;0,1=8,2=0.000000
L 3.25026683 4.0145 3.24813346 4.01533307 1 P 0 ;0,1=8,2=0.000000
L 3.24813346 4.01533307 3.24626663 4.01783258 1 P 0 ;0,1=8,2=0.000000
L 3.24626663 4.01783258 3.2451998 4.02158327 1 P 0 ;0,1=8,2=0.000000
L 3.2451998 4.02158327 3.24493317 4.0257498 1 P 0 ;0,1=8,2=0.000000
L 3.24493317 4.0257498 3.24546634 4.03116614 1 P 0 ;0,1=8,2=0.000000
L 3.24546634 4.03116614 3.24626663 4.03408366 1 P 0 ;0,1=8,2=0.000000
L 3.24626663 4.03408366 3.2475997 4.0369997 1 P 0 ;0,1=8,2=0.000000
L 3.2475997 4.0369997 3.24946654 4.03908337 1 P 0 ;0,1=8,2=0.000000
L 3.24946654 4.03908337 3.25133327 4.0395 1 P 0 ;0,1=8,2=0.000000
L 3.25133327 4.0395 3.2532 4.03866683 1 P 0 ;0,1=8,2=0.000000
L 3.2532 4.03866683 3.25453356 4.03658317 1 P 0 ;0,1=8,2=0.000000
L 3.24413327 4.06324911 3.24573297 4.06116624 1 P 0 ;0,1=20,2=0.000000
L 3.24573297 4.06116624 3.2475997 4.05991654 1 P 0 ;0,1=20,2=0.000000
L 3.2475997 4.05991654 3.2499997 4.0595 1 P 0 ;0,1=20,2=0.000000
L 3.2499997 4.0595 3.2524002 4.06033307 1 P 0 ;0,1=20,2=0.000000
L 3.2524002 4.06033307 3.25426644 4.06199941 1 P 0 ;0,1=20,2=0.000000
L 3.25426644 4.06199941 3.2556 4.06491624 1 P 0 ;0,1=20,2=0.000000
L 3.2556 4.06491624 3.25586663 4.06824961 1 P 0 ;0,1=20,2=0.000000
L 3.25586663 4.06824961 3.25533337 4.07158297 1 P 0 ;0,1=20,2=0.000000
L 3.25533337 4.07158297 3.2539998 4.07366663 1 P 0 ;0,1=20,2=0.000000
L 3.2539998 4.07366663 3.25213307 4.07533297 1 P 0 ;0,1=20,2=0.000000
L 3.25213307 4.07533297 3.25026683 4.07574951 1 P 0 ;0,1=20,2=0.000000
L 3.25026683 4.07574951 3.2484 4.07533297 1 P 0 ;0,1=20,2=0.000000
L 3.2484 4.07533297 3.2460001 4.07366663 1 P 0 ;0,1=20,2=0.000000
L 3.2460001 4.07366663 3.2467999 4.0845 1 P 0 ;0,1=20,2=0.000000
L 3.2467999 4.0845 3.2539998 4.0845 1 P 0 ;0,1=20,2=0.000000
L 3.24446654 3.9725 3.2449997 3.97791624 1 P 0 ;0,1=138,2=0.000000
L 3.2449997 3.97791624 3.2458 3.98249931 1 P 0 ;0,1=138,2=0.000000
L 3.2458 3.98249931 3.24686644 3.98666663 1 P 0 ;0,1=138,2=0.000000
L 3.24686644 3.98666663 3.2482 3.9912498 1 P 0 ;0,1=138,2=0.000000
L 3.2482 3.9912498 3.25033337 3.9975 1 P 0 ;0,1=138,2=0.000000
L 3.25033337 3.9975 3.23966654 3.9975 1 P 0 ;0,1=138,2=0.000000
L 3.2349997 3.9225 3.23686644 3.92291654 1 P 0 ;0,1=16,2=0.000000
L 3.23686644 3.92291654 3.2389998 3.92416624 1 P 0 ;0,1=16,2=0.000000
L 3.2389998 3.92416624 3.24033337 3.92624911 1 P 0 ;0,1=16,2=0.000000
L 3.24033337 3.92624911 3.24086663 3.92916673 1 P 0 ;0,1=16,2=0.000000
L 3.24086663 3.92916673 3.24033337 3.93208278 1 P 0 ;0,1=16,2=0.000000
L 3.24033337 3.93208278 3.23873327 3.93458297 1 P 0 ;0,1=16,2=0.000000
L 3.23873327 3.93458297 3.23633327 3.93583346 1 P 0 ;0,1=16,2=0.000000
L 3.23633327 3.93583346 3.23366663 3.93583346 1 P 0 ;0,1=16,2=0.000000
L 3.23366663 3.93583346 3.23206654 3.93666663 1 P 0 ;0,1=16,2=0.000000
L 3.23206654 3.93666663 3.23073297 3.93874951 1 P 0 ;0,1=16,2=0.000000
L 3.23073297 3.93874951 3.2301998 3.94166634 1 P 0 ;0,1=16,2=0.000000
L 3.2301998 3.94166634 3.2310001 3.94458317 1 P 0 ;0,1=16,2=0.000000
L 3.2310001 3.94458317 3.23286634 3.94666683 1 P 0 ;0,1=16,2=0.000000
L 3.23286634 3.94666683 3.2349997 3.9475 1 P 0 ;0,1=16,2=0.000000
L 3.2349997 3.9475 3.23713307 3.94666683 1 P 0 ;0,1=16,2=0.000000
L 3.23713307 3.94666683 3.2389998 3.94458317 1 P 0 ;0,1=16,2=0.000000
L 3.2389998 3.94458317 3.2398001 3.94166634 1 P 0 ;0,1=16,2=0.000000
L 3.2398001 3.94166634 3.23926644 3.93874951 1 P 0 ;0,1=16,2=0.000000
L 3.23926644 3.93874951 3.23793337 3.93666663 1 P 0 ;0,1=16,2=0.000000
L 3.23793337 3.93666663 3.23633327 3.93583346 1 P 0 ;0,1=16,2=0.000000
L 3.23633327 3.93583346 3.23366663 3.93583346 1 P 0 ;0,1=16,2=0.000000
L 3.23366663 3.93583346 3.23126663 3.93458297 1 P 0 ;0,1=16,2=0.000000
L 3.23126663 3.93458297 3.22966654 3.93208278 1 P 0 ;0,1=16,2=0.000000
L 3.22966654 3.93208278 3.22913327 3.92916673 1 P 0 ;0,1=16,2=0.000000
L 3.22913327 3.92916673 3.22966654 3.92624911 1 P 0 ;0,1=16,2=0.000000
L 3.22966654 3.92624911 3.2310001 3.92416624 1 P 0 ;0,1=16,2=0.000000
L 3.2310001 3.92416624 3.23313346 3.92291654 1 P 0 ;0,1=16,2=0.000000
L 3.23313346 3.92291654 3.2349997 3.9225 1 P 0 ;0,1=16,2=0.000000
L 5.66196004 2.24196004 5.66196004 2.06838002 1 P 0 
L 5.48803996 2.24196004 5.66196004 2.24196004 1 P 0 
L 5.48803996 2.06838002 5.48803996 2.24196004 1 P 0 
L 5.66196004 2.06838002 5.48803996 2.06838002 1 P 0 
S P 0
OB 5.473580019685 2.1941 I
OC 5.473580019685 2.1941 5.453580019685 2.1941 Y
OE
SE
L 5.6689997 2.2425 5.6689997 2.2675 1 P 0 ;0,1=218,2=0.000000
L 5.6689997 2.2675 5.6657999 2.2625003 1 P 0 ;0,1=218,2=0.000000
L 5.6657999 2.2425 5.67219951 2.2425 1 P 0 ;0,1=218,2=0.000000
L 5.68513327 2.24749961 5.68673297 2.24458287 1 P 0 ;0,1=218,2=0.000000
L 5.68673297 2.24458287 5.68886634 2.24291654 1 P 0 ;0,1=218,2=0.000000
L 5.68886634 2.24291654 5.69126683 2.2425 1 P 0 ;0,1=218,2=0.000000
L 5.69126683 2.2425 5.6934002 2.24291654 1 P 0 ;0,1=218,2=0.000000
L 5.6934002 2.24291654 5.69553356 2.24499941 1 P 0 ;0,1=218,2=0.000000
L 5.69553356 2.24499941 5.69686663 2.24749961 1 P 0 ;0,1=218,2=0.000000
L 5.69686663 2.24749961 5.69713317 2.2499999 1 P 0 ;0,1=218,2=0.000000
L 5.69713317 2.2499999 5.6966 2.25291594 1 P 0 ;0,1=218,2=0.000000
L 5.6966 2.25291594 5.69473327 2.25499961 1 P 0 ;0,1=218,2=0.000000
L 5.69473327 2.25499961 5.69286644 2.25583346 1 P 0 ;0,1=218,2=0.000000
L 5.69286644 2.25583346 5.69046654 2.25583346 1 P 0 ;0,1=218,2=0.000000
L 5.69286644 2.25583346 5.69446663 2.25708327 1 P 0 ;0,1=218,2=0.000000
L 5.69446663 2.25708327 5.6958001 2.25916614 1 P 0 ;0,1=218,2=0.000000
L 5.6958001 2.25916614 5.69633337 2.26166634 1 P 0 ;0,1=218,2=0.000000
L 5.69633337 2.26166634 5.6958001 2.26416654 1 P 0 ;0,1=218,2=0.000000
L 5.6958001 2.26416654 5.69446663 2.26624941 1 P 0 ;0,1=218,2=0.000000
L 5.69446663 2.26624941 5.69206663 2.2675 1 P 0 ;0,1=218,2=0.000000
L 5.69206663 2.2675 5.68966663 2.26708337 1 P 0 ;0,1=218,2=0.000000
L 5.68966663 2.26708337 5.68726663 2.26541634 1 P 0 ;0,1=218,2=0.000000
L 5.6889997 2.1925 5.6889997 2.2175 1 P 0 ;0,1=6,2=0.000000
L 5.6889997 2.2175 5.6857999 2.2125003 1 P 0 ;0,1=6,2=0.000000
L 5.6857999 2.1925 5.69219951 2.1925 1 P 0 ;0,1=6,2=0.000000
L 5.70593317 2.21333337 5.70753327 2.21583287 1 P 0 ;0,1=6,2=0.000000
L 5.70753327 2.21583287 5.7094 2.21708337 1 P 0 ;0,1=6,2=0.000000
L 5.7094 2.21708337 5.71153337 2.2175 1 P 0 ;0,1=6,2=0.000000
L 5.71153337 2.2175 5.7142 2.21666683 1 P 0 ;0,1=6,2=0.000000
L 5.7142 2.21666683 5.71606673 2.21458317 1 P 0 ;0,1=6,2=0.000000
L 5.71606673 2.21458317 5.7166 2.21208366 1 P 0 ;0,1=6,2=0.000000
L 5.7166 2.21208366 5.71633337 2.20958268 1 P 0 ;0,1=6,2=0.000000
L 5.71633337 2.20958268 5.71526644 2.2074998 1 P 0 ;0,1=6,2=0.000000
L 5.71526644 2.2074998 5.70993327 2.20333327 1 P 0 ;0,1=6,2=0.000000
L 5.70993327 2.20333327 5.70753327 2.20041644 1 P 0 ;0,1=6,2=0.000000
L 5.70753327 2.20041644 5.70593317 2.19624911 1 P 0 ;0,1=6,2=0.000000
L 5.70593317 2.19624911 5.7053999 2.1925 1 P 0 ;0,1=6,2=0.000000
L 5.7053999 2.1925 5.7166 2.1925 1 P 0 ;0,1=6,2=0.000000
L 5.6699997 2.0245 5.67186644 2.02491654 1 P 0 ;0,1=16,2=0.000000
L 5.67186644 2.02491654 5.6739998 2.02616624 1 P 0 ;0,1=16,2=0.000000
L 5.6739998 2.02616624 5.67533337 2.02824911 1 P 0 ;0,1=16,2=0.000000
L 5.67533337 2.02824911 5.67586663 2.03116673 1 P 0 ;0,1=16,2=0.000000
L 5.67586663 2.03116673 5.67533337 2.03408278 1 P 0 ;0,1=16,2=0.000000
L 5.67533337 2.03408278 5.67373327 2.03658297 1 P 0 ;0,1=16,2=0.000000
L 5.67373327 2.03658297 5.67133327 2.03783346 1 P 0 ;0,1=16,2=0.000000
L 5.67133327 2.03783346 5.66866663 2.03783346 1 P 0 ;0,1=16,2=0.000000
L 5.66866663 2.03783346 5.66706654 2.03866663 1 P 0 ;0,1=16,2=0.000000
L 5.66706654 2.03866663 5.66573297 2.04074951 1 P 0 ;0,1=16,2=0.000000
L 5.66573297 2.04074951 5.6651998 2.04366634 1 P 0 ;0,1=16,2=0.000000
L 5.6651998 2.04366634 5.6660001 2.04658317 1 P 0 ;0,1=16,2=0.000000
L 5.6660001 2.04658317 5.66786634 2.04866683 1 P 0 ;0,1=16,2=0.000000
L 5.66786634 2.04866683 5.6699997 2.0495 1 P 0 ;0,1=16,2=0.000000
L 5.6699997 2.0495 5.67213307 2.04866683 1 P 0 ;0,1=16,2=0.000000
L 5.67213307 2.04866683 5.6739998 2.04658317 1 P 0 ;0,1=16,2=0.000000
L 5.6739998 2.04658317 5.6748001 2.04366634 1 P 0 ;0,1=16,2=0.000000
L 5.6748001 2.04366634 5.67426644 2.04074951 1 P 0 ;0,1=16,2=0.000000
L 5.67426644 2.04074951 5.67293337 2.03866663 1 P 0 ;0,1=16,2=0.000000
L 5.67293337 2.03866663 5.67133327 2.03783346 1 P 0 ;0,1=16,2=0.000000
L 5.67133327 2.03783346 5.66866663 2.03783346 1 P 0 ;0,1=16,2=0.000000
L 5.66866663 2.03783346 5.66626663 2.03658297 1 P 0 ;0,1=16,2=0.000000
L 5.66626663 2.03658297 5.66466654 2.03408278 1 P 0 ;0,1=16,2=0.000000
L 5.66466654 2.03408278 5.66413327 2.03116673 1 P 0 ;0,1=16,2=0.000000
L 5.66413327 2.03116673 5.66466654 2.02824911 1 P 0 ;0,1=16,2=0.000000
L 5.66466654 2.02824911 5.6660001 2.02616624 1 P 0 ;0,1=16,2=0.000000
L 5.6660001 2.02616624 5.66813346 2.02491654 1 P 0 ;0,1=16,2=0.000000
L 5.66813346 2.02491654 5.6699997 2.0245 1 P 0 ;0,1=16,2=0.000000
L 5.59352657 2.02551004 5.59405974 2.03092628 1 P 0 ;0,1=138,2=0.000000
L 5.59405974 2.03092628 5.59486004 2.03550935 1 P 0 ;0,1=138,2=0.000000
L 5.59486004 2.03550935 5.59592648 2.03967667 1 P 0 ;0,1=138,2=0.000000
L 5.59592648 2.03967667 5.59726004 2.04425984 1 P 0 ;0,1=138,2=0.000000
L 5.59726004 2.04425984 5.59939341 2.05051004 1 P 0 ;0,1=138,2=0.000000
L 5.59939341 2.05051004 5.58872657 2.05051004 1 P 0 ;0,1=138,2=0.000000
L 5.4689997 2.2545 5.4689997 2.2795 1 P 0 ;0,1=217,2=0.000000
L 5.4689997 2.2795 5.4657999 2.2745003 1 P 0 ;0,1=217,2=0.000000
L 5.4657999 2.2545 5.47219951 2.2545 1 P 0 ;0,1=217,2=0.000000
L 5.4909997 2.2545 5.49286644 2.25491654 1 P 0 ;0,1=217,2=0.000000
L 5.49286644 2.25491654 5.4949998 2.25616624 1 P 0 ;0,1=217,2=0.000000
L 5.4949998 2.25616624 5.49633337 2.25824911 1 P 0 ;0,1=217,2=0.000000
L 5.49633337 2.25824911 5.49686663 2.26116673 1 P 0 ;0,1=217,2=0.000000
L 5.49686663 2.26116673 5.49633337 2.26408278 1 P 0 ;0,1=217,2=0.000000
L 5.49633337 2.26408278 5.49473327 2.26658297 1 P 0 ;0,1=217,2=0.000000
L 5.49473327 2.26658297 5.49233327 2.26783346 1 P 0 ;0,1=217,2=0.000000
L 5.49233327 2.26783346 5.48966663 2.26783346 1 P 0 ;0,1=217,2=0.000000
L 5.48966663 2.26783346 5.48806654 2.26866663 1 P 0 ;0,1=217,2=0.000000
L 5.48806654 2.26866663 5.48673297 2.27074951 1 P 0 ;0,1=217,2=0.000000
L 5.48673297 2.27074951 5.4861998 2.27366634 1 P 0 ;0,1=217,2=0.000000
L 5.4861998 2.27366634 5.4870001 2.27658317 1 P 0 ;0,1=217,2=0.000000
L 5.4870001 2.27658317 5.48886634 2.27866683 1 P 0 ;0,1=217,2=0.000000
L 5.48886634 2.27866683 5.4909997 2.2795 1 P 0 ;0,1=217,2=0.000000
L 5.4909997 2.2795 5.49313307 2.27866683 1 P 0 ;0,1=217,2=0.000000
L 5.49313307 2.27866683 5.4949998 2.27658317 1 P 0 ;0,1=217,2=0.000000
L 5.4949998 2.27658317 5.4958001 2.27366634 1 P 0 ;0,1=217,2=0.000000
L 5.4958001 2.27366634 5.49526644 2.27074951 1 P 0 ;0,1=217,2=0.000000
L 5.49526644 2.27074951 5.49393337 2.26866663 1 P 0 ;0,1=217,2=0.000000
L 5.49393337 2.26866663 5.49233327 2.26783346 1 P 0 ;0,1=217,2=0.000000
L 5.49233327 2.26783346 5.48966663 2.26783346 1 P 0 ;0,1=217,2=0.000000
L 5.48966663 2.26783346 5.48726663 2.26658297 1 P 0 ;0,1=217,2=0.000000
L 5.48726663 2.26658297 5.48566654 2.26408278 1 P 0 ;0,1=217,2=0.000000
L 5.48566654 2.26408278 5.48513327 2.26116673 1 P 0 ;0,1=217,2=0.000000
L 5.48513327 2.26116673 5.48566654 2.25824911 1 P 0 ;0,1=217,2=0.000000
L 5.48566654 2.25824911 5.4870001 2.25616624 1 P 0 ;0,1=217,2=0.000000
L 5.4870001 2.25616624 5.48913346 2.25491654 1 P 0 ;0,1=217,2=0.000000
L 5.48913346 2.25491654 5.4909997 2.2545 1 P 0 ;0,1=217,2=0.000000
L 5.54056663 2.2805 5.54056663 2.25828327 1 P 0 ;0,1=230,2=0.000000
L 5.54056663 2.25828327 5.5420997 2.25363238 1 P 0 ;0,1=230,2=0.000000
L 5.5420997 2.25363238 5.54516634 2.25053307 1 P 0 ;0,1=230,2=0.000000
L 5.54516634 2.25053307 5.54899961 2.2495 1 P 0 ;0,1=230,2=0.000000
L 5.54899961 2.2495 5.55283356 2.25053307 1 P 0 ;0,1=230,2=0.000000
L 5.55283356 2.25053307 5.5559002 2.25363238 1 P 0 ;0,1=230,2=0.000000
L 5.5559002 2.25363238 5.55743327 2.25828327 1 P 0 ;0,1=230,2=0.000000
L 5.55743327 2.25828327 5.55743327 2.2805 1 P 0 ;0,1=230,2=0.000000
L 5.57271644 2.27533346 5.57501663 2.27843278 1 P 0 ;0,1=230,2=0.000000
L 5.57501663 2.27843278 5.5777001 2.27998337 1 P 0 ;0,1=230,2=0.000000
L 5.5777001 2.27998337 5.58076683 2.2805 1 P 0 ;0,1=230,2=0.000000
L 5.58076683 2.2805 5.5846 2.27946683 1 P 0 ;0,1=230,2=0.000000
L 5.5846 2.27946683 5.58728346 2.27688307 1 P 0 ;0,1=230,2=0.000000
L 5.58728346 2.27688307 5.58805 2.27378376 1 P 0 ;0,1=230,2=0.000000
L 5.58805 2.27378376 5.58766673 2.27068258 1 P 0 ;0,1=230,2=0.000000
L 5.58766673 2.27068258 5.58613307 2.2680998 1 P 0 ;0,1=230,2=0.000000
L 5.58613307 2.2680998 5.57846663 2.26293327 1 P 0 ;0,1=230,2=0.000000
L 5.57846663 2.26293327 5.57501663 2.25931644 1 P 0 ;0,1=230,2=0.000000
L 5.57501663 2.25931644 5.57271644 2.25414892 1 P 0 ;0,1=230,2=0.000000
L 5.57271644 2.25414892 5.5719499 2.2495 1 P 0 ;0,1=230,2=0.000000
L 5.5719499 2.2495 5.58805 2.2495 1 P 0 ;0,1=230,2=0.000000
L 5.60371644 2.26241575 5.6063999 2.26603356 1 P 0 ;0,1=230,2=0.000000
L 5.6063999 2.26603356 5.6087001 2.2680998 1 P 0 ;0,1=230,2=0.000000
L 5.6087001 2.2680998 5.61176683 2.26913287 1 P 0 ;0,1=230,2=0.000000
L 5.61176683 2.26913287 5.6144503 2.2680998 1 P 0 ;0,1=230,2=0.000000
L 5.6144503 2.2680998 5.61636654 2.26603356 1 P 0 ;0,1=230,2=0.000000
L 5.61636654 2.26603356 5.6179002 2.26293327 1 P 0 ;0,1=230,2=0.000000
L 5.6179002 2.26293327 5.61828346 2.25931644 1 P 0 ;0,1=230,2=0.000000
L 5.61828346 2.25931644 5.6179002 2.25621614 1 P 0 ;0,1=230,2=0.000000
L 5.6179002 2.25621614 5.61636654 2.25311585 1 P 0 ;0,1=230,2=0.000000
L 5.61636654 2.25311585 5.61406634 2.25053307 1 P 0 ;0,1=230,2=0.000000
L 5.61406634 2.25053307 5.61138356 2.2495 1 P 0 ;0,1=230,2=0.000000
L 5.61138356 2.2495 5.60831683 2.25053307 1 P 0 ;0,1=230,2=0.000000
L 5.60831683 2.25053307 5.60563337 2.25363238 1 P 0 ;0,1=230,2=0.000000
L 5.60563337 2.25363238 5.6040997 2.25828327 1 P 0 ;0,1=230,2=0.000000
L 5.6040997 2.25828327 5.60371644 2.2634498 1 P 0 ;0,1=230,2=0.000000
L 5.60371644 2.2634498 5.60448287 2.27016594 1 P 0 ;0,1=230,2=0.000000
L 5.60448287 2.27016594 5.60563337 2.27378376 1 P 0 ;0,1=230,2=0.000000
L 5.60563337 2.27378376 5.60754961 2.2773997 1 P 0 ;0,1=230,2=0.000000
L 5.60754961 2.2773997 5.61023307 2.27998337 1 P 0 ;0,1=230,2=0.000000
L 5.61023307 2.27998337 5.61291654 2.2805 1 P 0 ;0,1=230,2=0.000000
L 5.61291654 2.2805 5.6156 2.27946683 1 P 0 ;0,1=230,2=0.000000
L 5.6156 2.27946683 5.61751703 2.27688307 1 P 0 ;0,1=230,2=0.000000
L 5.55680315 2.03594596 5.55866988 2.03886348 1 P 0 ;0,1=8,2=0.000000
L 5.55866988 2.03886348 5.56026998 2.04052982 1 P 0 ;0,1=8,2=0.000000
L 5.56026998 2.04052982 5.56240335 2.04136299 1 P 0 ;0,1=8,2=0.000000
L 5.56240335 2.04136299 5.56427018 2.04052982 1 P 0 ;0,1=8,2=0.000000
L 5.56427018 2.04052982 5.56560325 2.03886348 1 P 0 ;0,1=8,2=0.000000
L 5.56560325 2.03886348 5.56667008 2.03636329 1 P 0 ;0,1=8,2=0.000000
L 5.56667008 2.03636329 5.56693671 2.03344646 1 P 0 ;0,1=8,2=0.000000
L 5.56693671 2.03344646 5.56667008 2.03094626 1 P 0 ;0,1=8,2=0.000000
L 5.56667008 2.03094626 5.56560325 2.02844606 1 P 0 ;0,1=8,2=0.000000
L 5.56560325 2.02844606 5.56400305 2.02636309 1 P 0 ;0,1=8,2=0.000000
L 5.56400305 2.02636309 5.56213681 2.02553002 1 P 0 ;0,1=8,2=0.000000
L 5.56213681 2.02553002 5.56000344 2.02636309 1 P 0 ;0,1=8,2=0.000000
L 5.56000344 2.02636309 5.55813661 2.0288626 1 P 0 ;0,1=8,2=0.000000
L 5.55813661 2.0288626 5.55706978 2.03261329 1 P 0 ;0,1=8,2=0.000000
L 5.55706978 2.03261329 5.55680315 2.03677982 1 P 0 ;0,1=8,2=0.000000
L 5.55680315 2.03677982 5.55733632 2.04219616 1 P 0 ;0,1=8,2=0.000000
L 5.55733632 2.04219616 5.55813661 2.04511368 1 P 0 ;0,1=8,2=0.000000
L 5.55813661 2.04511368 5.55946969 2.04802972 1 P 0 ;0,1=8,2=0.000000
L 5.55946969 2.04802972 5.56133652 2.05011339 1 P 0 ;0,1=8,2=0.000000
L 5.56133652 2.05011339 5.56320325 2.05053002 1 P 0 ;0,1=8,2=0.000000
L 5.56320325 2.05053002 5.56506998 2.04969685 1 P 0 ;0,1=8,2=0.000000
L 5.56506998 2.04969685 5.56640354 2.04761319 1 P 0 ;0,1=8,2=0.000000
L 5.47913327 2.03324911 5.48073297 2.03116624 1 P 0 ;0,1=20,2=0.000000
L 5.48073297 2.03116624 5.4825997 2.02991654 1 P 0 ;0,1=20,2=0.000000
L 5.4825997 2.02991654 5.4849997 2.0295 1 P 0 ;0,1=20,2=0.000000
L 5.4849997 2.0295 5.4874002 2.03033307 1 P 0 ;0,1=20,2=0.000000
L 5.4874002 2.03033307 5.48926644 2.03199941 1 P 0 ;0,1=20,2=0.000000
L 5.48926644 2.03199941 5.4906 2.03491624 1 P 0 ;0,1=20,2=0.000000
L 5.4906 2.03491624 5.49086663 2.03824961 1 P 0 ;0,1=20,2=0.000000
L 5.49086663 2.03824961 5.49033337 2.04158297 1 P 0 ;0,1=20,2=0.000000
L 5.49033337 2.04158297 5.4889998 2.04366663 1 P 0 ;0,1=20,2=0.000000
L 5.4889998 2.04366663 5.48713307 2.04533297 1 P 0 ;0,1=20,2=0.000000
L 5.48713307 2.04533297 5.48526683 2.04574951 1 P 0 ;0,1=20,2=0.000000
L 5.48526683 2.04574951 5.4834 2.04533297 1 P 0 ;0,1=20,2=0.000000
L 5.4834 2.04533297 5.4810001 2.04366663 1 P 0 ;0,1=20,2=0.000000
L 5.4810001 2.04366663 5.4817999 2.0545 1 P 0 ;0,1=20,2=0.000000
L 5.4817999 2.0545 5.4889998 2.0545 1 P 0 ;0,1=20,2=0.000000
L 1.9257 0.76 1.9257 0.57 1 P 0 
L 1.8597 0.76 1.9257 0.76 1 P 0 
L 1.8597 0.7715 1.8597 0.76 1 P 0 
L 1.8597 0.57 1.8597 0.5585 1 P 0 
L 1.9257 0.57 1.8597 0.57 1 P 0 
L 1.6857 0.7715 1.8597 0.7715 1 P 0 
L 1.6857 0.76 1.6857 0.7715 1 P 0 
L 1.6197 0.76 1.6857 0.76 1 P 0 
L 1.8597 0.5585 1.6857 0.5585 1 P 0 
L 1.6197 0.57 1.6197 0.76 1 P 0 
L 1.6857 0.57 1.6197 0.57 1 P 0 
L 1.6857 0.5585 1.6857 0.57 1 P 0 
S P 0
OB 1.96531003937 0.59041003937 I
OC 1.96531003937 0.59041003937 1.95031003937 0.59041003937 Y
OE
SE
L 1.9496 0.7295 1.9496 0.7605 1 P 0 ;0,1=11,2=0.000000
L 1.9496 0.7605 1.93541624 0.73828327 1 P 0 ;0,1=11,2=0.000000
L 1.93541624 0.73828327 1.95458366 0.73828327 1 P 0 ;0,1=11,2=0.000000
L 1.77506663 0.8255 1.77506663 0.80328327 1 P 0 ;0,1=231,2=0.000000
L 1.77506663 0.80328327 1.7765997 0.79863238 1 P 0 ;0,1=231,2=0.000000
L 1.7765997 0.79863238 1.77966634 0.79553307 1 P 0 ;0,1=231,2=0.000000
L 1.77966634 0.79553307 1.78349961 0.7945 1 P 0 ;0,1=231,2=0.000000
L 1.78349961 0.7945 1.78733356 0.79553307 1 P 0 ;0,1=231,2=0.000000
L 1.78733356 0.79553307 1.7904002 0.79863238 1 P 0 ;0,1=231,2=0.000000
L 1.7904002 0.79863238 1.79193327 0.80328327 1 P 0 ;0,1=231,2=0.000000
L 1.79193327 0.80328327 1.79193327 0.8255 1 P 0 ;0,1=231,2=0.000000
L 1.80721644 0.82033346 1.80951663 0.82343278 1 P 0 ;0,1=231,2=0.000000
L 1.80951663 0.82343278 1.8122001 0.82498337 1 P 0 ;0,1=231,2=0.000000
L 1.8122001 0.82498337 1.81526683 0.8255 1 P 0 ;0,1=231,2=0.000000
L 1.81526683 0.8255 1.8191 0.82446683 1 P 0 ;0,1=231,2=0.000000
L 1.8191 0.82446683 1.82178346 0.82188307 1 P 0 ;0,1=231,2=0.000000
L 1.82178346 0.82188307 1.82255 0.81878376 1 P 0 ;0,1=231,2=0.000000
L 1.82255 0.81878376 1.82216673 0.81568258 1 P 0 ;0,1=231,2=0.000000
L 1.82216673 0.81568258 1.82063307 0.8130998 1 P 0 ;0,1=231,2=0.000000
L 1.82063307 0.8130998 1.81296663 0.80793327 1 P 0 ;0,1=231,2=0.000000
L 1.81296663 0.80793327 1.80951663 0.80431644 1 P 0 ;0,1=231,2=0.000000
L 1.80951663 0.80431644 1.80721644 0.79914892 1 P 0 ;0,1=231,2=0.000000
L 1.80721644 0.79914892 1.8064499 0.7945 1 P 0 ;0,1=231,2=0.000000
L 1.8064499 0.7945 1.82255 0.7945 1 P 0 ;0,1=231,2=0.000000
L 1.59656663 0.77414892 1.59886614 0.77156614 1 P 0 ;0,1=20,2=0.000000
L 1.59886614 0.77156614 1.60154961 0.77001654 1 P 0 ;0,1=20,2=0.000000
L 1.60154961 0.77001654 1.60499961 0.7695 1 P 0 ;0,1=20,2=0.000000
L 1.60499961 0.7695 1.6084503 0.77053307 1 P 0 ;0,1=20,2=0.000000
L 1.6084503 0.77053307 1.61113307 0.77259931 1 P 0 ;0,1=20,2=0.000000
L 1.61113307 0.77259931 1.61305 0.77621614 1 P 0 ;0,1=20,2=0.000000
L 1.61305 0.77621614 1.61343327 0.78034951 1 P 0 ;0,1=20,2=0.000000
L 1.61343327 0.78034951 1.61266673 0.78448287 1 P 0 ;0,1=20,2=0.000000
L 1.61266673 0.78448287 1.6107498 0.78706663 1 P 0 ;0,1=20,2=0.000000
L 1.6107498 0.78706663 1.60806634 0.78913287 1 P 0 ;0,1=20,2=0.000000
L 1.60806634 0.78913287 1.60538356 0.78964941 1 P 0 ;0,1=20,2=0.000000
L 1.60538356 0.78964941 1.6027001 0.78913287 1 P 0 ;0,1=20,2=0.000000
L 1.6027001 0.78913287 1.5992501 0.78706663 1 P 0 ;0,1=20,2=0.000000
L 1.5992501 0.78706663 1.6003999 0.8005 1 P 0 ;0,1=20,2=0.000000
L 1.6003999 0.8005 1.6107498 0.8005 1 P 0 ;0,1=20,2=0.000000
L 1.60069961 0.574 1.60338307 0.57451654 1 P 0 ;0,1=16,2=0.000000
L 1.60338307 0.57451654 1.6064498 0.57606614 1 P 0 ;0,1=16,2=0.000000
L 1.6064498 0.57606614 1.60836673 0.57864892 1 P 0 ;0,1=16,2=0.000000
L 1.60836673 0.57864892 1.60913327 0.58226673 1 P 0 ;0,1=16,2=0.000000
L 1.60913327 0.58226673 1.60836673 0.58588268 1 P 0 ;0,1=16,2=0.000000
L 1.60836673 0.58588268 1.60606654 0.58898287 1 P 0 ;0,1=16,2=0.000000
L 1.60606654 0.58898287 1.60261654 0.59053356 1 P 0 ;0,1=16,2=0.000000
L 1.60261654 0.59053356 1.59878337 0.59053356 1 P 0 ;0,1=16,2=0.000000
L 1.59878337 0.59053356 1.59648317 0.59156663 1 P 0 ;0,1=16,2=0.000000
L 1.59648317 0.59156663 1.59456614 0.59414941 1 P 0 ;0,1=16,2=0.000000
L 1.59456614 0.59414941 1.5937997 0.59776624 1 P 0 ;0,1=16,2=0.000000
L 1.5937997 0.59776624 1.5949501 0.60138307 1 P 0 ;0,1=16,2=0.000000
L 1.5949501 0.60138307 1.59763287 0.60396683 1 P 0 ;0,1=16,2=0.000000
L 1.59763287 0.60396683 1.60069961 0.605 1 P 0 ;0,1=16,2=0.000000
L 1.60069961 0.605 1.60376634 0.60396683 1 P 0 ;0,1=16,2=0.000000
L 1.60376634 0.60396683 1.6064498 0.60138307 1 P 0 ;0,1=16,2=0.000000
L 1.6064498 0.60138307 1.6076002 0.59776624 1 P 0 ;0,1=16,2=0.000000
L 1.6076002 0.59776624 1.60683307 0.59414941 1 P 0 ;0,1=16,2=0.000000
L 1.60683307 0.59414941 1.60491673 0.59156663 1 P 0 ;0,1=16,2=0.000000
L 1.60491673 0.59156663 1.60261654 0.59053356 1 P 0 ;0,1=16,2=0.000000
L 1.60261654 0.59053356 1.59878337 0.59053356 1 P 0 ;0,1=16,2=0.000000
L 1.59878337 0.59053356 1.59533337 0.58898287 1 P 0 ;0,1=16,2=0.000000
L 1.59533337 0.58898287 1.59303317 0.58588268 1 P 0 ;0,1=16,2=0.000000
L 1.59303317 0.58588268 1.59226663 0.58226673 1 P 0 ;0,1=16,2=0.000000
L 1.59226663 0.58226673 1.59303317 0.57864892 1 P 0 ;0,1=16,2=0.000000
L 1.59303317 0.57864892 1.5949501 0.57606614 1 P 0 ;0,1=16,2=0.000000
L 1.5949501 0.57606614 1.59801683 0.57451654 1 P 0 ;0,1=16,2=0.000000
L 1.59801683 0.57451654 1.60069961 0.574 1 P 0 ;0,1=16,2=0.000000
L 2.13613002 4.12576004 2.13613002 3.82623996 1 P 0 
L 1.78586998 4.12576004 2.13613002 4.12576004 1 P 0 
L 1.78586998 3.82623996 1.78586998 4.12576004 1 P 0 
L 2.13613002 3.82623996 1.78586998 3.82623996 1 P 0 
L 2.11271644 3.81033346 2.11501663 3.81343278 1 P 0 ;0,1=4,2=0.000000
L 2.11501663 3.81343278 2.1177001 3.81498337 1 P 0 ;0,1=4,2=0.000000
L 2.1177001 3.81498337 2.12076683 3.8155 1 P 0 ;0,1=4,2=0.000000
L 2.12076683 3.8155 2.1246 3.81446683 1 P 0 ;0,1=4,2=0.000000
L 2.1246 3.81446683 2.12728346 3.81188307 1 P 0 ;0,1=4,2=0.000000
L 2.12728346 3.81188307 2.12805 3.80878376 1 P 0 ;0,1=4,2=0.000000
L 2.12805 3.80878376 2.12766673 3.80568258 1 P 0 ;0,1=4,2=0.000000
L 2.12766673 3.80568258 2.12613307 3.8030998 1 P 0 ;0,1=4,2=0.000000
L 2.12613307 3.8030998 2.11846663 3.79793327 1 P 0 ;0,1=4,2=0.000000
L 2.11846663 3.79793327 2.11501663 3.79431644 1 P 0 ;0,1=4,2=0.000000
L 2.11501663 3.79431644 2.11271644 3.78914892 1 P 0 ;0,1=4,2=0.000000
L 2.11271644 3.78914892 2.1119499 3.7845 1 P 0 ;0,1=4,2=0.000000
L 2.1119499 3.7845 2.12805 3.7845 1 P 0 ;0,1=4,2=0.000000
L 1.94183317 3.8105 1.94183317 3.7795 1 P 0 ;0,1=232,2=0.000000
L 1.94183317 3.7795 1.95716673 3.7795 1 P 0 ;0,1=232,2=0.000000
L 1.98049961 3.7795 1.98049961 3.8105 1 P 0 ;0,1=232,2=0.000000
L 1.98049961 3.8105 1.9758999 3.8043003 1 P 0 ;0,1=232,2=0.000000
L 1.9758999 3.7795 1.98509931 3.7795 1 P 0 ;0,1=232,2=0.000000
L 1.81499961 3.7845 1.81499961 3.8155 1 P 0 ;0,1=2,2=0.000000
L 1.81499961 3.8155 1.8103999 3.8093003 1 P 0 ;0,1=2,2=0.000000
L 1.8103999 3.7845 1.81959931 3.7845 1 P 0 ;0,1=2,2=0.000000
L 3.19976004 4.04013002 3.19976004 3.68986998 1 P 0 
L 2.90023996 4.04013002 3.19976004 4.04013002 1 P 0 
L 3.19976004 3.68986998 2.90023996 3.68986998 1 P 0 
L 2.90023996 3.68986998 2.90023996 4.04013002 1 P 0 
L 3.04999961 4.0645 3.04999961 4.0955 1 P 0 ;0,1=2,2=0.000000
L 3.04999961 4.0955 3.0453999 4.0893003 1 P 0 ;0,1=2,2=0.000000
L 3.0453999 4.0645 3.05459931 4.0645 1 P 0 ;0,1=2,2=0.000000
L 3.05271644 3.66033346 3.05501663 3.66343278 1 P 0 ;0,1=4,2=0.000000
L 3.05501663 3.66343278 3.0577001 3.66498337 1 P 0 ;0,1=4,2=0.000000
L 3.0577001 3.66498337 3.06076683 3.6655 1 P 0 ;0,1=4,2=0.000000
L 3.06076683 3.6655 3.0646 3.66446683 1 P 0 ;0,1=4,2=0.000000
L 3.0646 3.66446683 3.06728346 3.66188307 1 P 0 ;0,1=4,2=0.000000
L 3.06728346 3.66188307 3.06805 3.65878376 1 P 0 ;0,1=4,2=0.000000
L 3.06805 3.65878376 3.06766673 3.65568258 1 P 0 ;0,1=4,2=0.000000
L 3.06766673 3.65568258 3.06613307 3.6530998 1 P 0 ;0,1=4,2=0.000000
L 3.06613307 3.6530998 3.05846663 3.64793327 1 P 0 ;0,1=4,2=0.000000
L 3.05846663 3.64793327 3.05501663 3.64431644 1 P 0 ;0,1=4,2=0.000000
L 3.05501663 3.64431644 3.05271644 3.63914892 1 P 0 ;0,1=4,2=0.000000
L 3.05271644 3.63914892 3.0519499 3.6345 1 P 0 ;0,1=4,2=0.000000
L 3.0519499 3.6345 3.06805 3.6345 1 P 0 ;0,1=4,2=0.000000
L 2.8345 3.83683317 2.8655 3.83683317 1 P 0 ;0,1=233,2=270.000000
L 2.8655 3.83683317 2.8655 3.85216673 1 P 0 ;0,1=233,2=270.000000
L 2.83966654 3.86821644 2.83656722 3.87051663 1 P 0 ;0,1=233,2=270.000000
L 2.83656722 3.87051663 2.83501663 3.8732001 1 P 0 ;0,1=233,2=270.000000
L 2.83501663 3.8732001 2.8345 3.87626683 1 P 0 ;0,1=233,2=270.000000
L 2.8345 3.87626683 2.83553317 3.8801 1 P 0 ;0,1=233,2=270.000000
L 2.83553317 3.8801 2.83811693 3.88278346 1 P 0 ;0,1=233,2=270.000000
L 2.83811693 3.88278346 2.84121624 3.88355 1 P 0 ;0,1=233,2=270.000000
L 2.84121624 3.88355 2.84431742 3.88316673 1 P 0 ;0,1=233,2=270.000000
L 2.84431742 3.88316673 2.8469002 3.88163307 1 P 0 ;0,1=233,2=270.000000
L 2.8469002 3.88163307 2.85206673 3.87396663 1 P 0 ;0,1=233,2=270.000000
L 2.85206673 3.87396663 2.85568356 3.87051663 1 P 0 ;0,1=233,2=270.000000
L 2.85568356 3.87051663 2.86085108 3.86821644 1 P 0 ;0,1=233,2=270.000000
L 2.86085108 3.86821644 2.8655 3.8674499 1 P 0 ;0,1=233,2=270.000000
L 2.8655 3.8674499 2.8655 3.88355 1 P 0 ;0,1=233,2=270.000000
L 2.205 3.245 2.1924 3.245 1 P 0 
L 2.1924 3.245 2.1924 3.3055 1 P 0 
L 2.1924 3.3055 2.0776 3.3055 1 P 0 
L 2.0776 3.3055 2.0776 3.245 1 P 0 
L 2.1924 3.105 2.205 3.105 1 P 0 
L 2.205 3.105 2.205 3.245 1 P 0 
L 2.0776 3.105 2.0776 3.0445 1 P 0 
L 2.0776 3.0445 2.1924 3.0445 1 P 0 
L 2.1924 3.0445 2.1924 3.105 1 P 0 
L 2.0776 3.245 2.065 3.245 1 P 0 
L 2.065 3.245 2.065 3.105 1 P 0 
L 2.065 3.105 2.0776 3.105 1 P 0 
S P 0
OB 2.189030019685 3.321869980315 I
OC 2.189030019685 3.321869980315 2.174030019685 3.321869980315 Y
OE
SE
L 2.2245 3.11556663 2.24671673 3.11556663 1 P 0 ;0,1=234,2=270.000000
L 2.24671673 3.11556663 2.25136762 3.1170997 1 P 0 ;0,1=234,2=270.000000
L 2.25136762 3.1170997 2.25446693 3.12016634 1 P 0 ;0,1=234,2=270.000000
L 2.25446693 3.12016634 2.2555 3.12399961 1 P 0 ;0,1=234,2=270.000000
L 2.2555 3.12399961 2.25446693 3.12783356 1 P 0 ;0,1=234,2=270.000000
L 2.25446693 3.12783356 2.25136762 3.1309002 1 P 0 ;0,1=234,2=270.000000
L 2.25136762 3.1309002 2.24671673 3.13243327 1 P 0 ;0,1=234,2=270.000000
L 2.24671673 3.13243327 2.2245 3.13243327 1 P 0 ;0,1=234,2=270.000000
L 2.24930039 3.14656663 2.25291722 3.14886614 1 P 0 ;0,1=234,2=270.000000
L 2.25291722 3.14886614 2.25498346 3.15193287 1 P 0 ;0,1=234,2=270.000000
L 2.25498346 3.15193287 2.2555 3.15538356 1 P 0 ;0,1=234,2=270.000000
L 2.2555 3.15538356 2.25498346 3.1584503 1 P 0 ;0,1=234,2=270.000000
L 2.25498346 3.1584503 2.25240069 3.16151703 1 P 0 ;0,1=234,2=270.000000
L 2.25240069 3.16151703 2.24930039 3.16343327 1 P 0 ;0,1=234,2=270.000000
L 2.24930039 3.16343327 2.2462001 3.16381654 1 P 0 ;0,1=234,2=270.000000
L 2.2462001 3.16381654 2.24258425 3.16305 1 P 0 ;0,1=234,2=270.000000
L 2.24258425 3.16305 2.24000049 3.16036654 1 P 0 ;0,1=234,2=270.000000
L 2.24000049 3.16036654 2.23896644 3.15768307 1 P 0 ;0,1=234,2=270.000000
L 2.23896644 3.15768307 2.23896644 3.15423307 1 P 0 ;0,1=234,2=270.000000
L 2.23896644 3.15768307 2.23741683 3.15998327 1 P 0 ;0,1=234,2=270.000000
L 2.23741683 3.15998327 2.23483406 3.1619002 1 P 0 ;0,1=234,2=270.000000
L 2.23483406 3.1619002 2.23173376 3.16266673 1 P 0 ;0,1=234,2=270.000000
L 2.23173376 3.16266673 2.22863346 3.1619002 1 P 0 ;0,1=234,2=270.000000
L 2.22863346 3.1619002 2.22605069 3.15998327 1 P 0 ;0,1=234,2=270.000000
L 2.22605069 3.15998327 2.2245 3.15653327 1 P 0 ;0,1=234,2=270.000000
L 2.2245 3.15653327 2.22501663 3.15308337 1 P 0 ;0,1=234,2=270.000000
L 2.22501663 3.15308337 2.22708376 3.14963337 1 P 0 ;0,1=234,2=270.000000
L 2.25085108 3.17756663 2.25343386 3.17986614 1 P 0 ;0,1=234,2=270.000000
L 2.25343386 3.17986614 2.25498346 3.18254961 1 P 0 ;0,1=234,2=270.000000
L 2.25498346 3.18254961 2.2555 3.18599961 1 P 0 ;0,1=234,2=270.000000
L 2.2555 3.18599961 2.25446693 3.1894503 1 P 0 ;0,1=234,2=270.000000
L 2.25446693 3.1894503 2.25240069 3.19213307 1 P 0 ;0,1=234,2=270.000000
L 2.25240069 3.19213307 2.24878386 3.19405 1 P 0 ;0,1=234,2=270.000000
L 2.24878386 3.19405 2.24465049 3.19443327 1 P 0 ;0,1=234,2=270.000000
L 2.24465049 3.19443327 2.24051713 3.19366673 1 P 0 ;0,1=234,2=270.000000
L 2.24051713 3.19366673 2.23793337 3.1917498 1 P 0 ;0,1=234,2=270.000000
L 2.23793337 3.1917498 2.23586713 3.18906634 1 P 0 ;0,1=234,2=270.000000
L 2.23586713 3.18906634 2.23535059 3.18638356 1 P 0 ;0,1=234,2=270.000000
L 2.23535059 3.18638356 2.23586713 3.1837001 1 P 0 ;0,1=234,2=270.000000
L 2.23586713 3.1837001 2.23793337 3.1802501 1 P 0 ;0,1=234,2=270.000000
L 2.23793337 3.1802501 2.2245 3.1813999 1 P 0 ;0,1=234,2=270.000000
L 2.2245 3.1813999 2.2245 3.1917498 1 P 0 ;0,1=234,2=270.000000
L 2.2299997 3.0295 2.23186644 3.02991654 1 P 0 ;0,1=16,2=0.000000
L 2.23186644 3.02991654 2.2339998 3.03116624 1 P 0 ;0,1=16,2=0.000000
L 2.2339998 3.03116624 2.23533337 3.03324911 1 P 0 ;0,1=16,2=0.000000
L 2.23533337 3.03324911 2.23586663 3.03616673 1 P 0 ;0,1=16,2=0.000000
L 2.23586663 3.03616673 2.23533337 3.03908278 1 P 0 ;0,1=16,2=0.000000
L 2.23533337 3.03908278 2.23373327 3.04158297 1 P 0 ;0,1=16,2=0.000000
L 2.23373327 3.04158297 2.23133327 3.04283346 1 P 0 ;0,1=16,2=0.000000
L 2.23133327 3.04283346 2.22866663 3.04283346 1 P 0 ;0,1=16,2=0.000000
L 2.22866663 3.04283346 2.22706654 3.04366663 1 P 0 ;0,1=16,2=0.000000
L 2.22706654 3.04366663 2.22573297 3.04574951 1 P 0 ;0,1=16,2=0.000000
L 2.22573297 3.04574951 2.2251998 3.04866634 1 P 0 ;0,1=16,2=0.000000
L 2.2251998 3.04866634 2.2260001 3.05158317 1 P 0 ;0,1=16,2=0.000000
L 2.2260001 3.05158317 2.22786634 3.05366683 1 P 0 ;0,1=16,2=0.000000
L 2.22786634 3.05366683 2.2299997 3.0545 1 P 0 ;0,1=16,2=0.000000
L 2.2299997 3.0545 2.23213307 3.05366683 1 P 0 ;0,1=16,2=0.000000
L 2.23213307 3.05366683 2.2339998 3.05158317 1 P 0 ;0,1=16,2=0.000000
L 2.2339998 3.05158317 2.2348001 3.04866634 1 P 0 ;0,1=16,2=0.000000
L 2.2348001 3.04866634 2.23426644 3.04574951 1 P 0 ;0,1=16,2=0.000000
L 2.23426644 3.04574951 2.23293337 3.04366663 1 P 0 ;0,1=16,2=0.000000
L 2.23293337 3.04366663 2.23133327 3.04283346 1 P 0 ;0,1=16,2=0.000000
L 2.23133327 3.04283346 2.22866663 3.04283346 1 P 0 ;0,1=16,2=0.000000
L 2.22866663 3.04283346 2.22626663 3.04158297 1 P 0 ;0,1=16,2=0.000000
L 2.22626663 3.04158297 2.22466654 3.03908278 1 P 0 ;0,1=16,2=0.000000
L 2.22466654 3.03908278 2.22413327 3.03616673 1 P 0 ;0,1=16,2=0.000000
L 2.22413327 3.03616673 2.22466654 3.03324911 1 P 0 ;0,1=16,2=0.000000
L 2.22466654 3.03324911 2.2260001 3.03116624 1 P 0 ;0,1=16,2=0.000000
L 2.2260001 3.03116624 2.22813346 3.02991654 1 P 0 ;0,1=16,2=0.000000
L 2.22813346 3.02991654 2.2299997 3.0295 1 P 0 ;0,1=16,2=0.000000
L 2.0682 3.3245 2.0682 3.3495 1 P 0 ;0,1=11,2=0.000000
L 2.0682 3.3495 2.05833297 3.33158327 1 P 0 ;0,1=11,2=0.000000
L 2.05833297 3.33158327 2.07166693 3.33158327 1 P 0 ;0,1=11,2=0.000000
L 2.05413327 3.01324911 2.05573297 3.01116624 1 P 0 ;0,1=20,2=0.000000
L 2.05573297 3.01116624 2.0575997 3.00991654 1 P 0 ;0,1=20,2=0.000000
L 2.0575997 3.00991654 2.0599997 3.0095 1 P 0 ;0,1=20,2=0.000000
L 2.0599997 3.0095 2.0624002 3.01033307 1 P 0 ;0,1=20,2=0.000000
L 2.0624002 3.01033307 2.06426644 3.01199941 1 P 0 ;0,1=20,2=0.000000
L 2.06426644 3.01199941 2.0656 3.01491624 1 P 0 ;0,1=20,2=0.000000
L 2.0656 3.01491624 2.06586663 3.01824961 1 P 0 ;0,1=20,2=0.000000
L 2.06586663 3.01824961 2.06533337 3.02158297 1 P 0 ;0,1=20,2=0.000000
L 2.06533337 3.02158297 2.0639998 3.02366663 1 P 0 ;0,1=20,2=0.000000
L 2.0639998 3.02366663 2.06213307 3.02533297 1 P 0 ;0,1=20,2=0.000000
L 2.06213307 3.02533297 2.06026683 3.02574951 1 P 0 ;0,1=20,2=0.000000
L 2.06026683 3.02574951 2.0584 3.02533297 1 P 0 ;0,1=20,2=0.000000
L 2.0584 3.02533297 2.0560001 3.02366663 1 P 0 ;0,1=20,2=0.000000
L 2.0560001 3.02366663 2.0567999 3.0345 1 P 0 ;0,1=20,2=0.000000
L 2.0567999 3.0345 2.0639998 3.0345 1 P 0 ;0,1=20,2=0.000000
L 0.891 2.407 0.8784 2.407 1 P 0 
L 0.8784 2.407 0.8784 2.4675 1 P 0 
L 0.8784 2.2065 0.8784 2.267 1 P 0 
L 0.8784 2.267 0.891 2.267 1 P 0 
L 0.891 2.267 0.891 2.407 1 P 0 
L 0.7636 2.407 0.751 2.407 1 P 0 
L 0.8784 2.4675 0.7636 2.4675 1 P 0 
L 0.7636 2.4675 0.7636 2.407 1 P 0 
L 0.751 2.407 0.751 2.267 1 P 0 
L 0.751 2.267 0.7636 2.267 1 P 0 
L 0.7636 2.267 0.7636 2.2065 1 P 0 
L 0.7636 2.2065 0.8784 2.2065 1 P 0 
S P 0
OB 0.755 2.205 I
OC 0.755 2.205 0.74 2.205 Y
OE
SE
L 0.90413327 2.44624911 0.90573297 2.44416624 1 P 0 ;0,1=20,2=0.000000
L 0.90573297 2.44416624 0.9075997 2.44291654 1 P 0 ;0,1=20,2=0.000000
L 0.9075997 2.44291654 0.9099997 2.4425 1 P 0 ;0,1=20,2=0.000000
L 0.9099997 2.4425 0.9124002 2.44333307 1 P 0 ;0,1=20,2=0.000000
L 0.9124002 2.44333307 0.91426644 2.44499941 1 P 0 ;0,1=20,2=0.000000
L 0.91426644 2.44499941 0.9156 2.44791624 1 P 0 ;0,1=20,2=0.000000
L 0.9156 2.44791624 0.91586663 2.45124961 1 P 0 ;0,1=20,2=0.000000
L 0.91586663 2.45124961 0.91533337 2.45458297 1 P 0 ;0,1=20,2=0.000000
L 0.91533337 2.45458297 0.9139998 2.45666663 1 P 0 ;0,1=20,2=0.000000
L 0.9139998 2.45666663 0.91213307 2.45833297 1 P 0 ;0,1=20,2=0.000000
L 0.91213307 2.45833297 0.91026683 2.45874951 1 P 0 ;0,1=20,2=0.000000
L 0.91026683 2.45874951 0.9084 2.45833297 1 P 0 ;0,1=20,2=0.000000
L 0.9084 2.45833297 0.9060001 2.45666663 1 P 0 ;0,1=20,2=0.000000
L 0.9060001 2.45666663 0.9067999 2.4675 1 P 0 ;0,1=20,2=0.000000
L 0.9067999 2.4675 0.9139998 2.4675 1 P 0 ;0,1=20,2=0.000000
L 0.9082 2.2095 0.9082 2.2345 1 P 0 ;0,1=11,2=0.000000
L 0.9082 2.2345 0.89833297 2.21658327 1 P 0 ;0,1=11,2=0.000000
L 0.89833297 2.21658327 0.91166693 2.21658327 1 P 0 ;0,1=11,2=0.000000
L 0.9095 2.30056663 0.93171673 2.30056663 1 P 0 ;0,1=235,2=270.000000
L 0.93171673 2.30056663 0.93636762 2.3020997 1 P 0 ;0,1=235,2=270.000000
L 0.93636762 2.3020997 0.93946693 2.30516634 1 P 0 ;0,1=235,2=270.000000
L 0.93946693 2.30516634 0.9405 2.30899961 1 P 0 ;0,1=235,2=270.000000
L 0.9405 2.30899961 0.93946693 2.31283356 1 P 0 ;0,1=235,2=270.000000
L 0.93946693 2.31283356 0.93636762 2.3159002 1 P 0 ;0,1=235,2=270.000000
L 0.93636762 2.3159002 0.93171673 2.31743327 1 P 0 ;0,1=235,2=270.000000
L 0.93171673 2.31743327 0.9095 2.31743327 1 P 0 ;0,1=235,2=270.000000
L 0.93430039 2.33156663 0.93791722 2.33386614 1 P 0 ;0,1=235,2=270.000000
L 0.93791722 2.33386614 0.93998346 2.33693287 1 P 0 ;0,1=235,2=270.000000
L 0.93998346 2.33693287 0.9405 2.34038356 1 P 0 ;0,1=235,2=270.000000
L 0.9405 2.34038356 0.93998346 2.3434503 1 P 0 ;0,1=235,2=270.000000
L 0.93998346 2.3434503 0.93740069 2.34651703 1 P 0 ;0,1=235,2=270.000000
L 0.93740069 2.34651703 0.93430039 2.34843327 1 P 0 ;0,1=235,2=270.000000
L 0.93430039 2.34843327 0.9312001 2.34881654 1 P 0 ;0,1=235,2=270.000000
L 0.9312001 2.34881654 0.92758425 2.34805 1 P 0 ;0,1=235,2=270.000000
L 0.92758425 2.34805 0.92500049 2.34536654 1 P 0 ;0,1=235,2=270.000000
L 0.92500049 2.34536654 0.92396644 2.34268307 1 P 0 ;0,1=235,2=270.000000
L 0.92396644 2.34268307 0.92396644 2.33923307 1 P 0 ;0,1=235,2=270.000000
L 0.92396644 2.34268307 0.92241683 2.34498327 1 P 0 ;0,1=235,2=270.000000
L 0.92241683 2.34498327 0.91983406 2.3469002 1 P 0 ;0,1=235,2=270.000000
L 0.91983406 2.3469002 0.91673376 2.34766673 1 P 0 ;0,1=235,2=270.000000
L 0.91673376 2.34766673 0.91363346 2.3469002 1 P 0 ;0,1=235,2=270.000000
L 0.91363346 2.3469002 0.91105069 2.34498327 1 P 0 ;0,1=235,2=270.000000
L 0.91105069 2.34498327 0.9095 2.34153327 1 P 0 ;0,1=235,2=270.000000
L 0.9095 2.34153327 0.91001663 2.33808337 1 P 0 ;0,1=235,2=270.000000
L 0.91001663 2.33808337 0.91208376 2.33463337 1 P 0 ;0,1=235,2=270.000000
L 0.91466654 2.36371644 0.91156722 2.36601663 1 P 0 ;0,1=235,2=270.000000
L 0.91156722 2.36601663 0.91001663 2.3687001 1 P 0 ;0,1=235,2=270.000000
L 0.91001663 2.3687001 0.9095 2.37176683 1 P 0 ;0,1=235,2=270.000000
L 0.9095 2.37176683 0.91053317 2.3756 1 P 0 ;0,1=235,2=270.000000
L 0.91053317 2.3756 0.91311693 2.37828346 1 P 0 ;0,1=235,2=270.000000
L 0.91311693 2.37828346 0.91621624 2.37905 1 P 0 ;0,1=235,2=270.000000
L 0.91621624 2.37905 0.91931742 2.37866673 1 P 0 ;0,1=235,2=270.000000
L 0.91931742 2.37866673 0.9219002 2.37713307 1 P 0 ;0,1=235,2=270.000000
L 0.9219002 2.37713307 0.92706673 2.36946663 1 P 0 ;0,1=235,2=270.000000
L 0.92706673 2.36946663 0.93068356 2.36601663 1 P 0 ;0,1=235,2=270.000000
L 0.93068356 2.36601663 0.93585108 2.36371644 1 P 0 ;0,1=235,2=270.000000
L 0.93585108 2.36371644 0.9405 2.3629499 1 P 0 ;0,1=235,2=270.000000
L 0.9405 2.3629499 0.9405 2.37905 1 P 0 ;0,1=235,2=270.000000
L 0.7399997 2.4725 0.74186644 2.47291654 1 P 0 ;0,1=16,2=0.000000
L 0.74186644 2.47291654 0.7439998 2.47416624 1 P 0 ;0,1=16,2=0.000000
L 0.7439998 2.47416624 0.74533337 2.47624911 1 P 0 ;0,1=16,2=0.000000
L 0.74533337 2.47624911 0.74586663 2.47916673 1 P 0 ;0,1=16,2=0.000000
L 0.74586663 2.47916673 0.74533337 2.48208278 1 P 0 ;0,1=16,2=0.000000
L 0.74533337 2.48208278 0.74373327 2.48458297 1 P 0 ;0,1=16,2=0.000000
L 0.74373327 2.48458297 0.74133327 2.48583346 1 P 0 ;0,1=16,2=0.000000
L 0.74133327 2.48583346 0.73866663 2.48583346 1 P 0 ;0,1=16,2=0.000000
L 0.73866663 2.48583346 0.73706654 2.48666663 1 P 0 ;0,1=16,2=0.000000
L 0.73706654 2.48666663 0.73573297 2.48874951 1 P 0 ;0,1=16,2=0.000000
L 0.73573297 2.48874951 0.7351998 2.49166634 1 P 0 ;0,1=16,2=0.000000
L 0.7351998 2.49166634 0.7360001 2.49458317 1 P 0 ;0,1=16,2=0.000000
L 0.7360001 2.49458317 0.73786634 2.49666683 1 P 0 ;0,1=16,2=0.000000
L 0.73786634 2.49666683 0.7399997 2.4975 1 P 0 ;0,1=16,2=0.000000
L 0.7399997 2.4975 0.74213307 2.49666683 1 P 0 ;0,1=16,2=0.000000
L 0.74213307 2.49666683 0.7439998 2.49458317 1 P 0 ;0,1=16,2=0.000000
L 0.7439998 2.49458317 0.7448001 2.49166634 1 P 0 ;0,1=16,2=0.000000
L 0.7448001 2.49166634 0.74426644 2.48874951 1 P 0 ;0,1=16,2=0.000000
L 0.74426644 2.48874951 0.74293337 2.48666663 1 P 0 ;0,1=16,2=0.000000
L 0.74293337 2.48666663 0.74133327 2.48583346 1 P 0 ;0,1=16,2=0.000000
L 0.74133327 2.48583346 0.73866663 2.48583346 1 P 0 ;0,1=16,2=0.000000
L 0.73866663 2.48583346 0.73626663 2.48458297 1 P 0 ;0,1=16,2=0.000000
L 0.73626663 2.48458297 0.73466654 2.48208278 1 P 0 ;0,1=16,2=0.000000
L 0.73466654 2.48208278 0.73413327 2.47916673 1 P 0 ;0,1=16,2=0.000000
L 0.73413327 2.47916673 0.73466654 2.47624911 1 P 0 ;0,1=16,2=0.000000
L 0.73466654 2.47624911 0.7360001 2.47416624 1 P 0 ;0,1=16,2=0.000000
L 0.7360001 2.47416624 0.73813346 2.47291654 1 P 0 ;0,1=16,2=0.000000
L 0.73813346 2.47291654 0.7399997 2.4725 1 P 0 ;0,1=16,2=0.000000
L 6.3055 0.9876 6.3055 1.1024 1 P 0 
L 6.245 1.1024 6.245 1.115 1 P 0 
L 6.245 1.115 6.105 1.115 1 P 0 
L 6.105 1.115 6.105 1.1024 1 P 0 
L 6.3055 1.1024 6.245 1.1024 1 P 0 
L 6.105 0.9876 6.105 0.975 1 P 0 
L 6.105 0.975 6.245 0.975 1 P 0 
L 6.245 0.975 6.245 0.9876 1 P 0 
L 6.245 0.9876 6.3055 0.9876 1 P 0 
L 6.105 1.1024 6.0445 1.1024 1 P 0 
L 6.0445 1.1024 6.0445 0.9876 1 P 0 
L 6.0445 0.9876 6.105 0.9876 1 P 0 
S P 0
OB 6.05 1.13 I
OC 6.05 1.13 6.035 1.13 Y
OE
SE
L 6.32999961 1.1145 6.33268307 1.11501654 1 P 0 ;0,1=16,2=0.000000
L 6.33268307 1.11501654 6.3357498 1.11656614 1 P 0 ;0,1=16,2=0.000000
L 6.3357498 1.11656614 6.33766673 1.11914892 1 P 0 ;0,1=16,2=0.000000
L 6.33766673 1.11914892 6.33843327 1.12276673 1 P 0 ;0,1=16,2=0.000000
L 6.33843327 1.12276673 6.33766673 1.12638268 1 P 0 ;0,1=16,2=0.000000
L 6.33766673 1.12638268 6.33536654 1.12948287 1 P 0 ;0,1=16,2=0.000000
L 6.33536654 1.12948287 6.33191654 1.13103356 1 P 0 ;0,1=16,2=0.000000
L 6.33191654 1.13103356 6.32808337 1.13103356 1 P 0 ;0,1=16,2=0.000000
L 6.32808337 1.13103356 6.32578317 1.13206663 1 P 0 ;0,1=16,2=0.000000
L 6.32578317 1.13206663 6.32386614 1.13464941 1 P 0 ;0,1=16,2=0.000000
L 6.32386614 1.13464941 6.3230997 1.13826624 1 P 0 ;0,1=16,2=0.000000
L 6.3230997 1.13826624 6.3242501 1.14188307 1 P 0 ;0,1=16,2=0.000000
L 6.3242501 1.14188307 6.32693287 1.14446683 1 P 0 ;0,1=16,2=0.000000
L 6.32693287 1.14446683 6.32999961 1.1455 1 P 0 ;0,1=16,2=0.000000
L 6.32999961 1.1455 6.33306634 1.14446683 1 P 0 ;0,1=16,2=0.000000
L 6.33306634 1.14446683 6.3357498 1.14188307 1 P 0 ;0,1=16,2=0.000000
L 6.3357498 1.14188307 6.3369002 1.13826624 1 P 0 ;0,1=16,2=0.000000
L 6.3369002 1.13826624 6.33613307 1.13464941 1 P 0 ;0,1=16,2=0.000000
L 6.33613307 1.13464941 6.33421673 1.13206663 1 P 0 ;0,1=16,2=0.000000
L 6.33421673 1.13206663 6.33191654 1.13103356 1 P 0 ;0,1=16,2=0.000000
L 6.33191654 1.13103356 6.32808337 1.13103356 1 P 0 ;0,1=16,2=0.000000
L 6.32808337 1.13103356 6.32463337 1.12948287 1 P 0 ;0,1=16,2=0.000000
L 6.32463337 1.12948287 6.32233317 1.12638268 1 P 0 ;0,1=16,2=0.000000
L 6.32233317 1.12638268 6.32156663 1.12276673 1 P 0 ;0,1=16,2=0.000000
L 6.32156663 1.12276673 6.32233317 1.11914892 1 P 0 ;0,1=16,2=0.000000
L 6.32233317 1.11914892 6.3242501 1.11656614 1 P 0 ;0,1=16,2=0.000000
L 6.3242501 1.11656614 6.32731683 1.11501654 1 P 0 ;0,1=16,2=0.000000
L 6.32731683 1.11501654 6.32999961 1.1145 1 P 0 ;0,1=16,2=0.000000
L 6.30656663 0.92914892 6.30886614 0.92656614 1 P 0 ;0,1=20,2=0.000000
L 6.30886614 0.92656614 6.31154961 0.92501654 1 P 0 ;0,1=20,2=0.000000
L 6.31154961 0.92501654 6.31499961 0.9245 1 P 0 ;0,1=20,2=0.000000
L 6.31499961 0.9245 6.3184503 0.92553307 1 P 0 ;0,1=20,2=0.000000
L 6.3184503 0.92553307 6.32113307 0.92759931 1 P 0 ;0,1=20,2=0.000000
L 6.32113307 0.92759931 6.32305 0.93121614 1 P 0 ;0,1=20,2=0.000000
L 6.32305 0.93121614 6.32343327 0.93534951 1 P 0 ;0,1=20,2=0.000000
L 6.32343327 0.93534951 6.32266673 0.93948287 1 P 0 ;0,1=20,2=0.000000
L 6.32266673 0.93948287 6.3207498 0.94206663 1 P 0 ;0,1=20,2=0.000000
L 6.3207498 0.94206663 6.31806634 0.94413287 1 P 0 ;0,1=20,2=0.000000
L 6.31806634 0.94413287 6.31538356 0.94464941 1 P 0 ;0,1=20,2=0.000000
L 6.31538356 0.94464941 6.3127001 0.94413287 1 P 0 ;0,1=20,2=0.000000
L 6.3127001 0.94413287 6.3092501 0.94206663 1 P 0 ;0,1=20,2=0.000000
L 6.3092501 0.94206663 6.3103999 0.9555 1 P 0 ;0,1=20,2=0.000000
L 6.3103999 0.9555 6.3207498 0.9555 1 P 0 ;0,1=20,2=0.000000
L 6.13056663 0.9605 6.13056663 0.93828327 1 P 0 ;0,1=236,2=0.000000
L 6.13056663 0.93828327 6.1320997 0.93363238 1 P 0 ;0,1=236,2=0.000000
L 6.1320997 0.93363238 6.13516634 0.93053307 1 P 0 ;0,1=236,2=0.000000
L 6.13516634 0.93053307 6.13899961 0.9295 1 P 0 ;0,1=236,2=0.000000
L 6.13899961 0.9295 6.14283356 0.93053307 1 P 0 ;0,1=236,2=0.000000
L 6.14283356 0.93053307 6.1459002 0.93363238 1 P 0 ;0,1=236,2=0.000000
L 6.1459002 0.93363238 6.14743327 0.93828327 1 P 0 ;0,1=236,2=0.000000
L 6.14743327 0.93828327 6.14743327 0.9605 1 P 0 ;0,1=236,2=0.000000
L 6.16156663 0.93569961 6.16386614 0.93208278 1 P 0 ;0,1=236,2=0.000000
L 6.16386614 0.93208278 6.16693287 0.93001654 1 P 0 ;0,1=236,2=0.000000
L 6.16693287 0.93001654 6.17038356 0.9295 1 P 0 ;0,1=236,2=0.000000
L 6.17038356 0.9295 6.1734503 0.93001654 1 P 0 ;0,1=236,2=0.000000
L 6.1734503 0.93001654 6.17651703 0.93259931 1 P 0 ;0,1=236,2=0.000000
L 6.17651703 0.93259931 6.17843327 0.93569961 1 P 0 ;0,1=236,2=0.000000
L 6.17843327 0.93569961 6.17881654 0.9387999 1 P 0 ;0,1=236,2=0.000000
L 6.17881654 0.9387999 6.17805 0.94241575 1 P 0 ;0,1=236,2=0.000000
L 6.17805 0.94241575 6.17536654 0.94499951 1 P 0 ;0,1=236,2=0.000000
L 6.17536654 0.94499951 6.17268307 0.94603356 1 P 0 ;0,1=236,2=0.000000
L 6.17268307 0.94603356 6.16923307 0.94603356 1 P 0 ;0,1=236,2=0.000000
L 6.17268307 0.94603356 6.17498327 0.94758317 1 P 0 ;0,1=236,2=0.000000
L 6.17498327 0.94758317 6.1769002 0.95016594 1 P 0 ;0,1=236,2=0.000000
L 6.1769002 0.95016594 6.17766673 0.95326624 1 P 0 ;0,1=236,2=0.000000
L 6.17766673 0.95326624 6.1769002 0.95636654 1 P 0 ;0,1=236,2=0.000000
L 6.1769002 0.95636654 6.17498327 0.95894931 1 P 0 ;0,1=236,2=0.000000
L 6.17498327 0.95894931 6.17153327 0.9605 1 P 0 ;0,1=236,2=0.000000
L 6.17153327 0.9605 6.16808337 0.95998337 1 P 0 ;0,1=236,2=0.000000
L 6.16808337 0.95998337 6.16463337 0.95791624 1 P 0 ;0,1=236,2=0.000000
L 6.19371644 0.94241575 6.1963999 0.94603356 1 P 0 ;0,1=236,2=0.000000
L 6.1963999 0.94603356 6.1987001 0.9480998 1 P 0 ;0,1=236,2=0.000000
L 6.1987001 0.9480998 6.20176683 0.94913287 1 P 0 ;0,1=236,2=0.000000
L 6.20176683 0.94913287 6.2044503 0.9480998 1 P 0 ;0,1=236,2=0.000000
L 6.2044503 0.9480998 6.20636654 0.94603356 1 P 0 ;0,1=236,2=0.000000
L 6.20636654 0.94603356 6.2079002 0.94293327 1 P 0 ;0,1=236,2=0.000000
L 6.2079002 0.94293327 6.20828346 0.93931644 1 P 0 ;0,1=236,2=0.000000
L 6.20828346 0.93931644 6.2079002 0.93621614 1 P 0 ;0,1=236,2=0.000000
L 6.2079002 0.93621614 6.20636654 0.93311585 1 P 0 ;0,1=236,2=0.000000
L 6.20636654 0.93311585 6.20406634 0.93053307 1 P 0 ;0,1=236,2=0.000000
L 6.20406634 0.93053307 6.20138356 0.9295 1 P 0 ;0,1=236,2=0.000000
L 6.20138356 0.9295 6.19831683 0.93053307 1 P 0 ;0,1=236,2=0.000000
L 6.19831683 0.93053307 6.19563337 0.93363238 1 P 0 ;0,1=236,2=0.000000
L 6.19563337 0.93363238 6.1940997 0.93828327 1 P 0 ;0,1=236,2=0.000000
L 6.1940997 0.93828327 6.19371644 0.9434498 1 P 0 ;0,1=236,2=0.000000
L 6.19371644 0.9434498 6.19448287 0.95016594 1 P 0 ;0,1=236,2=0.000000
L 6.19448287 0.95016594 6.19563337 0.95378376 1 P 0 ;0,1=236,2=0.000000
L 6.19563337 0.95378376 6.19754961 0.9573997 1 P 0 ;0,1=236,2=0.000000
L 6.19754961 0.9573997 6.20023307 0.95998337 1 P 0 ;0,1=236,2=0.000000
L 6.20023307 0.95998337 6.20291654 0.9605 1 P 0 ;0,1=236,2=0.000000
L 6.20291654 0.9605 6.2056 0.95946683 1 P 0 ;0,1=236,2=0.000000
L 6.2056 0.95946683 6.20751703 0.95688307 1 P 0 ;0,1=236,2=0.000000
L 5.62621004 3.86656004 5.62621004 3.60743996 1 P 0 
L 5.44578996 3.86656004 5.62621004 3.86656004 1 P 0 
L 5.62621004 3.60743996 5.44578996 3.60743996 1 P 0 
L 5.44578996 3.60743996 5.44578996 3.86656004 1 P 0 
S P 0
OB 5.67501003937 3.64 I
OC 5.67501003937 3.64 5.655003641732 3.63999980315 Y
OE
SE
L 5.64546634 3.81541604 5.64733317 3.81333307 1 P 0 ;0,1=14,2=0.000000
L 5.64733317 3.81333307 5.64946654 3.8125 1 P 0 ;0,1=14,2=0.000000
L 5.64946654 3.8125 5.6515999 3.81333307 1 P 0 ;0,1=14,2=0.000000
L 5.6515999 3.81333307 5.65346663 3.81583258 1 P 0 ;0,1=14,2=0.000000
L 5.65346663 3.81583258 5.6548001 3.81958327 1 P 0 ;0,1=14,2=0.000000
L 5.6548001 3.81958327 5.65533337 3.82333327 1 P 0 ;0,1=14,2=0.000000
L 5.65533337 3.82333327 5.65533337 3.82791634 1 P 0 ;0,1=14,2=0.000000
L 5.65533337 3.82791634 5.6548001 3.83166634 1 P 0 ;0,1=14,2=0.000000
L 5.6548001 3.83166634 5.65346663 3.8349997 1 P 0 ;0,1=14,2=0.000000
L 5.65346663 3.8349997 5.65186644 3.83666683 1 P 0 ;0,1=14,2=0.000000
L 5.65186644 3.83666683 5.6499997 3.8375 1 P 0 ;0,1=14,2=0.000000
L 5.6499997 3.8375 5.64786634 3.83666683 1 P 0 ;0,1=14,2=0.000000
L 5.64786634 3.83666683 5.64626663 3.8349997 1 P 0 ;0,1=14,2=0.000000
L 5.64626663 3.8349997 5.6451998 3.8325003 1 P 0 ;0,1=14,2=0.000000
L 5.6451998 3.8325003 5.64466654 3.82916614 1 P 0 ;0,1=14,2=0.000000
L 5.64466654 3.82916614 5.6451998 3.8262501 1 P 0 ;0,1=14,2=0.000000
L 5.6451998 3.8262501 5.64653327 3.82333327 1 P 0 ;0,1=14,2=0.000000
L 5.64653327 3.82333327 5.64813346 3.82166614 1 P 0 ;0,1=14,2=0.000000
L 5.64813346 3.82166614 5.6499997 3.82124961 1 P 0 ;0,1=14,2=0.000000
L 5.6499997 3.82124961 5.65213307 3.82208278 1 P 0 ;0,1=14,2=0.000000
L 5.65213307 3.82208278 5.65373327 3.82416644 1 P 0 ;0,1=14,2=0.000000
L 5.65373327 3.82416644 5.65533337 3.82791634 1 P 0 ;0,1=14,2=0.000000
L 5.4089997 3.8125 5.4089997 3.8375 1 P 0 ;0,1=6,2=0.000000
L 5.4089997 3.8375 5.4057999 3.8325003 1 P 0 ;0,1=6,2=0.000000
L 5.4057999 3.8125 5.41219951 3.8125 1 P 0 ;0,1=6,2=0.000000
L 5.42593317 3.83333337 5.42753327 3.83583287 1 P 0 ;0,1=6,2=0.000000
L 5.42753327 3.83583287 5.4294 3.83708337 1 P 0 ;0,1=6,2=0.000000
L 5.4294 3.83708337 5.43153337 3.8375 1 P 0 ;0,1=6,2=0.000000
L 5.43153337 3.8375 5.4342 3.83666683 1 P 0 ;0,1=6,2=0.000000
L 5.4342 3.83666683 5.43606673 3.83458317 1 P 0 ;0,1=6,2=0.000000
L 5.43606673 3.83458317 5.4366 3.83208366 1 P 0 ;0,1=6,2=0.000000
L 5.4366 3.83208366 5.43633337 3.82958268 1 P 0 ;0,1=6,2=0.000000
L 5.43633337 3.82958268 5.43526644 3.8274998 1 P 0 ;0,1=6,2=0.000000
L 5.43526644 3.8274998 5.42993327 3.82333327 1 P 0 ;0,1=6,2=0.000000
L 5.42993327 3.82333327 5.42753327 3.82041644 1 P 0 ;0,1=6,2=0.000000
L 5.42753327 3.82041644 5.42593317 3.81624911 1 P 0 ;0,1=6,2=0.000000
L 5.42593317 3.81624911 5.4253999 3.8125 1 P 0 ;0,1=6,2=0.000000
L 5.4253999 3.8125 5.4366 3.8125 1 P 0 ;0,1=6,2=0.000000
L 5.39893317 3.68333337 5.40053327 3.68583287 1 P 0 ;0,1=174,2=0.000000
L 5.40053327 3.68583287 5.4024 3.68708337 1 P 0 ;0,1=174,2=0.000000
L 5.4024 3.68708337 5.40453337 3.6875 1 P 0 ;0,1=174,2=0.000000
L 5.40453337 3.6875 5.4072 3.68666683 1 P 0 ;0,1=174,2=0.000000
L 5.4072 3.68666683 5.40906673 3.68458317 1 P 0 ;0,1=174,2=0.000000
L 5.40906673 3.68458317 5.4096 3.68208366 1 P 0 ;0,1=174,2=0.000000
L 5.4096 3.68208366 5.40933337 3.67958268 1 P 0 ;0,1=174,2=0.000000
L 5.40933337 3.67958268 5.40826644 3.6774998 1 P 0 ;0,1=174,2=0.000000
L 5.40826644 3.6774998 5.40293327 3.67333327 1 P 0 ;0,1=174,2=0.000000
L 5.40293327 3.67333327 5.40053327 3.67041644 1 P 0 ;0,1=174,2=0.000000
L 5.40053327 3.67041644 5.39893317 3.66624911 1 P 0 ;0,1=174,2=0.000000
L 5.39893317 3.66624911 5.3983999 3.6625 1 P 0 ;0,1=174,2=0.000000
L 5.3983999 3.6625 5.4096 3.6625 1 P 0 ;0,1=174,2=0.000000
L 5.4259997 3.6875 5.42386634 3.68666683 1 P 0 ;0,1=174,2=0.000000
L 5.42386634 3.68666683 5.42226663 3.68458317 1 P 0 ;0,1=174,2=0.000000
L 5.42226663 3.68458317 5.4211998 3.68208366 1 P 0 ;0,1=174,2=0.000000
L 5.4211998 3.68208366 5.4203999 3.67874951 1 P 0 ;0,1=174,2=0.000000
L 5.4203999 3.67874951 5.42013327 3.67499961 1 P 0 ;0,1=174,2=0.000000
L 5.42013327 3.67499961 5.4203999 3.67124961 1 P 0 ;0,1=174,2=0.000000
L 5.4203999 3.67124961 5.4211998 3.66791624 1 P 0 ;0,1=174,2=0.000000
L 5.4211998 3.66791624 5.42226663 3.66541604 1 P 0 ;0,1=174,2=0.000000
L 5.42226663 3.66541604 5.42386634 3.66333307 1 P 0 ;0,1=174,2=0.000000
L 5.42386634 3.66333307 5.4259997 3.6625 1 P 0 ;0,1=174,2=0.000000
L 5.4259997 3.6625 5.42813307 3.66333307 1 P 0 ;0,1=174,2=0.000000
L 5.42813307 3.66333307 5.42973327 3.66541604 1 P 0 ;0,1=174,2=0.000000
L 5.42973327 3.66541604 5.4308001 3.66791624 1 P 0 ;0,1=174,2=0.000000
L 5.4308001 3.66791624 5.4316 3.67124961 1 P 0 ;0,1=174,2=0.000000
L 5.4316 3.67124961 5.43186663 3.67499961 1 P 0 ;0,1=174,2=0.000000
L 5.43186663 3.67499961 5.4316 3.67874951 1 P 0 ;0,1=174,2=0.000000
L 5.4316 3.67874951 5.4308001 3.68208366 1 P 0 ;0,1=174,2=0.000000
L 5.4308001 3.68208366 5.42973327 3.68458317 1 P 0 ;0,1=174,2=0.000000
L 5.42973327 3.68458317 5.42813307 3.68666683 1 P 0 ;0,1=174,2=0.000000
L 5.42813307 3.68666683 5.4259997 3.6875 1 P 0 ;0,1=174,2=0.000000
L 5.39106663 3.7655 5.39106663 3.74328327 1 P 0 ;0,1=237,2=0.000000
L 5.39106663 3.74328327 5.3925997 3.73863238 1 P 0 ;0,1=237,2=0.000000
L 5.3925997 3.73863238 5.39566634 3.73553307 1 P 0 ;0,1=237,2=0.000000
L 5.39566634 3.73553307 5.39949961 3.7345 1 P 0 ;0,1=237,2=0.000000
L 5.39949961 3.7345 5.40333356 3.73553307 1 P 0 ;0,1=237,2=0.000000
L 5.40333356 3.73553307 5.4064002 3.73863238 1 P 0 ;0,1=237,2=0.000000
L 5.4064002 3.73863238 5.40793327 3.74328327 1 P 0 ;0,1=237,2=0.000000
L 5.40793327 3.74328327 5.40793327 3.7655 1 P 0 ;0,1=237,2=0.000000
L 5.43049961 3.7345 5.43049961 3.7655 1 P 0 ;0,1=237,2=0.000000
L 5.43049961 3.7655 5.4258999 3.7593003 1 P 0 ;0,1=237,2=0.000000
L 5.4258999 3.7345 5.43509931 3.7345 1 P 0 ;0,1=237,2=0.000000
L 3.882 2.703 3.882 2.747 1 P 0 
L 3.792 2.703 3.882 2.703 1 P 0 
L 3.882 2.747 3.792 2.747 1 P 0 
L 3.792 2.747 3.792 2.703 1 P 0 
L 2.67583317 3.4545 2.67583317 3.4855 1 P 0 ;0,1=238,2=0.000000
L 2.67583317 3.4855 2.68541654 3.4855 1 P 0 ;0,1=238,2=0.000000
L 2.68541654 3.4855 2.68848327 3.48394931 1 P 0 ;0,1=238,2=0.000000
L 2.68848327 3.48394931 2.6904002 3.48188307 1 P 0 ;0,1=238,2=0.000000
L 2.6904002 3.48188307 2.69116673 3.4777497 1 P 0 ;0,1=238,2=0.000000
L 2.69116673 3.4777497 2.6904002 3.47361634 1 P 0 ;0,1=238,2=0.000000
L 2.6904002 3.47361634 2.6881 3.47103356 1 P 0 ;0,1=238,2=0.000000
L 2.6881 3.47103356 2.68541654 3.46948287 1 P 0 ;0,1=238,2=0.000000
L 2.68541654 3.46948287 2.67583317 3.46948287 1 P 0 ;0,1=238,2=0.000000
L 2.68541654 3.46948287 2.69116673 3.4545 1 P 0 ;0,1=238,2=0.000000
L 2.71449961 3.4545 2.71449961 3.4855 1 P 0 ;0,1=238,2=0.000000
L 2.71449961 3.4855 2.7098999 3.4793003 1 P 0 ;0,1=238,2=0.000000
L 2.7098999 3.4545 2.71909931 3.4545 1 P 0 ;0,1=238,2=0.000000
L 2.74549961 3.4545 2.74818307 3.45501654 1 P 0 ;0,1=238,2=0.000000
L 2.74818307 3.45501654 2.7512498 3.45656614 1 P 0 ;0,1=238,2=0.000000
L 2.7512498 3.45656614 2.75316673 3.45914892 1 P 0 ;0,1=238,2=0.000000
L 2.75316673 3.45914892 2.75393327 3.46276673 1 P 0 ;0,1=238,2=0.000000
L 2.75393327 3.46276673 2.75316673 3.46638268 1 P 0 ;0,1=238,2=0.000000
L 2.75316673 3.46638268 2.75086654 3.46948287 1 P 0 ;0,1=238,2=0.000000
L 2.75086654 3.46948287 2.74741654 3.47103356 1 P 0 ;0,1=238,2=0.000000
L 2.74741654 3.47103356 2.74358337 3.47103356 1 P 0 ;0,1=238,2=0.000000
L 2.74358337 3.47103356 2.74128317 3.47206663 1 P 0 ;0,1=238,2=0.000000
L 2.74128317 3.47206663 2.73936614 3.47464941 1 P 0 ;0,1=238,2=0.000000
L 2.73936614 3.47464941 2.7385997 3.47826624 1 P 0 ;0,1=238,2=0.000000
L 2.7385997 3.47826624 2.7397501 3.48188307 1 P 0 ;0,1=238,2=0.000000
L 2.7397501 3.48188307 2.74243287 3.48446683 1 P 0 ;0,1=238,2=0.000000
L 2.74243287 3.48446683 2.74549961 3.4855 1 P 0 ;0,1=238,2=0.000000
L 2.74549961 3.4855 2.74856634 3.48446683 1 P 0 ;0,1=238,2=0.000000
L 2.74856634 3.48446683 2.7512498 3.48188307 1 P 0 ;0,1=238,2=0.000000
L 2.7512498 3.48188307 2.7524002 3.47826624 1 P 0 ;0,1=238,2=0.000000
L 2.7524002 3.47826624 2.75163307 3.47464941 1 P 0 ;0,1=238,2=0.000000
L 2.75163307 3.47464941 2.74971673 3.47206663 1 P 0 ;0,1=238,2=0.000000
L 2.74971673 3.47206663 2.74741654 3.47103356 1 P 0 ;0,1=238,2=0.000000
L 2.74741654 3.47103356 2.74358337 3.47103356 1 P 0 ;0,1=238,2=0.000000
L 2.74358337 3.47103356 2.74013337 3.46948287 1 P 0 ;0,1=238,2=0.000000
L 2.74013337 3.46948287 2.73783317 3.46638268 1 P 0 ;0,1=238,2=0.000000
L 2.73783317 3.46638268 2.73706663 3.46276673 1 P 0 ;0,1=238,2=0.000000
L 2.73706663 3.46276673 2.73783317 3.45914892 1 P 0 ;0,1=238,2=0.000000
L 2.73783317 3.45914892 2.7397501 3.45656614 1 P 0 ;0,1=238,2=0.000000
L 2.7397501 3.45656614 2.74281683 3.45501654 1 P 0 ;0,1=238,2=0.000000
L 2.74281683 3.45501654 2.74549961 3.4545 1 P 0 ;0,1=238,2=0.000000
L 2.76998287 3.45811585 2.77266634 3.45553307 1 P 0 ;0,1=238,2=0.000000
L 2.77266634 3.45553307 2.77573307 3.4545 1 P 0 ;0,1=238,2=0.000000
L 2.77573307 3.4545 2.7787998 3.45553307 1 P 0 ;0,1=238,2=0.000000
L 2.7787998 3.45553307 2.78148327 3.45863238 1 P 0 ;0,1=238,2=0.000000
L 2.78148327 3.45863238 2.7834002 3.46328327 1 P 0 ;0,1=238,2=0.000000
L 2.7834002 3.46328327 2.78416673 3.46793327 1 P 0 ;0,1=238,2=0.000000
L 2.78416673 3.46793327 2.78416673 3.47361634 1 P 0 ;0,1=238,2=0.000000
L 2.78416673 3.47361634 2.7834002 3.47826624 1 P 0 ;0,1=238,2=0.000000
L 2.7834002 3.47826624 2.78148327 3.4823997 1 P 0 ;0,1=238,2=0.000000
L 2.78148327 3.4823997 2.77918307 3.48446683 1 P 0 ;0,1=238,2=0.000000
L 2.77918307 3.48446683 2.77649961 3.4855 1 P 0 ;0,1=238,2=0.000000
L 2.77649961 3.4855 2.77343287 3.48446683 1 P 0 ;0,1=238,2=0.000000
L 2.77343287 3.48446683 2.77113337 3.4823997 1 P 0 ;0,1=238,2=0.000000
L 2.77113337 3.4823997 2.7695997 3.4793003 1 P 0 ;0,1=238,2=0.000000
L 2.7695997 3.4793003 2.76883317 3.47516594 1 P 0 ;0,1=238,2=0.000000
L 2.76883317 3.47516594 2.7695997 3.4715501 1 P 0 ;0,1=238,2=0.000000
L 2.7695997 3.4715501 2.77151663 3.46793327 1 P 0 ;0,1=238,2=0.000000
L 2.77151663 3.46793327 2.77381683 3.46586604 1 P 0 ;0,1=238,2=0.000000
L 2.77381683 3.46586604 2.77649961 3.46534951 1 P 0 ;0,1=238,2=0.000000
L 2.77649961 3.46534951 2.77956634 3.46638268 1 P 0 ;0,1=238,2=0.000000
L 2.77956634 3.46638268 2.78186654 3.46896634 1 P 0 ;0,1=238,2=0.000000
L 2.78186654 3.46896634 2.78416673 3.47361634 1 P 0 ;0,1=238,2=0.000000
L 5.35 2.677 5.306 2.677 1 P 0 
L 5.35 2.587 5.35 2.677 1 P 0 
L 5.306 2.677 5.306 2.587 1 P 0 
L 5.306 2.587 5.35 2.587 1 P 0 
L 5.3555 2.38583317 5.3245 2.38583317 1 P 0 ;0,1=239,2=270.000000
L 5.3245 2.38583317 5.3245 2.39541654 1 P 0 ;0,1=239,2=270.000000
L 5.3245 2.39541654 5.32605069 2.39848327 1 P 0 ;0,1=239,2=270.000000
L 5.32605069 2.39848327 5.32811693 2.4004002 1 P 0 ;0,1=239,2=270.000000
L 5.32811693 2.4004002 5.3322503 2.40116673 1 P 0 ;0,1=239,2=270.000000
L 5.3322503 2.40116673 5.33638366 2.4004002 1 P 0 ;0,1=239,2=270.000000
L 5.33638366 2.4004002 5.33896644 2.3981 1 P 0 ;0,1=239,2=270.000000
L 5.33896644 2.3981 5.34051713 2.39541654 1 P 0 ;0,1=239,2=270.000000
L 5.34051713 2.39541654 5.34051713 2.38583317 1 P 0 ;0,1=239,2=270.000000
L 5.34051713 2.39541654 5.3555 2.40116673 1 P 0 ;0,1=239,2=270.000000
L 5.3555 2.42449961 5.3245 2.42449961 1 P 0 ;0,1=239,2=270.000000
L 5.3245 2.42449961 5.3306997 2.4198999 1 P 0 ;0,1=239,2=270.000000
L 5.3555 2.4198999 5.3555 2.42909931 1 P 0 ;0,1=239,2=270.000000
L 5.35188415 2.44898287 5.35446693 2.45166634 1 P 0 ;0,1=239,2=270.000000
L 5.35446693 2.45166634 5.3555 2.45473307 1 P 0 ;0,1=239,2=270.000000
L 5.3555 2.45473307 5.35446693 2.4577998 1 P 0 ;0,1=239,2=270.000000
L 5.35446693 2.4577998 5.35136762 2.46048327 1 P 0 ;0,1=239,2=270.000000
L 5.35136762 2.46048327 5.34671673 2.4624002 1 P 0 ;0,1=239,2=270.000000
L 5.34671673 2.4624002 5.34206673 2.46316673 1 P 0 ;0,1=239,2=270.000000
L 5.34206673 2.46316673 5.33638366 2.46316673 1 P 0 ;0,1=239,2=270.000000
L 5.33638366 2.46316673 5.33173376 2.4624002 1 P 0 ;0,1=239,2=270.000000
L 5.33173376 2.4624002 5.3276003 2.46048327 1 P 0 ;0,1=239,2=270.000000
L 5.3276003 2.46048327 5.32553317 2.45818307 1 P 0 ;0,1=239,2=270.000000
L 5.32553317 2.45818307 5.3245 2.45549961 1 P 0 ;0,1=239,2=270.000000
L 5.3245 2.45549961 5.32553317 2.45243287 1 P 0 ;0,1=239,2=270.000000
L 5.32553317 2.45243287 5.3276003 2.45013337 1 P 0 ;0,1=239,2=270.000000
L 5.3276003 2.45013337 5.3306997 2.4485997 1 P 0 ;0,1=239,2=270.000000
L 5.3306997 2.4485997 5.33483406 2.44783317 1 P 0 ;0,1=239,2=270.000000
L 5.33483406 2.44783317 5.3384499 2.4485997 1 P 0 ;0,1=239,2=270.000000
L 5.3384499 2.4485997 5.34206673 2.45051663 1 P 0 ;0,1=239,2=270.000000
L 5.34206673 2.45051663 5.34413396 2.45281683 1 P 0 ;0,1=239,2=270.000000
L 5.34413396 2.45281683 5.34465049 2.45549961 1 P 0 ;0,1=239,2=270.000000
L 5.34465049 2.45549961 5.34361732 2.45856634 1 P 0 ;0,1=239,2=270.000000
L 5.34361732 2.45856634 5.34103366 2.46086654 1 P 0 ;0,1=239,2=270.000000
L 5.34103366 2.46086654 5.33638366 2.46316673 1 P 0 ;0,1=239,2=270.000000
L 5.3245 2.48649961 5.32553317 2.48343287 1 P 0 ;0,1=239,2=270.000000
L 5.32553317 2.48343287 5.32811693 2.48113337 1 P 0 ;0,1=239,2=270.000000
L 5.32811693 2.48113337 5.33121624 2.4795997 1 P 0 ;0,1=239,2=270.000000
L 5.33121624 2.4795997 5.33535059 2.4784499 1 P 0 ;0,1=239,2=270.000000
L 5.33535059 2.4784499 5.34000049 2.47806663 1 P 0 ;0,1=239,2=270.000000
L 5.34000049 2.47806663 5.34465049 2.4784499 1 P 0 ;0,1=239,2=270.000000
L 5.34465049 2.4784499 5.34878386 2.4795997 1 P 0 ;0,1=239,2=270.000000
L 5.34878386 2.4795997 5.35188415 2.48113337 1 P 0 ;0,1=239,2=270.000000
L 5.35188415 2.48113337 5.35446693 2.48343287 1 P 0 ;0,1=239,2=270.000000
L 5.35446693 2.48343287 5.3555 2.48649961 1 P 0 ;0,1=239,2=270.000000
L 5.3555 2.48649961 5.35446693 2.48956634 1 P 0 ;0,1=239,2=270.000000
L 5.35446693 2.48956634 5.35188415 2.49186654 1 P 0 ;0,1=239,2=270.000000
L 5.35188415 2.49186654 5.34878386 2.4934002 1 P 0 ;0,1=239,2=270.000000
L 5.34878386 2.4934002 5.34465049 2.49455 1 P 0 ;0,1=239,2=270.000000
L 5.34465049 2.49455 5.34000049 2.49493327 1 P 0 ;0,1=239,2=270.000000
L 5.34000049 2.49493327 5.33535059 2.49455 1 P 0 ;0,1=239,2=270.000000
L 5.33535059 2.49455 5.33121624 2.4934002 1 P 0 ;0,1=239,2=270.000000
L 5.33121624 2.4934002 5.32811693 2.49186654 1 P 0 ;0,1=239,2=270.000000
L 5.32811693 2.49186654 5.32553317 2.48956634 1 P 0 ;0,1=239,2=270.000000
L 5.32553317 2.48956634 5.3245 2.48649961 1 P 0 ;0,1=239,2=270.000000
L 3.5325 2.41206998 3.6075 2.41206998 1 P 0 
L 3.6075 2.30593002 3.5325 2.30593002 1 P 0 
L 3.5325 2.30593002 3.5325 2.41206998 1 P 0 
L 3.6075 2.41206998 3.6075 2.30593002 1 P 0 
L 3.5905 2.43949961 3.5765502 2.43949961 1 P 0 ;0,1=240,2=270.000000
L 3.5765502 2.43949961 3.5595 2.43183317 1 P 0 ;0,1=240,2=270.000000
L 3.5595 2.44716673 3.5765502 2.43949961 1 P 0 ;0,1=240,2=270.000000
L 3.5905 2.47049961 3.5595 2.47049961 1 P 0 ;0,1=240,2=270.000000
L 3.5595 2.47049961 3.5656997 2.4658999 1 P 0 ;0,1=240,2=270.000000
L 3.5905 2.4658999 3.5905 2.47509931 1 P 0 ;0,1=240,2=270.000000
L 3.94 0.948 4.03 0.948 1 P 0 
L 3.94 0.992 3.94 0.948 1 P 0 
L 4.03 0.992 3.94 0.992 1 P 0 
L 4.03 0.948 4.03 0.992 1 P 0 
L 3.50583317 0.9495 3.50583317 0.9805 1 P 0 ;0,1=241,2=0.000000
L 3.50583317 0.9805 3.51541654 0.9805 1 P 0 ;0,1=241,2=0.000000
L 3.51541654 0.9805 3.51848327 0.97894931 1 P 0 ;0,1=241,2=0.000000
L 3.51848327 0.97894931 3.5204002 0.97688307 1 P 0 ;0,1=241,2=0.000000
L 3.5204002 0.97688307 3.52116673 0.9727497 1 P 0 ;0,1=241,2=0.000000
L 3.52116673 0.9727497 3.5204002 0.96861634 1 P 0 ;0,1=241,2=0.000000
L 3.5204002 0.96861634 3.5181 0.96603356 1 P 0 ;0,1=241,2=0.000000
L 3.5181 0.96603356 3.51541654 0.96448287 1 P 0 ;0,1=241,2=0.000000
L 3.51541654 0.96448287 3.50583317 0.96448287 1 P 0 ;0,1=241,2=0.000000
L 3.51541654 0.96448287 3.52116673 0.9495 1 P 0 ;0,1=241,2=0.000000
L 3.53721644 0.97533346 3.53951663 0.97843278 1 P 0 ;0,1=241,2=0.000000
L 3.53951663 0.97843278 3.5422001 0.97998337 1 P 0 ;0,1=241,2=0.000000
L 3.5422001 0.97998337 3.54526683 0.9805 1 P 0 ;0,1=241,2=0.000000
L 3.54526683 0.9805 3.5491 0.97946683 1 P 0 ;0,1=241,2=0.000000
L 3.5491 0.97946683 3.55178346 0.97688307 1 P 0 ;0,1=241,2=0.000000
L 3.55178346 0.97688307 3.55255 0.97378376 1 P 0 ;0,1=241,2=0.000000
L 3.55255 0.97378376 3.55216673 0.97068258 1 P 0 ;0,1=241,2=0.000000
L 3.55216673 0.97068258 3.55063307 0.9680998 1 P 0 ;0,1=241,2=0.000000
L 3.55063307 0.9680998 3.54296663 0.96293327 1 P 0 ;0,1=241,2=0.000000
L 3.54296663 0.96293327 3.53951663 0.95931644 1 P 0 ;0,1=241,2=0.000000
L 3.53951663 0.95931644 3.53721644 0.95414892 1 P 0 ;0,1=241,2=0.000000
L 3.53721644 0.95414892 3.5364499 0.9495 1 P 0 ;0,1=241,2=0.000000
L 3.5364499 0.9495 3.55255 0.9495 1 P 0 ;0,1=241,2=0.000000
L 3.5801 0.9495 3.5801 0.9805 1 P 0 ;0,1=241,2=0.000000
L 3.5801 0.9805 3.56591624 0.95828327 1 P 0 ;0,1=241,2=0.000000
L 3.56591624 0.95828327 3.58508366 0.95828327 1 P 0 ;0,1=241,2=0.000000
L 3.60649961 0.9805 3.60343287 0.97946683 1 P 0 ;0,1=241,2=0.000000
L 3.60343287 0.97946683 3.60113337 0.97688307 1 P 0 ;0,1=241,2=0.000000
L 3.60113337 0.97688307 3.5995997 0.97378376 1 P 0 ;0,1=241,2=0.000000
L 3.5995997 0.97378376 3.5984499 0.96964941 1 P 0 ;0,1=241,2=0.000000
L 3.5984499 0.96964941 3.59806663 0.96499951 1 P 0 ;0,1=241,2=0.000000
L 3.59806663 0.96499951 3.5984499 0.96034951 1 P 0 ;0,1=241,2=0.000000
L 3.5984499 0.96034951 3.5995997 0.95621614 1 P 0 ;0,1=241,2=0.000000
L 3.5995997 0.95621614 3.60113337 0.95311585 1 P 0 ;0,1=241,2=0.000000
L 3.60113337 0.95311585 3.60343287 0.95053307 1 P 0 ;0,1=241,2=0.000000
L 3.60343287 0.95053307 3.60649961 0.9495 1 P 0 ;0,1=241,2=0.000000
L 3.60649961 0.9495 3.60956634 0.95053307 1 P 0 ;0,1=241,2=0.000000
L 3.60956634 0.95053307 3.61186654 0.95311585 1 P 0 ;0,1=241,2=0.000000
L 3.61186654 0.95311585 3.6134002 0.95621614 1 P 0 ;0,1=241,2=0.000000
L 3.6134002 0.95621614 3.61455 0.96034951 1 P 0 ;0,1=241,2=0.000000
L 3.61455 0.96034951 3.61493327 0.96499951 1 P 0 ;0,1=241,2=0.000000
L 3.61493327 0.96499951 3.61455 0.96964941 1 P 0 ;0,1=241,2=0.000000
L 3.61455 0.96964941 3.6134002 0.97378376 1 P 0 ;0,1=241,2=0.000000
L 3.6134002 0.97378376 3.61186654 0.97688307 1 P 0 ;0,1=241,2=0.000000
L 3.61186654 0.97688307 3.60956634 0.97946683 1 P 0 ;0,1=241,2=0.000000
L 3.60956634 0.97946683 3.60649961 0.9805 1 P 0 ;0,1=241,2=0.000000
L 4.035 0.992 4.035 0.948 1 P 0 
L 4.125 0.992 4.035 0.992 1 P 0 
L 4.125 0.948 4.125 0.992 1 P 0 
L 4.035 0.948 4.125 0.948 1 P 0 
L 3.63083317 0.9495 3.63083317 0.9805 1 P 0 ;0,1=242,2=0.000000
L 3.63083317 0.9805 3.64041654 0.9805 1 P 0 ;0,1=242,2=0.000000
L 3.64041654 0.9805 3.64348327 0.97894931 1 P 0 ;0,1=242,2=0.000000
L 3.64348327 0.97894931 3.6454002 0.97688307 1 P 0 ;0,1=242,2=0.000000
L 3.6454002 0.97688307 3.64616673 0.9727497 1 P 0 ;0,1=242,2=0.000000
L 3.64616673 0.9727497 3.6454002 0.96861634 1 P 0 ;0,1=242,2=0.000000
L 3.6454002 0.96861634 3.6431 0.96603356 1 P 0 ;0,1=242,2=0.000000
L 3.6431 0.96603356 3.64041654 0.96448287 1 P 0 ;0,1=242,2=0.000000
L 3.64041654 0.96448287 3.63083317 0.96448287 1 P 0 ;0,1=242,2=0.000000
L 3.64041654 0.96448287 3.64616673 0.9495 1 P 0 ;0,1=242,2=0.000000
L 3.66221644 0.97533346 3.66451663 0.97843278 1 P 0 ;0,1=242,2=0.000000
L 3.66451663 0.97843278 3.6672001 0.97998337 1 P 0 ;0,1=242,2=0.000000
L 3.6672001 0.97998337 3.67026683 0.9805 1 P 0 ;0,1=242,2=0.000000
L 3.67026683 0.9805 3.6741 0.97946683 1 P 0 ;0,1=242,2=0.000000
L 3.6741 0.97946683 3.67678346 0.97688307 1 P 0 ;0,1=242,2=0.000000
L 3.67678346 0.97688307 3.67755 0.97378376 1 P 0 ;0,1=242,2=0.000000
L 3.67755 0.97378376 3.67716673 0.97068258 1 P 0 ;0,1=242,2=0.000000
L 3.67716673 0.97068258 3.67563307 0.9680998 1 P 0 ;0,1=242,2=0.000000
L 3.67563307 0.9680998 3.66796663 0.96293327 1 P 0 ;0,1=242,2=0.000000
L 3.66796663 0.96293327 3.66451663 0.95931644 1 P 0 ;0,1=242,2=0.000000
L 3.66451663 0.95931644 3.66221644 0.95414892 1 P 0 ;0,1=242,2=0.000000
L 3.66221644 0.95414892 3.6614499 0.9495 1 P 0 ;0,1=242,2=0.000000
L 3.6614499 0.9495 3.67755 0.9495 1 P 0 ;0,1=242,2=0.000000
L 3.7051 0.9495 3.7051 0.9805 1 P 0 ;0,1=242,2=0.000000
L 3.7051 0.9805 3.69091624 0.95828327 1 P 0 ;0,1=242,2=0.000000
L 3.69091624 0.95828327 3.71008366 0.95828327 1 P 0 ;0,1=242,2=0.000000
L 3.72421644 0.97533346 3.72651663 0.97843278 1 P 0 ;0,1=242,2=0.000000
L 3.72651663 0.97843278 3.7292001 0.97998337 1 P 0 ;0,1=242,2=0.000000
L 3.7292001 0.97998337 3.73226683 0.9805 1 P 0 ;0,1=242,2=0.000000
L 3.73226683 0.9805 3.7361 0.97946683 1 P 0 ;0,1=242,2=0.000000
L 3.7361 0.97946683 3.73878346 0.97688307 1 P 0 ;0,1=242,2=0.000000
L 3.73878346 0.97688307 3.73955 0.97378376 1 P 0 ;0,1=242,2=0.000000
L 3.73955 0.97378376 3.73916673 0.97068258 1 P 0 ;0,1=242,2=0.000000
L 3.73916673 0.97068258 3.73763307 0.9680998 1 P 0 ;0,1=242,2=0.000000
L 3.73763307 0.9680998 3.72996663 0.96293327 1 P 0 ;0,1=242,2=0.000000
L 3.72996663 0.96293327 3.72651663 0.95931644 1 P 0 ;0,1=242,2=0.000000
L 3.72651663 0.95931644 3.72421644 0.95414892 1 P 0 ;0,1=242,2=0.000000
L 3.72421644 0.95414892 3.7234499 0.9495 1 P 0 ;0,1=242,2=0.000000
L 3.7234499 0.9495 3.73955 0.9495 1 P 0 ;0,1=242,2=0.000000
L 3.792 0.85 3.792 0.94 1 P 0 
L 3.748 0.85 3.792 0.85 1 P 0 
L 3.748 0.94 3.748 0.85 1 P 0 
L 3.792 0.94 3.748 0.94 1 P 0 
L 3.7805 0.73083317 3.7495 0.73083317 1 P 0 ;0,1=243,2=270.000000
L 3.7495 0.73083317 3.7495 0.74041654 1 P 0 ;0,1=243,2=270.000000
L 3.7495 0.74041654 3.75105069 0.74348327 1 P 0 ;0,1=243,2=270.000000
L 3.75105069 0.74348327 3.75311693 0.7454002 1 P 0 ;0,1=243,2=270.000000
L 3.75311693 0.7454002 3.7572503 0.74616673 1 P 0 ;0,1=243,2=270.000000
L 3.7572503 0.74616673 3.76138366 0.7454002 1 P 0 ;0,1=243,2=270.000000
L 3.76138366 0.7454002 3.76396644 0.7431 1 P 0 ;0,1=243,2=270.000000
L 3.76396644 0.7431 3.76551713 0.74041654 1 P 0 ;0,1=243,2=270.000000
L 3.76551713 0.74041654 3.76551713 0.73083317 1 P 0 ;0,1=243,2=270.000000
L 3.76551713 0.74041654 3.7805 0.74616673 1 P 0 ;0,1=243,2=270.000000
L 3.75466654 0.76221644 3.75156722 0.76451663 1 P 0 ;0,1=243,2=270.000000
L 3.75156722 0.76451663 3.75001663 0.7672001 1 P 0 ;0,1=243,2=270.000000
L 3.75001663 0.7672001 3.7495 0.77026683 1 P 0 ;0,1=243,2=270.000000
L 3.7495 0.77026683 3.75053317 0.7741 1 P 0 ;0,1=243,2=270.000000
L 3.75053317 0.7741 3.75311693 0.77678346 1 P 0 ;0,1=243,2=270.000000
L 3.75311693 0.77678346 3.75621624 0.77755 1 P 0 ;0,1=243,2=270.000000
L 3.75621624 0.77755 3.75931742 0.77716673 1 P 0 ;0,1=243,2=270.000000
L 3.75931742 0.77716673 3.7619002 0.77563307 1 P 0 ;0,1=243,2=270.000000
L 3.7619002 0.77563307 3.76706673 0.76796663 1 P 0 ;0,1=243,2=270.000000
L 3.76706673 0.76796663 3.77068356 0.76451663 1 P 0 ;0,1=243,2=270.000000
L 3.77068356 0.76451663 3.77585108 0.76221644 1 P 0 ;0,1=243,2=270.000000
L 3.77585108 0.76221644 3.7805 0.7614499 1 P 0 ;0,1=243,2=270.000000
L 3.7805 0.7614499 3.7805 0.77755 1 P 0 ;0,1=243,2=270.000000
L 3.77430039 0.79206663 3.77791722 0.79436614 1 P 0 ;0,1=243,2=270.000000
L 3.77791722 0.79436614 3.77998346 0.79743287 1 P 0 ;0,1=243,2=270.000000
L 3.77998346 0.79743287 3.7805 0.80088356 1 P 0 ;0,1=243,2=270.000000
L 3.7805 0.80088356 3.77998346 0.8039503 1 P 0 ;0,1=243,2=270.000000
L 3.77998346 0.8039503 3.77740069 0.80701703 1 P 0 ;0,1=243,2=270.000000
L 3.77740069 0.80701703 3.77430039 0.80893327 1 P 0 ;0,1=243,2=270.000000
L 3.77430039 0.80893327 3.7712001 0.80931654 1 P 0 ;0,1=243,2=270.000000
L 3.7712001 0.80931654 3.76758425 0.80855 1 P 0 ;0,1=243,2=270.000000
L 3.76758425 0.80855 3.76500049 0.80586654 1 P 0 ;0,1=243,2=270.000000
L 3.76500049 0.80586654 3.76396644 0.80318307 1 P 0 ;0,1=243,2=270.000000
L 3.76396644 0.80318307 3.76396644 0.79973307 1 P 0 ;0,1=243,2=270.000000
L 3.76396644 0.80318307 3.76241683 0.80548327 1 P 0 ;0,1=243,2=270.000000
L 3.76241683 0.80548327 3.75983406 0.8074002 1 P 0 ;0,1=243,2=270.000000
L 3.75983406 0.8074002 3.75673376 0.80816673 1 P 0 ;0,1=243,2=270.000000
L 3.75673376 0.80816673 3.75363346 0.8074002 1 P 0 ;0,1=243,2=270.000000
L 3.75363346 0.8074002 3.75105069 0.80548327 1 P 0 ;0,1=243,2=270.000000
L 3.75105069 0.80548327 3.7495 0.80203327 1 P 0 ;0,1=243,2=270.000000
L 3.7495 0.80203327 3.75001663 0.79858337 1 P 0 ;0,1=243,2=270.000000
L 3.75001663 0.79858337 3.75208376 0.79513337 1 P 0 ;0,1=243,2=270.000000
L 3.76758425 0.82421644 3.76396644 0.8268999 1 P 0 ;0,1=243,2=270.000000
L 3.76396644 0.8268999 3.7619002 0.8292001 1 P 0 ;0,1=243,2=270.000000
L 3.7619002 0.8292001 3.76086713 0.83226683 1 P 0 ;0,1=243,2=270.000000
L 3.76086713 0.83226683 3.7619002 0.8349503 1 P 0 ;0,1=243,2=270.000000
L 3.7619002 0.8349503 3.76396644 0.83686654 1 P 0 ;0,1=243,2=270.000000
L 3.76396644 0.83686654 3.76706673 0.8384002 1 P 0 ;0,1=243,2=270.000000
L 3.76706673 0.8384002 3.77068356 0.83878346 1 P 0 ;0,1=243,2=270.000000
L 3.77068356 0.83878346 3.77378386 0.8384002 1 P 0 ;0,1=243,2=270.000000
L 3.77378386 0.8384002 3.77688415 0.83686654 1 P 0 ;0,1=243,2=270.000000
L 3.77688415 0.83686654 3.77946693 0.83456634 1 P 0 ;0,1=243,2=270.000000
L 3.77946693 0.83456634 3.7805 0.83188356 1 P 0 ;0,1=243,2=270.000000
L 3.7805 0.83188356 3.77946693 0.82881683 1 P 0 ;0,1=243,2=270.000000
L 3.77946693 0.82881683 3.77636762 0.82613337 1 P 0 ;0,1=243,2=270.000000
L 3.77636762 0.82613337 3.77171673 0.8245997 1 P 0 ;0,1=243,2=270.000000
L 3.77171673 0.8245997 3.7665502 0.82421644 1 P 0 ;0,1=243,2=270.000000
L 3.7665502 0.82421644 3.75983406 0.82498287 1 P 0 ;0,1=243,2=270.000000
L 3.75983406 0.82498287 3.75621624 0.82613337 1 P 0 ;0,1=243,2=270.000000
L 3.75621624 0.82613337 3.7526003 0.82804961 1 P 0 ;0,1=243,2=270.000000
L 3.7526003 0.82804961 3.75001663 0.83073307 1 P 0 ;0,1=243,2=270.000000
L 3.75001663 0.83073307 3.7495 0.83341654 1 P 0 ;0,1=243,2=270.000000
L 3.7495 0.83341654 3.75053317 0.8361 1 P 0 ;0,1=243,2=270.000000
L 3.75053317 0.8361 3.75311693 0.83801703 1 P 0 ;0,1=243,2=270.000000
L 3.099 1.728 3.189 1.728 1 P 0 
L 3.099 1.772 3.099 1.728 1 P 0 
L 3.189 1.772 3.099 1.772 1 P 0 
L 3.189 1.728 3.189 1.772 1 P 0 
L 3.10633317 1.1845 3.10633317 1.2155 1 P 0 ;0,1=244,2=0.000000
L 3.10633317 1.2155 3.11591654 1.2155 1 P 0 ;0,1=244,2=0.000000
L 3.11591654 1.2155 3.11898327 1.21394931 1 P 0 ;0,1=244,2=0.000000
L 3.11898327 1.21394931 3.1209002 1.21188307 1 P 0 ;0,1=244,2=0.000000
L 3.1209002 1.21188307 3.12166673 1.2077497 1 P 0 ;0,1=244,2=0.000000
L 3.12166673 1.2077497 3.1209002 1.20361634 1 P 0 ;0,1=244,2=0.000000
L 3.1209002 1.20361634 3.1186 1.20103356 1 P 0 ;0,1=244,2=0.000000
L 3.1186 1.20103356 3.11591654 1.19948287 1 P 0 ;0,1=244,2=0.000000
L 3.11591654 1.19948287 3.10633317 1.19948287 1 P 0 ;0,1=244,2=0.000000
L 3.11591654 1.19948287 3.12166673 1.1845 1 P 0 ;0,1=244,2=0.000000
L 3.14499961 1.1845 3.14768307 1.18501654 1 P 0 ;0,1=244,2=0.000000
L 3.14768307 1.18501654 3.1507498 1.18656614 1 P 0 ;0,1=244,2=0.000000
L 3.1507498 1.18656614 3.15266673 1.18914892 1 P 0 ;0,1=244,2=0.000000
L 3.15266673 1.18914892 3.15343327 1.19276673 1 P 0 ;0,1=244,2=0.000000
L 3.15343327 1.19276673 3.15266673 1.19638268 1 P 0 ;0,1=244,2=0.000000
L 3.15266673 1.19638268 3.15036654 1.19948287 1 P 0 ;0,1=244,2=0.000000
L 3.15036654 1.19948287 3.14691654 1.20103356 1 P 0 ;0,1=244,2=0.000000
L 3.14691654 1.20103356 3.14308337 1.20103356 1 P 0 ;0,1=244,2=0.000000
L 3.14308337 1.20103356 3.14078317 1.20206663 1 P 0 ;0,1=244,2=0.000000
L 3.14078317 1.20206663 3.13886614 1.20464941 1 P 0 ;0,1=244,2=0.000000
L 3.13886614 1.20464941 3.1380997 1.20826624 1 P 0 ;0,1=244,2=0.000000
L 3.1380997 1.20826624 3.1392501 1.21188307 1 P 0 ;0,1=244,2=0.000000
L 3.1392501 1.21188307 3.14193287 1.21446683 1 P 0 ;0,1=244,2=0.000000
L 3.14193287 1.21446683 3.14499961 1.2155 1 P 0 ;0,1=244,2=0.000000
L 3.14499961 1.2155 3.14806634 1.21446683 1 P 0 ;0,1=244,2=0.000000
L 3.14806634 1.21446683 3.1507498 1.21188307 1 P 0 ;0,1=244,2=0.000000
L 3.1507498 1.21188307 3.1519002 1.20826624 1 P 0 ;0,1=244,2=0.000000
L 3.1519002 1.20826624 3.15113307 1.20464941 1 P 0 ;0,1=244,2=0.000000
L 3.15113307 1.20464941 3.14921673 1.20206663 1 P 0 ;0,1=244,2=0.000000
L 3.14921673 1.20206663 3.14691654 1.20103356 1 P 0 ;0,1=244,2=0.000000
L 3.14691654 1.20103356 3.14308337 1.20103356 1 P 0 ;0,1=244,2=0.000000
L 3.14308337 1.20103356 3.13963337 1.19948287 1 P 0 ;0,1=244,2=0.000000
L 3.13963337 1.19948287 3.13733317 1.19638268 1 P 0 ;0,1=244,2=0.000000
L 3.13733317 1.19638268 3.13656663 1.19276673 1 P 0 ;0,1=244,2=0.000000
L 3.13656663 1.19276673 3.13733317 1.18914892 1 P 0 ;0,1=244,2=0.000000
L 3.13733317 1.18914892 3.1392501 1.18656614 1 P 0 ;0,1=244,2=0.000000
L 3.1392501 1.18656614 3.14231683 1.18501654 1 P 0 ;0,1=244,2=0.000000
L 3.14231683 1.18501654 3.14499961 1.1845 1 P 0 ;0,1=244,2=0.000000
L 3.17599961 1.1845 3.17868307 1.18501654 1 P 0 ;0,1=244,2=0.000000
L 3.17868307 1.18501654 3.1817498 1.18656614 1 P 0 ;0,1=244,2=0.000000
L 3.1817498 1.18656614 3.18366673 1.18914892 1 P 0 ;0,1=244,2=0.000000
L 3.18366673 1.18914892 3.18443327 1.19276673 1 P 0 ;0,1=244,2=0.000000
L 3.18443327 1.19276673 3.18366673 1.19638268 1 P 0 ;0,1=244,2=0.000000
L 3.18366673 1.19638268 3.18136654 1.19948287 1 P 0 ;0,1=244,2=0.000000
L 3.18136654 1.19948287 3.17791654 1.20103356 1 P 0 ;0,1=244,2=0.000000
L 3.17791654 1.20103356 3.17408337 1.20103356 1 P 0 ;0,1=244,2=0.000000
L 3.17408337 1.20103356 3.17178317 1.20206663 1 P 0 ;0,1=244,2=0.000000
L 3.17178317 1.20206663 3.16986614 1.20464941 1 P 0 ;0,1=244,2=0.000000
L 3.16986614 1.20464941 3.1690997 1.20826624 1 P 0 ;0,1=244,2=0.000000
L 3.1690997 1.20826624 3.1702501 1.21188307 1 P 0 ;0,1=244,2=0.000000
L 3.1702501 1.21188307 3.17293287 1.21446683 1 P 0 ;0,1=244,2=0.000000
L 3.17293287 1.21446683 3.17599961 1.2155 1 P 0 ;0,1=244,2=0.000000
L 3.17599961 1.2155 3.17906634 1.21446683 1 P 0 ;0,1=244,2=0.000000
L 3.17906634 1.21446683 3.1817498 1.21188307 1 P 0 ;0,1=244,2=0.000000
L 3.1817498 1.21188307 3.1829002 1.20826624 1 P 0 ;0,1=244,2=0.000000
L 3.1829002 1.20826624 3.18213307 1.20464941 1 P 0 ;0,1=244,2=0.000000
L 3.18213307 1.20464941 3.18021673 1.20206663 1 P 0 ;0,1=244,2=0.000000
L 3.18021673 1.20206663 3.17791654 1.20103356 1 P 0 ;0,1=244,2=0.000000
L 3.17791654 1.20103356 3.17408337 1.20103356 1 P 0 ;0,1=244,2=0.000000
L 3.17408337 1.20103356 3.17063337 1.19948287 1 P 0 ;0,1=244,2=0.000000
L 3.17063337 1.19948287 3.16833317 1.19638268 1 P 0 ;0,1=244,2=0.000000
L 3.16833317 1.19638268 3.16756663 1.19276673 1 P 0 ;0,1=244,2=0.000000
L 3.16756663 1.19276673 3.16833317 1.18914892 1 P 0 ;0,1=244,2=0.000000
L 3.16833317 1.18914892 3.1702501 1.18656614 1 P 0 ;0,1=244,2=0.000000
L 3.1702501 1.18656614 3.17331683 1.18501654 1 P 0 ;0,1=244,2=0.000000
L 3.17331683 1.18501654 3.17599961 1.1845 1 P 0 ;0,1=244,2=0.000000
L 3.1 1.717 3.1 1.673 1 P 0 
L 3.19 1.717 3.1 1.717 1 P 0 
L 3.1 1.673 3.19 1.673 1 P 0 
L 3.19 1.673 3.19 1.717 1 P 0 
L 3.10633317 1.1345 3.10633317 1.1655 1 P 0 ;0,1=245,2=0.000000
L 3.10633317 1.1655 3.11591654 1.1655 1 P 0 ;0,1=245,2=0.000000
L 3.11591654 1.1655 3.11898327 1.16394931 1 P 0 ;0,1=245,2=0.000000
L 3.11898327 1.16394931 3.1209002 1.16188307 1 P 0 ;0,1=245,2=0.000000
L 3.1209002 1.16188307 3.12166673 1.1577497 1 P 0 ;0,1=245,2=0.000000
L 3.12166673 1.1577497 3.1209002 1.15361634 1 P 0 ;0,1=245,2=0.000000
L 3.1209002 1.15361634 3.1186 1.15103356 1 P 0 ;0,1=245,2=0.000000
L 3.1186 1.15103356 3.11591654 1.14948287 1 P 0 ;0,1=245,2=0.000000
L 3.11591654 1.14948287 3.10633317 1.14948287 1 P 0 ;0,1=245,2=0.000000
L 3.11591654 1.14948287 3.12166673 1.1345 1 P 0 ;0,1=245,2=0.000000
L 3.13848287 1.13811585 3.14116634 1.13553307 1 P 0 ;0,1=245,2=0.000000
L 3.14116634 1.13553307 3.14423307 1.1345 1 P 0 ;0,1=245,2=0.000000
L 3.14423307 1.1345 3.1472998 1.13553307 1 P 0 ;0,1=245,2=0.000000
L 3.1472998 1.13553307 3.14998327 1.13863238 1 P 0 ;0,1=245,2=0.000000
L 3.14998327 1.13863238 3.1519002 1.14328327 1 P 0 ;0,1=245,2=0.000000
L 3.1519002 1.14328327 3.15266673 1.14793327 1 P 0 ;0,1=245,2=0.000000
L 3.15266673 1.14793327 3.15266673 1.15361634 1 P 0 ;0,1=245,2=0.000000
L 3.15266673 1.15361634 3.1519002 1.15826624 1 P 0 ;0,1=245,2=0.000000
L 3.1519002 1.15826624 3.14998327 1.1623997 1 P 0 ;0,1=245,2=0.000000
L 3.14998327 1.1623997 3.14768307 1.16446683 1 P 0 ;0,1=245,2=0.000000
L 3.14768307 1.16446683 3.14499961 1.1655 1 P 0 ;0,1=245,2=0.000000
L 3.14499961 1.1655 3.14193287 1.16446683 1 P 0 ;0,1=245,2=0.000000
L 3.14193287 1.16446683 3.13963337 1.1623997 1 P 0 ;0,1=245,2=0.000000
L 3.13963337 1.1623997 3.1380997 1.1593003 1 P 0 ;0,1=245,2=0.000000
L 3.1380997 1.1593003 3.13733317 1.15516594 1 P 0 ;0,1=245,2=0.000000
L 3.13733317 1.15516594 3.1380997 1.1515501 1 P 0 ;0,1=245,2=0.000000
L 3.1380997 1.1515501 3.14001663 1.14793327 1 P 0 ;0,1=245,2=0.000000
L 3.14001663 1.14793327 3.14231683 1.14586604 1 P 0 ;0,1=245,2=0.000000
L 3.14231683 1.14586604 3.14499961 1.14534951 1 P 0 ;0,1=245,2=0.000000
L 3.14499961 1.14534951 3.14806634 1.14638268 1 P 0 ;0,1=245,2=0.000000
L 3.14806634 1.14638268 3.15036654 1.14896634 1 P 0 ;0,1=245,2=0.000000
L 3.15036654 1.14896634 3.15266673 1.15361634 1 P 0 ;0,1=245,2=0.000000
L 3.16871644 1.14741575 3.1713999 1.15103356 1 P 0 ;0,1=245,2=0.000000
L 3.1713999 1.15103356 3.1737001 1.1530998 1 P 0 ;0,1=245,2=0.000000
L 3.1737001 1.1530998 3.17676683 1.15413287 1 P 0 ;0,1=245,2=0.000000
L 3.17676683 1.15413287 3.1794503 1.1530998 1 P 0 ;0,1=245,2=0.000000
L 3.1794503 1.1530998 3.18136654 1.15103356 1 P 0 ;0,1=245,2=0.000000
L 3.18136654 1.15103356 3.1829002 1.14793327 1 P 0 ;0,1=245,2=0.000000
L 3.1829002 1.14793327 3.18328346 1.14431644 1 P 0 ;0,1=245,2=0.000000
L 3.18328346 1.14431644 3.1829002 1.14121614 1 P 0 ;0,1=245,2=0.000000
L 3.1829002 1.14121614 3.18136654 1.13811585 1 P 0 ;0,1=245,2=0.000000
L 3.18136654 1.13811585 3.17906634 1.13553307 1 P 0 ;0,1=245,2=0.000000
L 3.17906634 1.13553307 3.17638356 1.1345 1 P 0 ;0,1=245,2=0.000000
L 3.17638356 1.1345 3.17331683 1.13553307 1 P 0 ;0,1=245,2=0.000000
L 3.17331683 1.13553307 3.17063337 1.13863238 1 P 0 ;0,1=245,2=0.000000
L 3.17063337 1.13863238 3.1690997 1.14328327 1 P 0 ;0,1=245,2=0.000000
L 3.1690997 1.14328327 3.16871644 1.1484498 1 P 0 ;0,1=245,2=0.000000
L 3.16871644 1.1484498 3.16948287 1.15516594 1 P 0 ;0,1=245,2=0.000000
L 3.16948287 1.15516594 3.17063337 1.15878376 1 P 0 ;0,1=245,2=0.000000
L 3.17063337 1.15878376 3.17254961 1.1623997 1 P 0 ;0,1=245,2=0.000000
L 3.17254961 1.1623997 3.17523307 1.16498337 1 P 0 ;0,1=245,2=0.000000
L 3.17523307 1.16498337 3.17791654 1.1655 1 P 0 ;0,1=245,2=0.000000
L 3.17791654 1.1655 3.1806 1.16446683 1 P 0 ;0,1=245,2=0.000000
L 3.1806 1.16446683 3.18251703 1.16188307 1 P 0 ;0,1=245,2=0.000000
L 3.1 1.623 3.19 1.623 1 P 0 
L 3.1 1.667 3.1 1.623 1 P 0 
L 3.19 1.667 3.1 1.667 1 P 0 
L 3.19 1.623 3.19 1.667 1 P 0 
L 3.10583317 1.0845 3.10583317 1.1155 1 P 0 ;0,1=246,2=0.000000
L 3.10583317 1.1155 3.11541654 1.1155 1 P 0 ;0,1=246,2=0.000000
L 3.11541654 1.1155 3.11848327 1.11394931 1 P 0 ;0,1=246,2=0.000000
L 3.11848327 1.11394931 3.1204002 1.11188307 1 P 0 ;0,1=246,2=0.000000
L 3.1204002 1.11188307 3.12116673 1.1077497 1 P 0 ;0,1=246,2=0.000000
L 3.12116673 1.1077497 3.1204002 1.10361634 1 P 0 ;0,1=246,2=0.000000
L 3.1204002 1.10361634 3.1181 1.10103356 1 P 0 ;0,1=246,2=0.000000
L 3.1181 1.10103356 3.11541654 1.09948287 1 P 0 ;0,1=246,2=0.000000
L 3.11541654 1.09948287 3.10583317 1.09948287 1 P 0 ;0,1=246,2=0.000000
L 3.11541654 1.09948287 3.12116673 1.0845 1 P 0 ;0,1=246,2=0.000000
L 3.13721644 1.11033346 3.13951663 1.11343278 1 P 0 ;0,1=246,2=0.000000
L 3.13951663 1.11343278 3.1422001 1.11498337 1 P 0 ;0,1=246,2=0.000000
L 3.1422001 1.11498337 3.14526683 1.1155 1 P 0 ;0,1=246,2=0.000000
L 3.14526683 1.1155 3.1491 1.11446683 1 P 0 ;0,1=246,2=0.000000
L 3.1491 1.11446683 3.15178346 1.11188307 1 P 0 ;0,1=246,2=0.000000
L 3.15178346 1.11188307 3.15255 1.10878376 1 P 0 ;0,1=246,2=0.000000
L 3.15255 1.10878376 3.15216673 1.10568258 1 P 0 ;0,1=246,2=0.000000
L 3.15216673 1.10568258 3.15063307 1.1030998 1 P 0 ;0,1=246,2=0.000000
L 3.15063307 1.1030998 3.14296663 1.09793327 1 P 0 ;0,1=246,2=0.000000
L 3.14296663 1.09793327 3.13951663 1.09431644 1 P 0 ;0,1=246,2=0.000000
L 3.13951663 1.09431644 3.13721644 1.08914892 1 P 0 ;0,1=246,2=0.000000
L 3.13721644 1.08914892 3.1364499 1.0845 1 P 0 ;0,1=246,2=0.000000
L 3.1364499 1.0845 3.15255 1.0845 1 P 0 ;0,1=246,2=0.000000
L 3.17549961 1.0845 3.17818307 1.08501654 1 P 0 ;0,1=246,2=0.000000
L 3.17818307 1.08501654 3.1812498 1.08656614 1 P 0 ;0,1=246,2=0.000000
L 3.1812498 1.08656614 3.18316673 1.08914892 1 P 0 ;0,1=246,2=0.000000
L 3.18316673 1.08914892 3.18393327 1.09276673 1 P 0 ;0,1=246,2=0.000000
L 3.18393327 1.09276673 3.18316673 1.09638268 1 P 0 ;0,1=246,2=0.000000
L 3.18316673 1.09638268 3.18086654 1.09948287 1 P 0 ;0,1=246,2=0.000000
L 3.18086654 1.09948287 3.17741654 1.10103356 1 P 0 ;0,1=246,2=0.000000
L 3.17741654 1.10103356 3.17358337 1.10103356 1 P 0 ;0,1=246,2=0.000000
L 3.17358337 1.10103356 3.17128317 1.10206663 1 P 0 ;0,1=246,2=0.000000
L 3.17128317 1.10206663 3.16936614 1.10464941 1 P 0 ;0,1=246,2=0.000000
L 3.16936614 1.10464941 3.1685997 1.10826624 1 P 0 ;0,1=246,2=0.000000
L 3.1685997 1.10826624 3.1697501 1.11188307 1 P 0 ;0,1=246,2=0.000000
L 3.1697501 1.11188307 3.17243287 1.11446683 1 P 0 ;0,1=246,2=0.000000
L 3.17243287 1.11446683 3.17549961 1.1155 1 P 0 ;0,1=246,2=0.000000
L 3.17549961 1.1155 3.17856634 1.11446683 1 P 0 ;0,1=246,2=0.000000
L 3.17856634 1.11446683 3.1812498 1.11188307 1 P 0 ;0,1=246,2=0.000000
L 3.1812498 1.11188307 3.1824002 1.10826624 1 P 0 ;0,1=246,2=0.000000
L 3.1824002 1.10826624 3.18163307 1.10464941 1 P 0 ;0,1=246,2=0.000000
L 3.18163307 1.10464941 3.17971673 1.10206663 1 P 0 ;0,1=246,2=0.000000
L 3.17971673 1.10206663 3.17741654 1.10103356 1 P 0 ;0,1=246,2=0.000000
L 3.17741654 1.10103356 3.17358337 1.10103356 1 P 0 ;0,1=246,2=0.000000
L 3.17358337 1.10103356 3.17013337 1.09948287 1 P 0 ;0,1=246,2=0.000000
L 3.17013337 1.09948287 3.16783317 1.09638268 1 P 0 ;0,1=246,2=0.000000
L 3.16783317 1.09638268 3.16706663 1.09276673 1 P 0 ;0,1=246,2=0.000000
L 3.16706663 1.09276673 3.16783317 1.08914892 1 P 0 ;0,1=246,2=0.000000
L 3.16783317 1.08914892 3.1697501 1.08656614 1 P 0 ;0,1=246,2=0.000000
L 3.1697501 1.08656614 3.17281683 1.08501654 1 P 0 ;0,1=246,2=0.000000
L 3.17281683 1.08501654 3.17549961 1.0845 1 P 0 ;0,1=246,2=0.000000
L 3.20573307 1.0845 3.20649961 1.09121614 1 P 0 ;0,1=246,2=0.000000
L 3.20649961 1.09121614 3.2076501 1.09689921 1 P 0 ;0,1=246,2=0.000000
L 3.2076501 1.09689921 3.20918307 1.10206663 1 P 0 ;0,1=246,2=0.000000
L 3.20918307 1.10206663 3.2111 1.1077497 1 P 0 ;0,1=246,2=0.000000
L 3.2111 1.1077497 3.21416673 1.1155 1 P 0 ;0,1=246,2=0.000000
L 3.21416673 1.1155 3.19883317 1.1155 1 P 0 ;0,1=246,2=0.000000
L 2.931 0.643 2.931 0.599 1 P 0 
L 3.021 0.643 2.931 0.643 1 P 0 
L 2.931 0.599 3.021 0.599 1 P 0 
L 3.021 0.599 3.021 0.643 1 P 0 
L 2.95133317 0.7245 2.95133317 0.7555 1 P 0 ;0,1=247,2=0.000000
L 2.95133317 0.7555 2.96091654 0.7555 1 P 0 ;0,1=247,2=0.000000
L 2.96091654 0.7555 2.96398327 0.75394931 1 P 0 ;0,1=247,2=0.000000
L 2.96398327 0.75394931 2.9659002 0.75188307 1 P 0 ;0,1=247,2=0.000000
L 2.9659002 0.75188307 2.96666673 0.7477497 1 P 0 ;0,1=247,2=0.000000
L 2.96666673 0.7477497 2.9659002 0.74361634 1 P 0 ;0,1=247,2=0.000000
L 2.9659002 0.74361634 2.9636 0.74103356 1 P 0 ;0,1=247,2=0.000000
L 2.9636 0.74103356 2.96091654 0.73948287 1 P 0 ;0,1=247,2=0.000000
L 2.96091654 0.73948287 2.95133317 0.73948287 1 P 0 ;0,1=247,2=0.000000
L 2.96091654 0.73948287 2.96666673 0.7245 1 P 0 ;0,1=247,2=0.000000
L 2.98271644 0.73741575 2.9853999 0.74103356 1 P 0 ;0,1=247,2=0.000000
L 2.9853999 0.74103356 2.9877001 0.7430998 1 P 0 ;0,1=247,2=0.000000
L 2.9877001 0.7430998 2.99076683 0.74413287 1 P 0 ;0,1=247,2=0.000000
L 2.99076683 0.74413287 2.9934503 0.7430998 1 P 0 ;0,1=247,2=0.000000
L 2.9934503 0.7430998 2.99536654 0.74103356 1 P 0 ;0,1=247,2=0.000000
L 2.99536654 0.74103356 2.9969002 0.73793327 1 P 0 ;0,1=247,2=0.000000
L 2.9969002 0.73793327 2.99728346 0.73431644 1 P 0 ;0,1=247,2=0.000000
L 2.99728346 0.73431644 2.9969002 0.73121614 1 P 0 ;0,1=247,2=0.000000
L 2.9969002 0.73121614 2.99536654 0.72811585 1 P 0 ;0,1=247,2=0.000000
L 2.99536654 0.72811585 2.99306634 0.72553307 1 P 0 ;0,1=247,2=0.000000
L 2.99306634 0.72553307 2.99038356 0.7245 1 P 0 ;0,1=247,2=0.000000
L 2.99038356 0.7245 2.98731683 0.72553307 1 P 0 ;0,1=247,2=0.000000
L 2.98731683 0.72553307 2.98463337 0.72863238 1 P 0 ;0,1=247,2=0.000000
L 2.98463337 0.72863238 2.9830997 0.73328327 1 P 0 ;0,1=247,2=0.000000
L 2.9830997 0.73328327 2.98271644 0.7384498 1 P 0 ;0,1=247,2=0.000000
L 2.98271644 0.7384498 2.98348287 0.74516594 1 P 0 ;0,1=247,2=0.000000
L 2.98348287 0.74516594 2.98463337 0.74878376 1 P 0 ;0,1=247,2=0.000000
L 2.98463337 0.74878376 2.98654961 0.7523997 1 P 0 ;0,1=247,2=0.000000
L 2.98654961 0.7523997 2.98923307 0.75498337 1 P 0 ;0,1=247,2=0.000000
L 2.98923307 0.75498337 2.99191654 0.7555 1 P 0 ;0,1=247,2=0.000000
L 2.99191654 0.7555 2.9946 0.75446683 1 P 0 ;0,1=247,2=0.000000
L 2.9946 0.75446683 2.99651703 0.75188307 1 P 0 ;0,1=247,2=0.000000
L 3.01256663 0.73069961 3.01486614 0.72708278 1 P 0 ;0,1=247,2=0.000000
L 3.01486614 0.72708278 3.01793287 0.72501654 1 P 0 ;0,1=247,2=0.000000
L 3.01793287 0.72501654 3.02138356 0.7245 1 P 0 ;0,1=247,2=0.000000
L 3.02138356 0.7245 3.0244503 0.72501654 1 P 0 ;0,1=247,2=0.000000
L 3.0244503 0.72501654 3.02751703 0.72759931 1 P 0 ;0,1=247,2=0.000000
L 3.02751703 0.72759931 3.02943327 0.73069961 1 P 0 ;0,1=247,2=0.000000
L 3.02943327 0.73069961 3.02981654 0.7337999 1 P 0 ;0,1=247,2=0.000000
L 3.02981654 0.7337999 3.02905 0.73741575 1 P 0 ;0,1=247,2=0.000000
L 3.02905 0.73741575 3.02636654 0.73999951 1 P 0 ;0,1=247,2=0.000000
L 3.02636654 0.73999951 3.02368307 0.74103356 1 P 0 ;0,1=247,2=0.000000
L 3.02368307 0.74103356 3.02023307 0.74103356 1 P 0 ;0,1=247,2=0.000000
L 3.02368307 0.74103356 3.02598327 0.74258317 1 P 0 ;0,1=247,2=0.000000
L 3.02598327 0.74258317 3.0279002 0.74516594 1 P 0 ;0,1=247,2=0.000000
L 3.0279002 0.74516594 3.02866673 0.74826624 1 P 0 ;0,1=247,2=0.000000
L 3.02866673 0.74826624 3.0279002 0.75136654 1 P 0 ;0,1=247,2=0.000000
L 3.0279002 0.75136654 3.02598327 0.75394931 1 P 0 ;0,1=247,2=0.000000
L 3.02598327 0.75394931 3.02253327 0.7555 1 P 0 ;0,1=247,2=0.000000
L 3.02253327 0.7555 3.01908337 0.75498337 1 P 0 ;0,1=247,2=0.000000
L 3.01908337 0.75498337 3.01563337 0.75291624 1 P 0 ;0,1=247,2=0.000000
L 2.93 0.59641004 2.93 0.55241004 1 P 0 
L 2.93 0.55241004 3.02 0.55241004 1 P 0 
L 3.02 0.59641004 2.93 0.59641004 1 P 0 
L 3.02 0.55241004 3.02 0.59641004 1 P 0 
L 2.94133317 0.5095 2.94133317 0.5405 1 P 0 ;0,1=248,2=0.000000
L 2.94133317 0.5405 2.95091654 0.5405 1 P 0 ;0,1=248,2=0.000000
L 2.95091654 0.5405 2.95398327 0.53894931 1 P 0 ;0,1=248,2=0.000000
L 2.95398327 0.53894931 2.9559002 0.53688307 1 P 0 ;0,1=248,2=0.000000
L 2.9559002 0.53688307 2.95666673 0.5327497 1 P 0 ;0,1=248,2=0.000000
L 2.95666673 0.5327497 2.9559002 0.52861634 1 P 0 ;0,1=248,2=0.000000
L 2.9559002 0.52861634 2.9536 0.52603356 1 P 0 ;0,1=248,2=0.000000
L 2.9536 0.52603356 2.95091654 0.52448287 1 P 0 ;0,1=248,2=0.000000
L 2.95091654 0.52448287 2.94133317 0.52448287 1 P 0 ;0,1=248,2=0.000000
L 2.95091654 0.52448287 2.95666673 0.5095 1 P 0 ;0,1=248,2=0.000000
L 2.97156663 0.51414892 2.97386614 0.51156614 1 P 0 ;0,1=248,2=0.000000
L 2.97386614 0.51156614 2.97654961 0.51001654 1 P 0 ;0,1=248,2=0.000000
L 2.97654961 0.51001654 2.97999961 0.5095 1 P 0 ;0,1=248,2=0.000000
L 2.97999961 0.5095 2.9834503 0.51053307 1 P 0 ;0,1=248,2=0.000000
L 2.9834503 0.51053307 2.98613307 0.51259931 1 P 0 ;0,1=248,2=0.000000
L 2.98613307 0.51259931 2.98805 0.51621614 1 P 0 ;0,1=248,2=0.000000
L 2.98805 0.51621614 2.98843327 0.52034951 1 P 0 ;0,1=248,2=0.000000
L 2.98843327 0.52034951 2.98766673 0.52448287 1 P 0 ;0,1=248,2=0.000000
L 2.98766673 0.52448287 2.9857498 0.52706663 1 P 0 ;0,1=248,2=0.000000
L 2.9857498 0.52706663 2.98306634 0.52913287 1 P 0 ;0,1=248,2=0.000000
L 2.98306634 0.52913287 2.98038356 0.52964941 1 P 0 ;0,1=248,2=0.000000
L 2.98038356 0.52964941 2.9777001 0.52913287 1 P 0 ;0,1=248,2=0.000000
L 2.9777001 0.52913287 2.9742501 0.52706663 1 P 0 ;0,1=248,2=0.000000
L 2.9742501 0.52706663 2.9753999 0.5405 1 P 0 ;0,1=248,2=0.000000
L 2.9753999 0.5405 2.9857498 0.5405 1 P 0 ;0,1=248,2=0.000000
L 3.01023307 0.5095 3.01099961 0.51621614 1 P 0 ;0,1=248,2=0.000000
L 3.01099961 0.51621614 3.0121501 0.52189921 1 P 0 ;0,1=248,2=0.000000
L 3.0121501 0.52189921 3.01368307 0.52706663 1 P 0 ;0,1=248,2=0.000000
L 3.01368307 0.52706663 3.0156 0.5327497 1 P 0 ;0,1=248,2=0.000000
L 3.0156 0.5327497 3.01866673 0.5405 1 P 0 ;0,1=248,2=0.000000
L 3.01866673 0.5405 3.00333317 0.5405 1 P 0 ;0,1=248,2=0.000000
L 2.571 0.633 2.661 0.633 1 P 0 
L 2.571 0.677 2.571 0.633 1 P 0 
L 2.661 0.677 2.571 0.677 1 P 0 
L 2.661 0.633 2.661 0.677 1 P 0 
L 2.61633317 0.6895 2.61633317 0.7205 1 P 0 ;0,1=249,2=0.000000
L 2.61633317 0.7205 2.62591654 0.7205 1 P 0 ;0,1=249,2=0.000000
L 2.62591654 0.7205 2.62898327 0.71894931 1 P 0 ;0,1=249,2=0.000000
L 2.62898327 0.71894931 2.6309002 0.71688307 1 P 0 ;0,1=249,2=0.000000
L 2.6309002 0.71688307 2.63166673 0.7127497 1 P 0 ;0,1=249,2=0.000000
L 2.63166673 0.7127497 2.6309002 0.70861634 1 P 0 ;0,1=249,2=0.000000
L 2.6309002 0.70861634 2.6286 0.70603356 1 P 0 ;0,1=249,2=0.000000
L 2.6286 0.70603356 2.62591654 0.70448287 1 P 0 ;0,1=249,2=0.000000
L 2.62591654 0.70448287 2.61633317 0.70448287 1 P 0 ;0,1=249,2=0.000000
L 2.62591654 0.70448287 2.63166673 0.6895 1 P 0 ;0,1=249,2=0.000000
L 2.64656663 0.69414892 2.64886614 0.69156614 1 P 0 ;0,1=249,2=0.000000
L 2.64886614 0.69156614 2.65154961 0.69001654 1 P 0 ;0,1=249,2=0.000000
L 2.65154961 0.69001654 2.65499961 0.6895 1 P 0 ;0,1=249,2=0.000000
L 2.65499961 0.6895 2.6584503 0.69053307 1 P 0 ;0,1=249,2=0.000000
L 2.6584503 0.69053307 2.66113307 0.69259931 1 P 0 ;0,1=249,2=0.000000
L 2.66113307 0.69259931 2.66305 0.69621614 1 P 0 ;0,1=249,2=0.000000
L 2.66305 0.69621614 2.66343327 0.70034951 1 P 0 ;0,1=249,2=0.000000
L 2.66343327 0.70034951 2.66266673 0.70448287 1 P 0 ;0,1=249,2=0.000000
L 2.66266673 0.70448287 2.6607498 0.70706663 1 P 0 ;0,1=249,2=0.000000
L 2.6607498 0.70706663 2.65806634 0.70913287 1 P 0 ;0,1=249,2=0.000000
L 2.65806634 0.70913287 2.65538356 0.70964941 1 P 0 ;0,1=249,2=0.000000
L 2.65538356 0.70964941 2.6527001 0.70913287 1 P 0 ;0,1=249,2=0.000000
L 2.6527001 0.70913287 2.6492501 0.70706663 1 P 0 ;0,1=249,2=0.000000
L 2.6492501 0.70706663 2.6503999 0.7205 1 P 0 ;0,1=249,2=0.000000
L 2.6503999 0.7205 2.6607498 0.7205 1 P 0 ;0,1=249,2=0.000000
L 2.67756663 0.69414892 2.67986614 0.69156614 1 P 0 ;0,1=249,2=0.000000
L 2.67986614 0.69156614 2.68254961 0.69001654 1 P 0 ;0,1=249,2=0.000000
L 2.68254961 0.69001654 2.68599961 0.6895 1 P 0 ;0,1=249,2=0.000000
L 2.68599961 0.6895 2.6894503 0.69053307 1 P 0 ;0,1=249,2=0.000000
L 2.6894503 0.69053307 2.69213307 0.69259931 1 P 0 ;0,1=249,2=0.000000
L 2.69213307 0.69259931 2.69405 0.69621614 1 P 0 ;0,1=249,2=0.000000
L 2.69405 0.69621614 2.69443327 0.70034951 1 P 0 ;0,1=249,2=0.000000
L 2.69443327 0.70034951 2.69366673 0.70448287 1 P 0 ;0,1=249,2=0.000000
L 2.69366673 0.70448287 2.6917498 0.70706663 1 P 0 ;0,1=249,2=0.000000
L 2.6917498 0.70706663 2.68906634 0.70913287 1 P 0 ;0,1=249,2=0.000000
L 2.68906634 0.70913287 2.68638356 0.70964941 1 P 0 ;0,1=249,2=0.000000
L 2.68638356 0.70964941 2.6837001 0.70913287 1 P 0 ;0,1=249,2=0.000000
L 2.6837001 0.70913287 2.6802501 0.70706663 1 P 0 ;0,1=249,2=0.000000
L 2.6802501 0.70706663 2.6813999 0.7205 1 P 0 ;0,1=249,2=0.000000
L 2.6813999 0.7205 2.6917498 0.7205 1 P 0 ;0,1=249,2=0.000000
L 2.571 0.627 2.571 0.583 1 P 0 
L 2.661 0.627 2.571 0.627 1 P 0 
L 2.571 0.583 2.661 0.583 1 P 0 
L 2.661 0.583 2.661 0.627 1 P 0 
L 2.57633317 0.5045 2.57633317 0.5355 1 P 0 ;0,1=250,2=0.000000
L 2.57633317 0.5355 2.58591654 0.5355 1 P 0 ;0,1=250,2=0.000000
L 2.58591654 0.5355 2.58898327 0.53394931 1 P 0 ;0,1=250,2=0.000000
L 2.58898327 0.53394931 2.5909002 0.53188307 1 P 0 ;0,1=250,2=0.000000
L 2.5909002 0.53188307 2.59166673 0.5277497 1 P 0 ;0,1=250,2=0.000000
L 2.59166673 0.5277497 2.5909002 0.52361634 1 P 0 ;0,1=250,2=0.000000
L 2.5909002 0.52361634 2.5886 0.52103356 1 P 0 ;0,1=250,2=0.000000
L 2.5886 0.52103356 2.58591654 0.51948287 1 P 0 ;0,1=250,2=0.000000
L 2.58591654 0.51948287 2.57633317 0.51948287 1 P 0 ;0,1=250,2=0.000000
L 2.58591654 0.51948287 2.59166673 0.5045 1 P 0 ;0,1=250,2=0.000000
L 2.60656663 0.50914892 2.60886614 0.50656614 1 P 0 ;0,1=250,2=0.000000
L 2.60886614 0.50656614 2.61154961 0.50501654 1 P 0 ;0,1=250,2=0.000000
L 2.61154961 0.50501654 2.61499961 0.5045 1 P 0 ;0,1=250,2=0.000000
L 2.61499961 0.5045 2.6184503 0.50553307 1 P 0 ;0,1=250,2=0.000000
L 2.6184503 0.50553307 2.62113307 0.50759931 1 P 0 ;0,1=250,2=0.000000
L 2.62113307 0.50759931 2.62305 0.51121614 1 P 0 ;0,1=250,2=0.000000
L 2.62305 0.51121614 2.62343327 0.51534951 1 P 0 ;0,1=250,2=0.000000
L 2.62343327 0.51534951 2.62266673 0.51948287 1 P 0 ;0,1=250,2=0.000000
L 2.62266673 0.51948287 2.6207498 0.52206663 1 P 0 ;0,1=250,2=0.000000
L 2.6207498 0.52206663 2.61806634 0.52413287 1 P 0 ;0,1=250,2=0.000000
L 2.61806634 0.52413287 2.61538356 0.52464941 1 P 0 ;0,1=250,2=0.000000
L 2.61538356 0.52464941 2.6127001 0.52413287 1 P 0 ;0,1=250,2=0.000000
L 2.6127001 0.52413287 2.6092501 0.52206663 1 P 0 ;0,1=250,2=0.000000
L 2.6092501 0.52206663 2.6103999 0.5355 1 P 0 ;0,1=250,2=0.000000
L 2.6103999 0.5355 2.6207498 0.5355 1 P 0 ;0,1=250,2=0.000000
L 2.63871644 0.51741575 2.6413999 0.52103356 1 P 0 ;0,1=250,2=0.000000
L 2.6413999 0.52103356 2.6437001 0.5230998 1 P 0 ;0,1=250,2=0.000000
L 2.6437001 0.5230998 2.64676683 0.52413287 1 P 0 ;0,1=250,2=0.000000
L 2.64676683 0.52413287 2.6494503 0.5230998 1 P 0 ;0,1=250,2=0.000000
L 2.6494503 0.5230998 2.65136654 0.52103356 1 P 0 ;0,1=250,2=0.000000
L 2.65136654 0.52103356 2.6529002 0.51793327 1 P 0 ;0,1=250,2=0.000000
L 2.6529002 0.51793327 2.65328346 0.51431644 1 P 0 ;0,1=250,2=0.000000
L 2.65328346 0.51431644 2.6529002 0.51121614 1 P 0 ;0,1=250,2=0.000000
L 2.6529002 0.51121614 2.65136654 0.50811585 1 P 0 ;0,1=250,2=0.000000
L 2.65136654 0.50811585 2.64906634 0.50553307 1 P 0 ;0,1=250,2=0.000000
L 2.64906634 0.50553307 2.64638356 0.5045 1 P 0 ;0,1=250,2=0.000000
L 2.64638356 0.5045 2.64331683 0.50553307 1 P 0 ;0,1=250,2=0.000000
L 2.64331683 0.50553307 2.64063337 0.50863238 1 P 0 ;0,1=250,2=0.000000
L 2.64063337 0.50863238 2.6390997 0.51328327 1 P 0 ;0,1=250,2=0.000000
L 2.6390997 0.51328327 2.63871644 0.5184498 1 P 0 ;0,1=250,2=0.000000
L 2.63871644 0.5184498 2.63948287 0.52516594 1 P 0 ;0,1=250,2=0.000000
L 2.63948287 0.52516594 2.64063337 0.52878376 1 P 0 ;0,1=250,2=0.000000
L 2.64063337 0.52878376 2.64254961 0.5323997 1 P 0 ;0,1=250,2=0.000000
L 2.64254961 0.5323997 2.64523307 0.53498337 1 P 0 ;0,1=250,2=0.000000
L 2.64523307 0.53498337 2.64791654 0.5355 1 P 0 ;0,1=250,2=0.000000
L 2.64791654 0.5355 2.6506 0.53446683 1 P 0 ;0,1=250,2=0.000000
L 2.6506 0.53446683 2.65251703 0.53188307 1 P 0 ;0,1=250,2=0.000000
L 2.53321998 0.56 2.53321998 0.65 1 P 0 
L 2.48921998 0.56 2.53321998 0.56 1 P 0 
L 2.48921998 0.65 2.48921998 0.56 1 P 0 
L 2.53321998 0.65 2.48921998 0.65 1 P 0 
L 2.5267 0.66133317 2.4957 0.66133317 1 P 0 ;0,1=251,2=270.000000
L 2.4957 0.66133317 2.4957 0.67091654 1 P 0 ;0,1=251,2=270.000000
L 2.4957 0.67091654 2.49725069 0.67398327 1 P 0 ;0,1=251,2=270.000000
L 2.49725069 0.67398327 2.49931693 0.6759002 1 P 0 ;0,1=251,2=270.000000
L 2.49931693 0.6759002 2.5034503 0.67666673 1 P 0 ;0,1=251,2=270.000000
L 2.5034503 0.67666673 2.50758366 0.6759002 1 P 0 ;0,1=251,2=270.000000
L 2.50758366 0.6759002 2.51016644 0.6736 1 P 0 ;0,1=251,2=270.000000
L 2.51016644 0.6736 2.51171713 0.67091654 1 P 0 ;0,1=251,2=270.000000
L 2.51171713 0.67091654 2.51171713 0.66133317 1 P 0 ;0,1=251,2=270.000000
L 2.51171713 0.67091654 2.5267 0.67666673 1 P 0 ;0,1=251,2=270.000000
L 2.50086654 0.69271644 2.49776722 0.69501663 1 P 0 ;0,1=251,2=270.000000
L 2.49776722 0.69501663 2.49621663 0.6977001 1 P 0 ;0,1=251,2=270.000000
L 2.49621663 0.6977001 2.4957 0.70076683 1 P 0 ;0,1=251,2=270.000000
L 2.4957 0.70076683 2.49673317 0.7046 1 P 0 ;0,1=251,2=270.000000
L 2.49673317 0.7046 2.49931693 0.70728346 1 P 0 ;0,1=251,2=270.000000
L 2.49931693 0.70728346 2.50241624 0.70805 1 P 0 ;0,1=251,2=270.000000
L 2.50241624 0.70805 2.50551742 0.70766673 1 P 0 ;0,1=251,2=270.000000
L 2.50551742 0.70766673 2.5081002 0.70613307 1 P 0 ;0,1=251,2=270.000000
L 2.5081002 0.70613307 2.51326673 0.69846663 1 P 0 ;0,1=251,2=270.000000
L 2.51326673 0.69846663 2.51688356 0.69501663 1 P 0 ;0,1=251,2=270.000000
L 2.51688356 0.69501663 2.52205108 0.69271644 1 P 0 ;0,1=251,2=270.000000
L 2.52205108 0.69271644 2.5267 0.6919499 1 P 0 ;0,1=251,2=270.000000
L 2.5267 0.6919499 2.5267 0.70805 1 P 0 ;0,1=251,2=270.000000
L 2.50086654 0.72371644 2.49776722 0.72601663 1 P 0 ;0,1=251,2=270.000000
L 2.49776722 0.72601663 2.49621663 0.7287001 1 P 0 ;0,1=251,2=270.000000
L 2.49621663 0.7287001 2.4957 0.73176683 1 P 0 ;0,1=251,2=270.000000
L 2.4957 0.73176683 2.49673317 0.7356 1 P 0 ;0,1=251,2=270.000000
L 2.49673317 0.7356 2.49931693 0.73828346 1 P 0 ;0,1=251,2=270.000000
L 2.49931693 0.73828346 2.50241624 0.73905 1 P 0 ;0,1=251,2=270.000000
L 2.50241624 0.73905 2.50551742 0.73866673 1 P 0 ;0,1=251,2=270.000000
L 2.50551742 0.73866673 2.5081002 0.73713307 1 P 0 ;0,1=251,2=270.000000
L 2.5081002 0.73713307 2.51326673 0.72946663 1 P 0 ;0,1=251,2=270.000000
L 2.51326673 0.72946663 2.51688356 0.72601663 1 P 0 ;0,1=251,2=270.000000
L 2.51688356 0.72601663 2.52205108 0.72371644 1 P 0 ;0,1=251,2=270.000000
L 2.52205108 0.72371644 2.5267 0.7229499 1 P 0 ;0,1=251,2=270.000000
L 2.5267 0.7229499 2.5267 0.73905 1 P 0 ;0,1=251,2=270.000000
L 2.0697 0.566 2.0697 0.656 1 P 0 
L 2.0257 0.566 2.0697 0.566 1 P 0 
L 2.0257 0.656 2.0257 0.566 1 P 0 
L 2.0697 0.656 2.0257 0.656 1 P 0 
L 2.0705 0.69133317 2.0395 0.69133317 1 P 0 ;0,1=252,2=270.000000
L 2.0395 0.69133317 2.0395 0.70091654 1 P 0 ;0,1=252,2=270.000000
L 2.0395 0.70091654 2.04105069 0.70398327 1 P 0 ;0,1=252,2=270.000000
L 2.04105069 0.70398327 2.04311693 0.7059002 1 P 0 ;0,1=252,2=270.000000
L 2.04311693 0.7059002 2.0472503 0.70666673 1 P 0 ;0,1=252,2=270.000000
L 2.0472503 0.70666673 2.05138366 0.7059002 1 P 0 ;0,1=252,2=270.000000
L 2.05138366 0.7059002 2.05396644 0.7036 1 P 0 ;0,1=252,2=270.000000
L 2.05396644 0.7036 2.05551713 0.70091654 1 P 0 ;0,1=252,2=270.000000
L 2.05551713 0.70091654 2.05551713 0.69133317 1 P 0 ;0,1=252,2=270.000000
L 2.05551713 0.70091654 2.0705 0.70666673 1 P 0 ;0,1=252,2=270.000000
L 2.04466654 0.72271644 2.04156722 0.72501663 1 P 0 ;0,1=252,2=270.000000
L 2.04156722 0.72501663 2.04001663 0.7277001 1 P 0 ;0,1=252,2=270.000000
L 2.04001663 0.7277001 2.0395 0.73076683 1 P 0 ;0,1=252,2=270.000000
L 2.0395 0.73076683 2.04053317 0.7346 1 P 0 ;0,1=252,2=270.000000
L 2.04053317 0.7346 2.04311693 0.73728346 1 P 0 ;0,1=252,2=270.000000
L 2.04311693 0.73728346 2.04621624 0.73805 1 P 0 ;0,1=252,2=270.000000
L 2.04621624 0.73805 2.04931742 0.73766673 1 P 0 ;0,1=252,2=270.000000
L 2.04931742 0.73766673 2.0519002 0.73613307 1 P 0 ;0,1=252,2=270.000000
L 2.0519002 0.73613307 2.05706673 0.72846663 1 P 0 ;0,1=252,2=270.000000
L 2.05706673 0.72846663 2.06068356 0.72501663 1 P 0 ;0,1=252,2=270.000000
L 2.06068356 0.72501663 2.06585108 0.72271644 1 P 0 ;0,1=252,2=270.000000
L 2.06585108 0.72271644 2.0705 0.7219499 1 P 0 ;0,1=252,2=270.000000
L 2.0705 0.7219499 2.0705 0.73805 1 P 0 ;0,1=252,2=270.000000
L 2.06585108 0.75256663 2.06843386 0.75486614 1 P 0 ;0,1=252,2=270.000000
L 2.06843386 0.75486614 2.06998346 0.75754961 1 P 0 ;0,1=252,2=270.000000
L 2.06998346 0.75754961 2.0705 0.76099961 1 P 0 ;0,1=252,2=270.000000
L 2.0705 0.76099961 2.06946693 0.7644503 1 P 0 ;0,1=252,2=270.000000
L 2.06946693 0.7644503 2.06740069 0.76713307 1 P 0 ;0,1=252,2=270.000000
L 2.06740069 0.76713307 2.06378386 0.76905 1 P 0 ;0,1=252,2=270.000000
L 2.06378386 0.76905 2.05965049 0.76943327 1 P 0 ;0,1=252,2=270.000000
L 2.05965049 0.76943327 2.05551713 0.76866673 1 P 0 ;0,1=252,2=270.000000
L 2.05551713 0.76866673 2.05293337 0.7667498 1 P 0 ;0,1=252,2=270.000000
L 2.05293337 0.7667498 2.05086713 0.76406634 1 P 0 ;0,1=252,2=270.000000
L 2.05086713 0.76406634 2.05035059 0.76138356 1 P 0 ;0,1=252,2=270.000000
L 2.05035059 0.76138356 2.05086713 0.7587001 1 P 0 ;0,1=252,2=270.000000
L 2.05086713 0.7587001 2.05293337 0.7552501 1 P 0 ;0,1=252,2=270.000000
L 2.05293337 0.7552501 2.0395 0.7563999 1 P 0 ;0,1=252,2=270.000000
L 2.0395 0.7563999 2.0395 0.7667498 1 P 0 ;0,1=252,2=270.000000
L 1.9757 0.656 1.9757 0.566 1 P 0 
L 1.9757 0.566 2.0197 0.566 1 P 0 
L 2.0197 0.566 2.0197 0.656 1 P 0 
L 2.0197 0.656 1.9757 0.656 1 P 0 
L 2.0155 0.69083317 1.9845 0.69083317 1 P 0 ;0,1=253,2=270.000000
L 1.9845 0.69083317 1.9845 0.70041654 1 P 0 ;0,1=253,2=270.000000
L 1.9845 0.70041654 1.98605069 0.70348327 1 P 0 ;0,1=253,2=270.000000
L 1.98605069 0.70348327 1.98811693 0.7054002 1 P 0 ;0,1=253,2=270.000000
L 1.98811693 0.7054002 1.9922503 0.70616673 1 P 0 ;0,1=253,2=270.000000
L 1.9922503 0.70616673 1.99638366 0.7054002 1 P 0 ;0,1=253,2=270.000000
L 1.99638366 0.7054002 1.99896644 0.7031 1 P 0 ;0,1=253,2=270.000000
L 1.99896644 0.7031 2.00051713 0.70041654 1 P 0 ;0,1=253,2=270.000000
L 2.00051713 0.70041654 2.00051713 0.69083317 1 P 0 ;0,1=253,2=270.000000
L 2.00051713 0.70041654 2.0155 0.70616673 1 P 0 ;0,1=253,2=270.000000
L 2.00930039 0.72106663 2.01291722 0.72336614 1 P 0 ;0,1=253,2=270.000000
L 2.01291722 0.72336614 2.01498346 0.72643287 1 P 0 ;0,1=253,2=270.000000
L 2.01498346 0.72643287 2.0155 0.72988356 1 P 0 ;0,1=253,2=270.000000
L 2.0155 0.72988356 2.01498346 0.7329503 1 P 0 ;0,1=253,2=270.000000
L 2.01498346 0.7329503 2.01240069 0.73601703 1 P 0 ;0,1=253,2=270.000000
L 2.01240069 0.73601703 2.00930039 0.73793327 1 P 0 ;0,1=253,2=270.000000
L 2.00930039 0.73793327 2.0062001 0.73831654 1 P 0 ;0,1=253,2=270.000000
L 2.0062001 0.73831654 2.00258425 0.73755 1 P 0 ;0,1=253,2=270.000000
L 2.00258425 0.73755 2.00000049 0.73486654 1 P 0 ;0,1=253,2=270.000000
L 2.00000049 0.73486654 1.99896644 0.73218307 1 P 0 ;0,1=253,2=270.000000
L 1.99896644 0.73218307 1.99896644 0.72873307 1 P 0 ;0,1=253,2=270.000000
L 1.99896644 0.73218307 1.99741683 0.73448327 1 P 0 ;0,1=253,2=270.000000
L 1.99741683 0.73448327 1.99483406 0.7364002 1 P 0 ;0,1=253,2=270.000000
L 1.99483406 0.7364002 1.99173376 0.73716673 1 P 0 ;0,1=253,2=270.000000
L 1.99173376 0.73716673 1.98863346 0.7364002 1 P 0 ;0,1=253,2=270.000000
L 1.98863346 0.7364002 1.98605069 0.73448327 1 P 0 ;0,1=253,2=270.000000
L 1.98605069 0.73448327 1.9845 0.73103327 1 P 0 ;0,1=253,2=270.000000
L 1.9845 0.73103327 1.98501663 0.72758337 1 P 0 ;0,1=253,2=270.000000
L 1.98501663 0.72758337 1.98708376 0.72413337 1 P 0 ;0,1=253,2=270.000000
L 2.01085108 0.75206663 2.01343386 0.75436614 1 P 0 ;0,1=253,2=270.000000
L 2.01343386 0.75436614 2.01498346 0.75704961 1 P 0 ;0,1=253,2=270.000000
L 2.01498346 0.75704961 2.0155 0.76049961 1 P 0 ;0,1=253,2=270.000000
L 2.0155 0.76049961 2.01446693 0.7639503 1 P 0 ;0,1=253,2=270.000000
L 2.01446693 0.7639503 2.01240069 0.76663307 1 P 0 ;0,1=253,2=270.000000
L 2.01240069 0.76663307 2.00878386 0.76855 1 P 0 ;0,1=253,2=270.000000
L 2.00878386 0.76855 2.00465049 0.76893327 1 P 0 ;0,1=253,2=270.000000
L 2.00465049 0.76893327 2.00051713 0.76816673 1 P 0 ;0,1=253,2=270.000000
L 2.00051713 0.76816673 1.99793337 0.7662498 1 P 0 ;0,1=253,2=270.000000
L 1.99793337 0.7662498 1.99586713 0.76356634 1 P 0 ;0,1=253,2=270.000000
L 1.99586713 0.76356634 1.99535059 0.76088356 1 P 0 ;0,1=253,2=270.000000
L 1.99535059 0.76088356 1.99586713 0.7582001 1 P 0 ;0,1=253,2=270.000000
L 1.99586713 0.7582001 1.99793337 0.7547501 1 P 0 ;0,1=253,2=270.000000
L 1.99793337 0.7547501 1.9845 0.7558999 1 P 0 ;0,1=253,2=270.000000
L 1.9845 0.7558999 1.9845 0.7662498 1 P 0 ;0,1=253,2=270.000000
L 2.0155 0.7961 1.9845 0.7961 1 P 0 ;0,1=253,2=270.000000
L 1.9845 0.7961 2.00671673 0.78191624 1 P 0 ;0,1=253,2=270.000000
L 2.00671673 0.78191624 2.00671673 0.80108366 1 P 0 ;0,1=253,2=270.000000
L 3.626 1.72148996 3.626 1.81148996 1 P 0 
L 3.582 1.72148996 3.626 1.72148996 1 P 0 
L 3.582 1.81148996 3.582 1.72148996 1 P 0 
L 3.626 1.81148996 3.582 1.81148996 1 P 0 
L 3.675 1.73583317 3.644 1.73583317 1 P 0 ;0,1=254,2=270.000000
L 3.644 1.73583317 3.644 1.74541654 1 P 0 ;0,1=254,2=270.000000
L 3.644 1.74541654 3.64555069 1.74848327 1 P 0 ;0,1=254,2=270.000000
L 3.64555069 1.74848327 3.64761693 1.7504002 1 P 0 ;0,1=254,2=270.000000
L 3.64761693 1.7504002 3.6517503 1.75116673 1 P 0 ;0,1=254,2=270.000000
L 3.6517503 1.75116673 3.65588366 1.7504002 1 P 0 ;0,1=254,2=270.000000
L 3.65588366 1.7504002 3.65846644 1.7481 1 P 0 ;0,1=254,2=270.000000
L 3.65846644 1.7481 3.66001713 1.74541654 1 P 0 ;0,1=254,2=270.000000
L 3.66001713 1.74541654 3.66001713 1.73583317 1 P 0 ;0,1=254,2=270.000000
L 3.66001713 1.74541654 3.675 1.75116673 1 P 0 ;0,1=254,2=270.000000
L 3.675 1.77449961 3.644 1.77449961 1 P 0 ;0,1=254,2=270.000000
L 3.644 1.77449961 3.6501997 1.7698999 1 P 0 ;0,1=254,2=270.000000
L 3.675 1.7698999 3.675 1.77909931 1 P 0 ;0,1=254,2=270.000000
L 3.644 1.80549961 3.64503317 1.80243287 1 P 0 ;0,1=254,2=270.000000
L 3.64503317 1.80243287 3.64761693 1.80013337 1 P 0 ;0,1=254,2=270.000000
L 3.64761693 1.80013337 3.65071624 1.7985997 1 P 0 ;0,1=254,2=270.000000
L 3.65071624 1.7985997 3.65485059 1.7974499 1 P 0 ;0,1=254,2=270.000000
L 3.65485059 1.7974499 3.65950049 1.79706663 1 P 0 ;0,1=254,2=270.000000
L 3.65950049 1.79706663 3.66415049 1.7974499 1 P 0 ;0,1=254,2=270.000000
L 3.66415049 1.7974499 3.66828386 1.7985997 1 P 0 ;0,1=254,2=270.000000
L 3.66828386 1.7985997 3.67138415 1.80013337 1 P 0 ;0,1=254,2=270.000000
L 3.67138415 1.80013337 3.67396693 1.80243287 1 P 0 ;0,1=254,2=270.000000
L 3.67396693 1.80243287 3.675 1.80549961 1 P 0 ;0,1=254,2=270.000000
L 3.675 1.80549961 3.67396693 1.80856634 1 P 0 ;0,1=254,2=270.000000
L 3.67396693 1.80856634 3.67138415 1.81086654 1 P 0 ;0,1=254,2=270.000000
L 3.67138415 1.81086654 3.66828386 1.8124002 1 P 0 ;0,1=254,2=270.000000
L 3.66828386 1.8124002 3.66415049 1.81355 1 P 0 ;0,1=254,2=270.000000
L 3.66415049 1.81355 3.65950049 1.81393327 1 P 0 ;0,1=254,2=270.000000
L 3.65950049 1.81393327 3.65485059 1.81355 1 P 0 ;0,1=254,2=270.000000
L 3.65485059 1.81355 3.65071624 1.8124002 1 P 0 ;0,1=254,2=270.000000
L 3.65071624 1.8124002 3.64761693 1.81086654 1 P 0 ;0,1=254,2=270.000000
L 3.64761693 1.81086654 3.64503317 1.80856634 1 P 0 ;0,1=254,2=270.000000
L 3.64503317 1.80856634 3.644 1.80549961 1 P 0 ;0,1=254,2=270.000000
L 3.675 1.8411 3.644 1.8411 1 P 0 ;0,1=254,2=270.000000
L 3.644 1.8411 3.66621673 1.82691624 1 P 0 ;0,1=254,2=270.000000
L 3.66621673 1.82691624 3.66621673 1.84608366 1 P 0 ;0,1=254,2=270.000000
L 3.532 1.72148996 3.576 1.72148996 1 P 0 
L 3.532 1.81148996 3.532 1.72148996 1 P 0 
L 3.576 1.72148996 3.576 1.81148996 1 P 0 
L 3.576 1.81148996 3.532 1.81148996 1 P 0 
L 3.51 1.70583317 3.479 1.70583317 1 P 0 ;0,1=255,2=270.000000
L 3.479 1.70583317 3.479 1.71541654 1 P 0 ;0,1=255,2=270.000000
L 3.479 1.71541654 3.48055069 1.71848327 1 P 0 ;0,1=255,2=270.000000
L 3.48055069 1.71848327 3.48261693 1.7204002 1 P 0 ;0,1=255,2=270.000000
L 3.48261693 1.7204002 3.4867503 1.72116673 1 P 0 ;0,1=255,2=270.000000
L 3.4867503 1.72116673 3.49088366 1.7204002 1 P 0 ;0,1=255,2=270.000000
L 3.49088366 1.7204002 3.49346644 1.7181 1 P 0 ;0,1=255,2=270.000000
L 3.49346644 1.7181 3.49501713 1.71541654 1 P 0 ;0,1=255,2=270.000000
L 3.49501713 1.71541654 3.49501713 1.70583317 1 P 0 ;0,1=255,2=270.000000
L 3.49501713 1.71541654 3.51 1.72116673 1 P 0 ;0,1=255,2=270.000000
L 3.48416654 1.73721644 3.48106722 1.73951663 1 P 0 ;0,1=255,2=270.000000
L 3.48106722 1.73951663 3.47951663 1.7422001 1 P 0 ;0,1=255,2=270.000000
L 3.47951663 1.7422001 3.479 1.74526683 1 P 0 ;0,1=255,2=270.000000
L 3.479 1.74526683 3.48003317 1.7491 1 P 0 ;0,1=255,2=270.000000
L 3.48003317 1.7491 3.48261693 1.75178346 1 P 0 ;0,1=255,2=270.000000
L 3.48261693 1.75178346 3.48571624 1.75255 1 P 0 ;0,1=255,2=270.000000
L 3.48571624 1.75255 3.48881742 1.75216673 1 P 0 ;0,1=255,2=270.000000
L 3.48881742 1.75216673 3.4914002 1.75063307 1 P 0 ;0,1=255,2=270.000000
L 3.4914002 1.75063307 3.49656673 1.74296663 1 P 0 ;0,1=255,2=270.000000
L 3.49656673 1.74296663 3.50018356 1.73951663 1 P 0 ;0,1=255,2=270.000000
L 3.50018356 1.73951663 3.50535108 1.73721644 1 P 0 ;0,1=255,2=270.000000
L 3.50535108 1.73721644 3.51 1.7364499 1 P 0 ;0,1=255,2=270.000000
L 3.51 1.7364499 3.51 1.75255 1 P 0 ;0,1=255,2=270.000000
L 3.49708425 1.76821644 3.49346644 1.7708999 1 P 0 ;0,1=255,2=270.000000
L 3.49346644 1.7708999 3.4914002 1.7732001 1 P 0 ;0,1=255,2=270.000000
L 3.4914002 1.7732001 3.49036713 1.77626683 1 P 0 ;0,1=255,2=270.000000
L 3.49036713 1.77626683 3.4914002 1.7789503 1 P 0 ;0,1=255,2=270.000000
L 3.4914002 1.7789503 3.49346644 1.78086654 1 P 0 ;0,1=255,2=270.000000
L 3.49346644 1.78086654 3.49656673 1.7824002 1 P 0 ;0,1=255,2=270.000000
L 3.49656673 1.7824002 3.50018356 1.78278346 1 P 0 ;0,1=255,2=270.000000
L 3.50018356 1.78278346 3.50328386 1.7824002 1 P 0 ;0,1=255,2=270.000000
L 3.50328386 1.7824002 3.50638415 1.78086654 1 P 0 ;0,1=255,2=270.000000
L 3.50638415 1.78086654 3.50896693 1.77856634 1 P 0 ;0,1=255,2=270.000000
L 3.50896693 1.77856634 3.51 1.77588356 1 P 0 ;0,1=255,2=270.000000
L 3.51 1.77588356 3.50896693 1.77281683 1 P 0 ;0,1=255,2=270.000000
L 3.50896693 1.77281683 3.50586762 1.77013337 1 P 0 ;0,1=255,2=270.000000
L 3.50586762 1.77013337 3.50121673 1.7685997 1 P 0 ;0,1=255,2=270.000000
L 3.50121673 1.7685997 3.4960502 1.76821644 1 P 0 ;0,1=255,2=270.000000
L 3.4960502 1.76821644 3.48933406 1.76898287 1 P 0 ;0,1=255,2=270.000000
L 3.48933406 1.76898287 3.48571624 1.77013337 1 P 0 ;0,1=255,2=270.000000
L 3.48571624 1.77013337 3.4821003 1.77204961 1 P 0 ;0,1=255,2=270.000000
L 3.4821003 1.77204961 3.47951663 1.77473307 1 P 0 ;0,1=255,2=270.000000
L 3.47951663 1.77473307 3.479 1.77741654 1 P 0 ;0,1=255,2=270.000000
L 3.479 1.77741654 3.48003317 1.7801 1 P 0 ;0,1=255,2=270.000000
L 3.48003317 1.7801 3.48261693 1.78201703 1 P 0 ;0,1=255,2=270.000000
L 3.49708425 1.79921644 3.49346644 1.8018999 1 P 0 ;0,1=255,2=270.000000
L 3.49346644 1.8018999 3.4914002 1.8042001 1 P 0 ;0,1=255,2=270.000000
L 3.4914002 1.8042001 3.49036713 1.80726683 1 P 0 ;0,1=255,2=270.000000
L 3.49036713 1.80726683 3.4914002 1.8099503 1 P 0 ;0,1=255,2=270.000000
L 3.4914002 1.8099503 3.49346644 1.81186654 1 P 0 ;0,1=255,2=270.000000
L 3.49346644 1.81186654 3.49656673 1.8134002 1 P 0 ;0,1=255,2=270.000000
L 3.49656673 1.8134002 3.50018356 1.81378346 1 P 0 ;0,1=255,2=270.000000
L 3.50018356 1.81378346 3.50328386 1.8134002 1 P 0 ;0,1=255,2=270.000000
L 3.50328386 1.8134002 3.50638415 1.81186654 1 P 0 ;0,1=255,2=270.000000
L 3.50638415 1.81186654 3.50896693 1.80956634 1 P 0 ;0,1=255,2=270.000000
L 3.50896693 1.80956634 3.51 1.80688356 1 P 0 ;0,1=255,2=270.000000
L 3.51 1.80688356 3.50896693 1.80381683 1 P 0 ;0,1=255,2=270.000000
L 3.50896693 1.80381683 3.50586762 1.80113337 1 P 0 ;0,1=255,2=270.000000
L 3.50586762 1.80113337 3.50121673 1.7995997 1 P 0 ;0,1=255,2=270.000000
L 3.50121673 1.7995997 3.4960502 1.79921644 1 P 0 ;0,1=255,2=270.000000
L 3.4960502 1.79921644 3.48933406 1.79998287 1 P 0 ;0,1=255,2=270.000000
L 3.48933406 1.79998287 3.48571624 1.80113337 1 P 0 ;0,1=255,2=270.000000
L 3.48571624 1.80113337 3.4821003 1.80304961 1 P 0 ;0,1=255,2=270.000000
L 3.4821003 1.80304961 3.47951663 1.80573307 1 P 0 ;0,1=255,2=270.000000
L 3.47951663 1.80573307 3.479 1.80841654 1 P 0 ;0,1=255,2=270.000000
L 3.479 1.80841654 3.48003317 1.8111 1 P 0 ;0,1=255,2=270.000000
L 3.48003317 1.8111 3.48261693 1.81301703 1 P 0 ;0,1=255,2=270.000000
L 3.095 1.872 3.095 1.828 1 P 0 
L 3.185 1.872 3.095 1.872 1 P 0 
L 3.095 1.828 3.185 1.828 1 P 0 
L 3.185 1.828 3.185 1.872 1 P 0 
L 3.10633317 1.2795 3.10633317 1.3105 1 P 0 ;0,1=256,2=0.000000
L 3.10633317 1.3105 3.11591654 1.3105 1 P 0 ;0,1=256,2=0.000000
L 3.11591654 1.3105 3.11898327 1.30894931 1 P 0 ;0,1=256,2=0.000000
L 3.11898327 1.30894931 3.1209002 1.30688307 1 P 0 ;0,1=256,2=0.000000
L 3.1209002 1.30688307 3.12166673 1.3027497 1 P 0 ;0,1=256,2=0.000000
L 3.12166673 1.3027497 3.1209002 1.29861634 1 P 0 ;0,1=256,2=0.000000
L 3.1209002 1.29861634 3.1186 1.29603356 1 P 0 ;0,1=256,2=0.000000
L 3.1186 1.29603356 3.11591654 1.29448287 1 P 0 ;0,1=256,2=0.000000
L 3.11591654 1.29448287 3.10633317 1.29448287 1 P 0 ;0,1=256,2=0.000000
L 3.11591654 1.29448287 3.12166673 1.2795 1 P 0 ;0,1=256,2=0.000000
L 3.13848287 1.28311585 3.14116634 1.28053307 1 P 0 ;0,1=256,2=0.000000
L 3.14116634 1.28053307 3.14423307 1.2795 1 P 0 ;0,1=256,2=0.000000
L 3.14423307 1.2795 3.1472998 1.28053307 1 P 0 ;0,1=256,2=0.000000
L 3.1472998 1.28053307 3.14998327 1.28363238 1 P 0 ;0,1=256,2=0.000000
L 3.14998327 1.28363238 3.1519002 1.28828327 1 P 0 ;0,1=256,2=0.000000
L 3.1519002 1.28828327 3.15266673 1.29293327 1 P 0 ;0,1=256,2=0.000000
L 3.15266673 1.29293327 3.15266673 1.29861634 1 P 0 ;0,1=256,2=0.000000
L 3.15266673 1.29861634 3.1519002 1.30326624 1 P 0 ;0,1=256,2=0.000000
L 3.1519002 1.30326624 3.14998327 1.3073997 1 P 0 ;0,1=256,2=0.000000
L 3.14998327 1.3073997 3.14768307 1.30946683 1 P 0 ;0,1=256,2=0.000000
L 3.14768307 1.30946683 3.14499961 1.3105 1 P 0 ;0,1=256,2=0.000000
L 3.14499961 1.3105 3.14193287 1.30946683 1 P 0 ;0,1=256,2=0.000000
L 3.14193287 1.30946683 3.13963337 1.3073997 1 P 0 ;0,1=256,2=0.000000
L 3.13963337 1.3073997 3.1380997 1.3043003 1 P 0 ;0,1=256,2=0.000000
L 3.1380997 1.3043003 3.13733317 1.30016594 1 P 0 ;0,1=256,2=0.000000
L 3.13733317 1.30016594 3.1380997 1.2965501 1 P 0 ;0,1=256,2=0.000000
L 3.1380997 1.2965501 3.14001663 1.29293327 1 P 0 ;0,1=256,2=0.000000
L 3.14001663 1.29293327 3.14231683 1.29086604 1 P 0 ;0,1=256,2=0.000000
L 3.14231683 1.29086604 3.14499961 1.29034951 1 P 0 ;0,1=256,2=0.000000
L 3.14499961 1.29034951 3.14806634 1.29138268 1 P 0 ;0,1=256,2=0.000000
L 3.14806634 1.29138268 3.15036654 1.29396634 1 P 0 ;0,1=256,2=0.000000
L 3.15036654 1.29396634 3.15266673 1.29861634 1 P 0 ;0,1=256,2=0.000000
L 3.17599961 1.2795 3.17868307 1.28001654 1 P 0 ;0,1=256,2=0.000000
L 3.17868307 1.28001654 3.1817498 1.28156614 1 P 0 ;0,1=256,2=0.000000
L 3.1817498 1.28156614 3.18366673 1.28414892 1 P 0 ;0,1=256,2=0.000000
L 3.18366673 1.28414892 3.18443327 1.28776673 1 P 0 ;0,1=256,2=0.000000
L 3.18443327 1.28776673 3.18366673 1.29138268 1 P 0 ;0,1=256,2=0.000000
L 3.18366673 1.29138268 3.18136654 1.29448287 1 P 0 ;0,1=256,2=0.000000
L 3.18136654 1.29448287 3.17791654 1.29603356 1 P 0 ;0,1=256,2=0.000000
L 3.17791654 1.29603356 3.17408337 1.29603356 1 P 0 ;0,1=256,2=0.000000
L 3.17408337 1.29603356 3.17178317 1.29706663 1 P 0 ;0,1=256,2=0.000000
L 3.17178317 1.29706663 3.16986614 1.29964941 1 P 0 ;0,1=256,2=0.000000
L 3.16986614 1.29964941 3.1690997 1.30326624 1 P 0 ;0,1=256,2=0.000000
L 3.1690997 1.30326624 3.1702501 1.30688307 1 P 0 ;0,1=256,2=0.000000
L 3.1702501 1.30688307 3.17293287 1.30946683 1 P 0 ;0,1=256,2=0.000000
L 3.17293287 1.30946683 3.17599961 1.3105 1 P 0 ;0,1=256,2=0.000000
L 3.17599961 1.3105 3.17906634 1.30946683 1 P 0 ;0,1=256,2=0.000000
L 3.17906634 1.30946683 3.1817498 1.30688307 1 P 0 ;0,1=256,2=0.000000
L 3.1817498 1.30688307 3.1829002 1.30326624 1 P 0 ;0,1=256,2=0.000000
L 3.1829002 1.30326624 3.18213307 1.29964941 1 P 0 ;0,1=256,2=0.000000
L 3.18213307 1.29964941 3.18021673 1.29706663 1 P 0 ;0,1=256,2=0.000000
L 3.18021673 1.29706663 3.17791654 1.29603356 1 P 0 ;0,1=256,2=0.000000
L 3.17791654 1.29603356 3.17408337 1.29603356 1 P 0 ;0,1=256,2=0.000000
L 3.17408337 1.29603356 3.17063337 1.29448287 1 P 0 ;0,1=256,2=0.000000
L 3.17063337 1.29448287 3.16833317 1.29138268 1 P 0 ;0,1=256,2=0.000000
L 3.16833317 1.29138268 3.16756663 1.28776673 1 P 0 ;0,1=256,2=0.000000
L 3.16756663 1.28776673 3.16833317 1.28414892 1 P 0 ;0,1=256,2=0.000000
L 3.16833317 1.28414892 3.1702501 1.28156614 1 P 0 ;0,1=256,2=0.000000
L 3.1702501 1.28156614 3.17331683 1.28001654 1 P 0 ;0,1=256,2=0.000000
L 3.17331683 1.28001654 3.17599961 1.2795 1 P 0 ;0,1=256,2=0.000000
L 3.095 1.917 3.095 1.873 1 P 0 
L 3.185 1.917 3.095 1.917 1 P 0 
L 3.095 1.873 3.185 1.873 1 P 0 
L 3.185 1.873 3.185 1.917 1 P 0 
L 3.10633317 1.3195 3.10633317 1.3505 1 P 0 ;0,1=257,2=0.000000
L 3.10633317 1.3505 3.11591654 1.3505 1 P 0 ;0,1=257,2=0.000000
L 3.11591654 1.3505 3.11898327 1.34894931 1 P 0 ;0,1=257,2=0.000000
L 3.11898327 1.34894931 3.1209002 1.34688307 1 P 0 ;0,1=257,2=0.000000
L 3.1209002 1.34688307 3.12166673 1.3427497 1 P 0 ;0,1=257,2=0.000000
L 3.12166673 1.3427497 3.1209002 1.33861634 1 P 0 ;0,1=257,2=0.000000
L 3.1209002 1.33861634 3.1186 1.33603356 1 P 0 ;0,1=257,2=0.000000
L 3.1186 1.33603356 3.11591654 1.33448287 1 P 0 ;0,1=257,2=0.000000
L 3.11591654 1.33448287 3.10633317 1.33448287 1 P 0 ;0,1=257,2=0.000000
L 3.11591654 1.33448287 3.12166673 1.3195 1 P 0 ;0,1=257,2=0.000000
L 3.13848287 1.32311585 3.14116634 1.32053307 1 P 0 ;0,1=257,2=0.000000
L 3.14116634 1.32053307 3.14423307 1.3195 1 P 0 ;0,1=257,2=0.000000
L 3.14423307 1.3195 3.1472998 1.32053307 1 P 0 ;0,1=257,2=0.000000
L 3.1472998 1.32053307 3.14998327 1.32363238 1 P 0 ;0,1=257,2=0.000000
L 3.14998327 1.32363238 3.1519002 1.32828327 1 P 0 ;0,1=257,2=0.000000
L 3.1519002 1.32828327 3.15266673 1.33293327 1 P 0 ;0,1=257,2=0.000000
L 3.15266673 1.33293327 3.15266673 1.33861634 1 P 0 ;0,1=257,2=0.000000
L 3.15266673 1.33861634 3.1519002 1.34326624 1 P 0 ;0,1=257,2=0.000000
L 3.1519002 1.34326624 3.14998327 1.3473997 1 P 0 ;0,1=257,2=0.000000
L 3.14998327 1.3473997 3.14768307 1.34946683 1 P 0 ;0,1=257,2=0.000000
L 3.14768307 1.34946683 3.14499961 1.3505 1 P 0 ;0,1=257,2=0.000000
L 3.14499961 1.3505 3.14193287 1.34946683 1 P 0 ;0,1=257,2=0.000000
L 3.14193287 1.34946683 3.13963337 1.3473997 1 P 0 ;0,1=257,2=0.000000
L 3.13963337 1.3473997 3.1380997 1.3443003 1 P 0 ;0,1=257,2=0.000000
L 3.1380997 1.3443003 3.13733317 1.34016594 1 P 0 ;0,1=257,2=0.000000
L 3.13733317 1.34016594 3.1380997 1.3365501 1 P 0 ;0,1=257,2=0.000000
L 3.1380997 1.3365501 3.14001663 1.33293327 1 P 0 ;0,1=257,2=0.000000
L 3.14001663 1.33293327 3.14231683 1.33086604 1 P 0 ;0,1=257,2=0.000000
L 3.14231683 1.33086604 3.14499961 1.33034951 1 P 0 ;0,1=257,2=0.000000
L 3.14499961 1.33034951 3.14806634 1.33138268 1 P 0 ;0,1=257,2=0.000000
L 3.14806634 1.33138268 3.15036654 1.33396634 1 P 0 ;0,1=257,2=0.000000
L 3.15036654 1.33396634 3.15266673 1.33861634 1 P 0 ;0,1=257,2=0.000000
L 3.17523307 1.3195 3.17599961 1.32621614 1 P 0 ;0,1=257,2=0.000000
L 3.17599961 1.32621614 3.1771501 1.33189921 1 P 0 ;0,1=257,2=0.000000
L 3.1771501 1.33189921 3.17868307 1.33706663 1 P 0 ;0,1=257,2=0.000000
L 3.17868307 1.33706663 3.1806 1.3427497 1 P 0 ;0,1=257,2=0.000000
L 3.1806 1.3427497 3.18366673 1.3505 1 P 0 ;0,1=257,2=0.000000
L 3.18366673 1.3505 3.16833317 1.3505 1 P 0 ;0,1=257,2=0.000000
L 3.099 1.778 3.189 1.778 1 P 0 
L 3.099 1.822 3.099 1.778 1 P 0 
L 3.189 1.822 3.099 1.822 1 P 0 
L 3.189 1.778 3.189 1.822 1 P 0 
L 3.10633317 1.2295 3.10633317 1.2605 1 P 0 ;0,1=258,2=0.000000
L 3.10633317 1.2605 3.11591654 1.2605 1 P 0 ;0,1=258,2=0.000000
L 3.11591654 1.2605 3.11898327 1.25894931 1 P 0 ;0,1=258,2=0.000000
L 3.11898327 1.25894931 3.1209002 1.25688307 1 P 0 ;0,1=258,2=0.000000
L 3.1209002 1.25688307 3.12166673 1.2527497 1 P 0 ;0,1=258,2=0.000000
L 3.12166673 1.2527497 3.1209002 1.24861634 1 P 0 ;0,1=258,2=0.000000
L 3.1209002 1.24861634 3.1186 1.24603356 1 P 0 ;0,1=258,2=0.000000
L 3.1186 1.24603356 3.11591654 1.24448287 1 P 0 ;0,1=258,2=0.000000
L 3.11591654 1.24448287 3.10633317 1.24448287 1 P 0 ;0,1=258,2=0.000000
L 3.11591654 1.24448287 3.12166673 1.2295 1 P 0 ;0,1=258,2=0.000000
L 3.14499961 1.2295 3.14768307 1.23001654 1 P 0 ;0,1=258,2=0.000000
L 3.14768307 1.23001654 3.1507498 1.23156614 1 P 0 ;0,1=258,2=0.000000
L 3.1507498 1.23156614 3.15266673 1.23414892 1 P 0 ;0,1=258,2=0.000000
L 3.15266673 1.23414892 3.15343327 1.23776673 1 P 0 ;0,1=258,2=0.000000
L 3.15343327 1.23776673 3.15266673 1.24138268 1 P 0 ;0,1=258,2=0.000000
L 3.15266673 1.24138268 3.15036654 1.24448287 1 P 0 ;0,1=258,2=0.000000
L 3.15036654 1.24448287 3.14691654 1.24603356 1 P 0 ;0,1=258,2=0.000000
L 3.14691654 1.24603356 3.14308337 1.24603356 1 P 0 ;0,1=258,2=0.000000
L 3.14308337 1.24603356 3.14078317 1.24706663 1 P 0 ;0,1=258,2=0.000000
L 3.14078317 1.24706663 3.13886614 1.24964941 1 P 0 ;0,1=258,2=0.000000
L 3.13886614 1.24964941 3.1380997 1.25326624 1 P 0 ;0,1=258,2=0.000000
L 3.1380997 1.25326624 3.1392501 1.25688307 1 P 0 ;0,1=258,2=0.000000
L 3.1392501 1.25688307 3.14193287 1.25946683 1 P 0 ;0,1=258,2=0.000000
L 3.14193287 1.25946683 3.14499961 1.2605 1 P 0 ;0,1=258,2=0.000000
L 3.14499961 1.2605 3.14806634 1.25946683 1 P 0 ;0,1=258,2=0.000000
L 3.14806634 1.25946683 3.1507498 1.25688307 1 P 0 ;0,1=258,2=0.000000
L 3.1507498 1.25688307 3.1519002 1.25326624 1 P 0 ;0,1=258,2=0.000000
L 3.1519002 1.25326624 3.15113307 1.24964941 1 P 0 ;0,1=258,2=0.000000
L 3.15113307 1.24964941 3.14921673 1.24706663 1 P 0 ;0,1=258,2=0.000000
L 3.14921673 1.24706663 3.14691654 1.24603356 1 P 0 ;0,1=258,2=0.000000
L 3.14691654 1.24603356 3.14308337 1.24603356 1 P 0 ;0,1=258,2=0.000000
L 3.14308337 1.24603356 3.13963337 1.24448287 1 P 0 ;0,1=258,2=0.000000
L 3.13963337 1.24448287 3.13733317 1.24138268 1 P 0 ;0,1=258,2=0.000000
L 3.13733317 1.24138268 3.13656663 1.23776673 1 P 0 ;0,1=258,2=0.000000
L 3.13656663 1.23776673 3.13733317 1.23414892 1 P 0 ;0,1=258,2=0.000000
L 3.13733317 1.23414892 3.1392501 1.23156614 1 P 0 ;0,1=258,2=0.000000
L 3.1392501 1.23156614 3.14231683 1.23001654 1 P 0 ;0,1=258,2=0.000000
L 3.14231683 1.23001654 3.14499961 1.2295 1 P 0 ;0,1=258,2=0.000000
L 3.17523307 1.2295 3.17599961 1.23621614 1 P 0 ;0,1=258,2=0.000000
L 3.17599961 1.23621614 3.1771501 1.24189921 1 P 0 ;0,1=258,2=0.000000
L 3.1771501 1.24189921 3.17868307 1.24706663 1 P 0 ;0,1=258,2=0.000000
L 3.17868307 1.24706663 3.1806 1.2527497 1 P 0 ;0,1=258,2=0.000000
L 3.1806 1.2527497 3.18366673 1.2605 1 P 0 ;0,1=258,2=0.000000
L 3.18366673 1.2605 3.16833317 1.2605 1 P 0 ;0,1=258,2=0.000000
L 4.42 4.093 4.42 4.137 1 P 0 
L 4.42 4.137 4.33 4.137 1 P 0 
L 4.33 4.137 4.33 4.093 1 P 0 
L 4.33 4.093 4.42 4.093 1 P 0 
L 4.44583317 4.2195 4.44583317 4.2505 1 P 0 ;0,1=259,2=0.000000
L 4.44583317 4.2505 4.45541654 4.2505 1 P 0 ;0,1=259,2=0.000000
L 4.45541654 4.2505 4.45848327 4.24894931 1 P 0 ;0,1=259,2=0.000000
L 4.45848327 4.24894931 4.4604002 4.24688307 1 P 0 ;0,1=259,2=0.000000
L 4.4604002 4.24688307 4.46116673 4.2427497 1 P 0 ;0,1=259,2=0.000000
L 4.46116673 4.2427497 4.4604002 4.23861634 1 P 0 ;0,1=259,2=0.000000
L 4.4604002 4.23861634 4.4581 4.23603356 1 P 0 ;0,1=259,2=0.000000
L 4.4581 4.23603356 4.45541654 4.23448287 1 P 0 ;0,1=259,2=0.000000
L 4.45541654 4.23448287 4.44583317 4.23448287 1 P 0 ;0,1=259,2=0.000000
L 4.45541654 4.23448287 4.46116673 4.2195 1 P 0 ;0,1=259,2=0.000000
L 4.47606663 4.22569961 4.47836614 4.22208278 1 P 0 ;0,1=259,2=0.000000
L 4.47836614 4.22208278 4.48143287 4.22001654 1 P 0 ;0,1=259,2=0.000000
L 4.48143287 4.22001654 4.48488356 4.2195 1 P 0 ;0,1=259,2=0.000000
L 4.48488356 4.2195 4.4879503 4.22001654 1 P 0 ;0,1=259,2=0.000000
L 4.4879503 4.22001654 4.49101703 4.22259931 1 P 0 ;0,1=259,2=0.000000
L 4.49101703 4.22259931 4.49293327 4.22569961 1 P 0 ;0,1=259,2=0.000000
L 4.49293327 4.22569961 4.49331654 4.2287999 1 P 0 ;0,1=259,2=0.000000
L 4.49331654 4.2287999 4.49255 4.23241575 1 P 0 ;0,1=259,2=0.000000
L 4.49255 4.23241575 4.48986654 4.23499951 1 P 0 ;0,1=259,2=0.000000
L 4.48986654 4.23499951 4.48718307 4.23603356 1 P 0 ;0,1=259,2=0.000000
L 4.48718307 4.23603356 4.48373307 4.23603356 1 P 0 ;0,1=259,2=0.000000
L 4.48718307 4.23603356 4.48948327 4.23758317 1 P 0 ;0,1=259,2=0.000000
L 4.48948327 4.23758317 4.4914002 4.24016594 1 P 0 ;0,1=259,2=0.000000
L 4.4914002 4.24016594 4.49216673 4.24326624 1 P 0 ;0,1=259,2=0.000000
L 4.49216673 4.24326624 4.4914002 4.24636654 1 P 0 ;0,1=259,2=0.000000
L 4.4914002 4.24636654 4.48948327 4.24894931 1 P 0 ;0,1=259,2=0.000000
L 4.48948327 4.24894931 4.48603327 4.2505 1 P 0 ;0,1=259,2=0.000000
L 4.48603327 4.2505 4.48258337 4.24998337 1 P 0 ;0,1=259,2=0.000000
L 4.48258337 4.24998337 4.47913337 4.24791624 1 P 0 ;0,1=259,2=0.000000
L 4.50821644 4.23241575 4.5108999 4.23603356 1 P 0 ;0,1=259,2=0.000000
L 4.5108999 4.23603356 4.5132001 4.2380998 1 P 0 ;0,1=259,2=0.000000
L 4.5132001 4.2380998 4.51626683 4.23913287 1 P 0 ;0,1=259,2=0.000000
L 4.51626683 4.23913287 4.5189503 4.2380998 1 P 0 ;0,1=259,2=0.000000
L 4.5189503 4.2380998 4.52086654 4.23603356 1 P 0 ;0,1=259,2=0.000000
L 4.52086654 4.23603356 4.5224002 4.23293327 1 P 0 ;0,1=259,2=0.000000
L 4.5224002 4.23293327 4.52278346 4.22931644 1 P 0 ;0,1=259,2=0.000000
L 4.52278346 4.22931644 4.5224002 4.22621614 1 P 0 ;0,1=259,2=0.000000
L 4.5224002 4.22621614 4.52086654 4.22311585 1 P 0 ;0,1=259,2=0.000000
L 4.52086654 4.22311585 4.51856634 4.22053307 1 P 0 ;0,1=259,2=0.000000
L 4.51856634 4.22053307 4.51588356 4.2195 1 P 0 ;0,1=259,2=0.000000
L 4.51588356 4.2195 4.51281683 4.22053307 1 P 0 ;0,1=259,2=0.000000
L 4.51281683 4.22053307 4.51013337 4.22363238 1 P 0 ;0,1=259,2=0.000000
L 4.51013337 4.22363238 4.5085997 4.22828327 1 P 0 ;0,1=259,2=0.000000
L 4.5085997 4.22828327 4.50821644 4.2334498 1 P 0 ;0,1=259,2=0.000000
L 4.50821644 4.2334498 4.50898287 4.24016594 1 P 0 ;0,1=259,2=0.000000
L 4.50898287 4.24016594 4.51013337 4.24378376 1 P 0 ;0,1=259,2=0.000000
L 4.51013337 4.24378376 4.51204961 4.2473997 1 P 0 ;0,1=259,2=0.000000
L 4.51204961 4.2473997 4.51473307 4.24998337 1 P 0 ;0,1=259,2=0.000000
L 4.51473307 4.24998337 4.51741654 4.2505 1 P 0 ;0,1=259,2=0.000000
L 4.51741654 4.2505 4.5201 4.24946683 1 P 0 ;0,1=259,2=0.000000
L 4.5201 4.24946683 4.52201703 4.24688307 1 P 0 ;0,1=259,2=0.000000
L 4.53921644 4.23241575 4.5418999 4.23603356 1 P 0 ;0,1=259,2=0.000000
L 4.5418999 4.23603356 4.5442001 4.2380998 1 P 0 ;0,1=259,2=0.000000
L 4.5442001 4.2380998 4.54726683 4.23913287 1 P 0 ;0,1=259,2=0.000000
L 4.54726683 4.23913287 4.5499503 4.2380998 1 P 0 ;0,1=259,2=0.000000
L 4.5499503 4.2380998 4.55186654 4.23603356 1 P 0 ;0,1=259,2=0.000000
L 4.55186654 4.23603356 4.5534002 4.23293327 1 P 0 ;0,1=259,2=0.000000
L 4.5534002 4.23293327 4.55378346 4.22931644 1 P 0 ;0,1=259,2=0.000000
L 4.55378346 4.22931644 4.5534002 4.22621614 1 P 0 ;0,1=259,2=0.000000
L 4.5534002 4.22621614 4.55186654 4.22311585 1 P 0 ;0,1=259,2=0.000000
L 4.55186654 4.22311585 4.54956634 4.22053307 1 P 0 ;0,1=259,2=0.000000
L 4.54956634 4.22053307 4.54688356 4.2195 1 P 0 ;0,1=259,2=0.000000
L 4.54688356 4.2195 4.54381683 4.22053307 1 P 0 ;0,1=259,2=0.000000
L 4.54381683 4.22053307 4.54113337 4.22363238 1 P 0 ;0,1=259,2=0.000000
L 4.54113337 4.22363238 4.5395997 4.22828327 1 P 0 ;0,1=259,2=0.000000
L 4.5395997 4.22828327 4.53921644 4.2334498 1 P 0 ;0,1=259,2=0.000000
L 4.53921644 4.2334498 4.53998287 4.24016594 1 P 0 ;0,1=259,2=0.000000
L 4.53998287 4.24016594 4.54113337 4.24378376 1 P 0 ;0,1=259,2=0.000000
L 4.54113337 4.24378376 4.54304961 4.2473997 1 P 0 ;0,1=259,2=0.000000
L 4.54304961 4.2473997 4.54573307 4.24998337 1 P 0 ;0,1=259,2=0.000000
L 4.54573307 4.24998337 4.54841654 4.2505 1 P 0 ;0,1=259,2=0.000000
L 4.54841654 4.2505 4.5511 4.24946683 1 P 0 ;0,1=259,2=0.000000
L 4.5511 4.24946683 4.55301703 4.24688307 1 P 0 ;0,1=259,2=0.000000
L 4.42 4.043 4.42 4.087 1 P 0 
L 4.42 4.087 4.33 4.087 1 P 0 
L 4.33 4.087 4.33 4.043 1 P 0 
L 4.33 4.043 4.42 4.043 1 P 0 
L 4.44583317 4.1795 4.44583317 4.2105 1 P 0 ;0,1=260,2=0.000000
L 4.44583317 4.2105 4.45541654 4.2105 1 P 0 ;0,1=260,2=0.000000
L 4.45541654 4.2105 4.45848327 4.20894931 1 P 0 ;0,1=260,2=0.000000
L 4.45848327 4.20894931 4.4604002 4.20688307 1 P 0 ;0,1=260,2=0.000000
L 4.4604002 4.20688307 4.46116673 4.2027497 1 P 0 ;0,1=260,2=0.000000
L 4.46116673 4.2027497 4.4604002 4.19861634 1 P 0 ;0,1=260,2=0.000000
L 4.4604002 4.19861634 4.4581 4.19603356 1 P 0 ;0,1=260,2=0.000000
L 4.4581 4.19603356 4.45541654 4.19448287 1 P 0 ;0,1=260,2=0.000000
L 4.45541654 4.19448287 4.44583317 4.19448287 1 P 0 ;0,1=260,2=0.000000
L 4.45541654 4.19448287 4.46116673 4.1795 1 P 0 ;0,1=260,2=0.000000
L 4.47606663 4.18569961 4.47836614 4.18208278 1 P 0 ;0,1=260,2=0.000000
L 4.47836614 4.18208278 4.48143287 4.18001654 1 P 0 ;0,1=260,2=0.000000
L 4.48143287 4.18001654 4.48488356 4.1795 1 P 0 ;0,1=260,2=0.000000
L 4.48488356 4.1795 4.4879503 4.18001654 1 P 0 ;0,1=260,2=0.000000
L 4.4879503 4.18001654 4.49101703 4.18259931 1 P 0 ;0,1=260,2=0.000000
L 4.49101703 4.18259931 4.49293327 4.18569961 1 P 0 ;0,1=260,2=0.000000
L 4.49293327 4.18569961 4.49331654 4.1887999 1 P 0 ;0,1=260,2=0.000000
L 4.49331654 4.1887999 4.49255 4.19241575 1 P 0 ;0,1=260,2=0.000000
L 4.49255 4.19241575 4.48986654 4.19499951 1 P 0 ;0,1=260,2=0.000000
L 4.48986654 4.19499951 4.48718307 4.19603356 1 P 0 ;0,1=260,2=0.000000
L 4.48718307 4.19603356 4.48373307 4.19603356 1 P 0 ;0,1=260,2=0.000000
L 4.48718307 4.19603356 4.48948327 4.19758317 1 P 0 ;0,1=260,2=0.000000
L 4.48948327 4.19758317 4.4914002 4.20016594 1 P 0 ;0,1=260,2=0.000000
L 4.4914002 4.20016594 4.49216673 4.20326624 1 P 0 ;0,1=260,2=0.000000
L 4.49216673 4.20326624 4.4914002 4.20636654 1 P 0 ;0,1=260,2=0.000000
L 4.4914002 4.20636654 4.48948327 4.20894931 1 P 0 ;0,1=260,2=0.000000
L 4.48948327 4.20894931 4.48603327 4.2105 1 P 0 ;0,1=260,2=0.000000
L 4.48603327 4.2105 4.48258337 4.20998337 1 P 0 ;0,1=260,2=0.000000
L 4.48258337 4.20998337 4.47913337 4.20791624 1 P 0 ;0,1=260,2=0.000000
L 4.50821644 4.19241575 4.5108999 4.19603356 1 P 0 ;0,1=260,2=0.000000
L 4.5108999 4.19603356 4.5132001 4.1980998 1 P 0 ;0,1=260,2=0.000000
L 4.5132001 4.1980998 4.51626683 4.19913287 1 P 0 ;0,1=260,2=0.000000
L 4.51626683 4.19913287 4.5189503 4.1980998 1 P 0 ;0,1=260,2=0.000000
L 4.5189503 4.1980998 4.52086654 4.19603356 1 P 0 ;0,1=260,2=0.000000
L 4.52086654 4.19603356 4.5224002 4.19293327 1 P 0 ;0,1=260,2=0.000000
L 4.5224002 4.19293327 4.52278346 4.18931644 1 P 0 ;0,1=260,2=0.000000
L 4.52278346 4.18931644 4.5224002 4.18621614 1 P 0 ;0,1=260,2=0.000000
L 4.5224002 4.18621614 4.52086654 4.18311585 1 P 0 ;0,1=260,2=0.000000
L 4.52086654 4.18311585 4.51856634 4.18053307 1 P 0 ;0,1=260,2=0.000000
L 4.51856634 4.18053307 4.51588356 4.1795 1 P 0 ;0,1=260,2=0.000000
L 4.51588356 4.1795 4.51281683 4.18053307 1 P 0 ;0,1=260,2=0.000000
L 4.51281683 4.18053307 4.51013337 4.18363238 1 P 0 ;0,1=260,2=0.000000
L 4.51013337 4.18363238 4.5085997 4.18828327 1 P 0 ;0,1=260,2=0.000000
L 4.5085997 4.18828327 4.50821644 4.1934498 1 P 0 ;0,1=260,2=0.000000
L 4.50821644 4.1934498 4.50898287 4.20016594 1 P 0 ;0,1=260,2=0.000000
L 4.50898287 4.20016594 4.51013337 4.20378376 1 P 0 ;0,1=260,2=0.000000
L 4.51013337 4.20378376 4.51204961 4.2073997 1 P 0 ;0,1=260,2=0.000000
L 4.51204961 4.2073997 4.51473307 4.20998337 1 P 0 ;0,1=260,2=0.000000
L 4.51473307 4.20998337 4.51741654 4.2105 1 P 0 ;0,1=260,2=0.000000
L 4.51741654 4.2105 4.5201 4.20946683 1 P 0 ;0,1=260,2=0.000000
L 4.5201 4.20946683 4.52201703 4.20688307 1 P 0 ;0,1=260,2=0.000000
L 4.5511 4.1795 4.5511 4.2105 1 P 0 ;0,1=260,2=0.000000
L 4.5511 4.2105 4.53691624 4.18828327 1 P 0 ;0,1=260,2=0.000000
L 4.53691624 4.18828327 4.55608366 4.18828327 1 P 0 ;0,1=260,2=0.000000
L 4.672 2.365 4.628 2.365 1 P 0 
L 4.672 2.275 4.672 2.365 1 P 0 
L 4.628 2.365 4.628 2.275 1 P 0 
L 4.628 2.275 4.672 2.275 1 P 0 
L 4.7155 2.26083317 4.6845 2.26083317 1 P 0 ;0,1=261,2=270.000000
L 4.6845 2.26083317 4.6845 2.27041654 1 P 0 ;0,1=261,2=270.000000
L 4.6845 2.27041654 4.68605069 2.27348327 1 P 0 ;0,1=261,2=270.000000
L 4.68605069 2.27348327 4.68811693 2.2754002 1 P 0 ;0,1=261,2=270.000000
L 4.68811693 2.2754002 4.6922503 2.27616673 1 P 0 ;0,1=261,2=270.000000
L 4.6922503 2.27616673 4.69638366 2.2754002 1 P 0 ;0,1=261,2=270.000000
L 4.69638366 2.2754002 4.69896644 2.2731 1 P 0 ;0,1=261,2=270.000000
L 4.69896644 2.2731 4.70051713 2.27041654 1 P 0 ;0,1=261,2=270.000000
L 4.70051713 2.27041654 4.70051713 2.26083317 1 P 0 ;0,1=261,2=270.000000
L 4.70051713 2.27041654 4.7155 2.27616673 1 P 0 ;0,1=261,2=270.000000
L 4.70930039 2.29106663 4.71291722 2.29336614 1 P 0 ;0,1=261,2=270.000000
L 4.71291722 2.29336614 4.71498346 2.29643287 1 P 0 ;0,1=261,2=270.000000
L 4.71498346 2.29643287 4.7155 2.29988356 1 P 0 ;0,1=261,2=270.000000
L 4.7155 2.29988356 4.71498346 2.3029503 1 P 0 ;0,1=261,2=270.000000
L 4.71498346 2.3029503 4.71240069 2.30601703 1 P 0 ;0,1=261,2=270.000000
L 4.71240069 2.30601703 4.70930039 2.30793327 1 P 0 ;0,1=261,2=270.000000
L 4.70930039 2.30793327 4.7062001 2.30831654 1 P 0 ;0,1=261,2=270.000000
L 4.7062001 2.30831654 4.70258425 2.30755 1 P 0 ;0,1=261,2=270.000000
L 4.70258425 2.30755 4.70000049 2.30486654 1 P 0 ;0,1=261,2=270.000000
L 4.70000049 2.30486654 4.69896644 2.30218307 1 P 0 ;0,1=261,2=270.000000
L 4.69896644 2.30218307 4.69896644 2.29873307 1 P 0 ;0,1=261,2=270.000000
L 4.69896644 2.30218307 4.69741683 2.30448327 1 P 0 ;0,1=261,2=270.000000
L 4.69741683 2.30448327 4.69483406 2.3064002 1 P 0 ;0,1=261,2=270.000000
L 4.69483406 2.3064002 4.69173376 2.30716673 1 P 0 ;0,1=261,2=270.000000
L 4.69173376 2.30716673 4.68863346 2.3064002 1 P 0 ;0,1=261,2=270.000000
L 4.68863346 2.3064002 4.68605069 2.30448327 1 P 0 ;0,1=261,2=270.000000
L 4.68605069 2.30448327 4.6845 2.30103327 1 P 0 ;0,1=261,2=270.000000
L 4.6845 2.30103327 4.68501663 2.29758337 1 P 0 ;0,1=261,2=270.000000
L 4.68501663 2.29758337 4.68708376 2.29413337 1 P 0 ;0,1=261,2=270.000000
L 4.70258425 2.32321644 4.69896644 2.3258999 1 P 0 ;0,1=261,2=270.000000
L 4.69896644 2.3258999 4.6969002 2.3282001 1 P 0 ;0,1=261,2=270.000000
L 4.6969002 2.3282001 4.69586713 2.33126683 1 P 0 ;0,1=261,2=270.000000
L 4.69586713 2.33126683 4.6969002 2.3339503 1 P 0 ;0,1=261,2=270.000000
L 4.6969002 2.3339503 4.69896644 2.33586654 1 P 0 ;0,1=261,2=270.000000
L 4.69896644 2.33586654 4.70206673 2.3374002 1 P 0 ;0,1=261,2=270.000000
L 4.70206673 2.3374002 4.70568356 2.33778346 1 P 0 ;0,1=261,2=270.000000
L 4.70568356 2.33778346 4.70878386 2.3374002 1 P 0 ;0,1=261,2=270.000000
L 4.70878386 2.3374002 4.71188415 2.33586654 1 P 0 ;0,1=261,2=270.000000
L 4.71188415 2.33586654 4.71446693 2.33356634 1 P 0 ;0,1=261,2=270.000000
L 4.71446693 2.33356634 4.7155 2.33088356 1 P 0 ;0,1=261,2=270.000000
L 4.7155 2.33088356 4.71446693 2.32781683 1 P 0 ;0,1=261,2=270.000000
L 4.71446693 2.32781683 4.71136762 2.32513337 1 P 0 ;0,1=261,2=270.000000
L 4.71136762 2.32513337 4.70671673 2.3235997 1 P 0 ;0,1=261,2=270.000000
L 4.70671673 2.3235997 4.7015502 2.32321644 1 P 0 ;0,1=261,2=270.000000
L 4.7015502 2.32321644 4.69483406 2.32398287 1 P 0 ;0,1=261,2=270.000000
L 4.69483406 2.32398287 4.69121624 2.32513337 1 P 0 ;0,1=261,2=270.000000
L 4.69121624 2.32513337 4.6876003 2.32704961 1 P 0 ;0,1=261,2=270.000000
L 4.6876003 2.32704961 4.68501663 2.32973307 1 P 0 ;0,1=261,2=270.000000
L 4.68501663 2.32973307 4.6845 2.33241654 1 P 0 ;0,1=261,2=270.000000
L 4.6845 2.33241654 4.68553317 2.3351 1 P 0 ;0,1=261,2=270.000000
L 4.68553317 2.3351 4.68811693 2.33701703 1 P 0 ;0,1=261,2=270.000000
L 4.68966654 2.35421644 4.68656722 2.35651663 1 P 0 ;0,1=261,2=270.000000
L 4.68656722 2.35651663 4.68501663 2.3592001 1 P 0 ;0,1=261,2=270.000000
L 4.68501663 2.3592001 4.6845 2.36226683 1 P 0 ;0,1=261,2=270.000000
L 4.6845 2.36226683 4.68553317 2.3661 1 P 0 ;0,1=261,2=270.000000
L 4.68553317 2.3661 4.68811693 2.36878346 1 P 0 ;0,1=261,2=270.000000
L 4.68811693 2.36878346 4.69121624 2.36955 1 P 0 ;0,1=261,2=270.000000
L 4.69121624 2.36955 4.69431742 2.36916673 1 P 0 ;0,1=261,2=270.000000
L 4.69431742 2.36916673 4.6969002 2.36763307 1 P 0 ;0,1=261,2=270.000000
L 4.6969002 2.36763307 4.70206673 2.35996663 1 P 0 ;0,1=261,2=270.000000
L 4.70206673 2.35996663 4.70568356 2.35651663 1 P 0 ;0,1=261,2=270.000000
L 4.70568356 2.35651663 4.71085108 2.35421644 1 P 0 ;0,1=261,2=270.000000
L 4.71085108 2.35421644 4.7155 2.3534499 1 P 0 ;0,1=261,2=270.000000
L 4.7155 2.3534499 4.7155 2.36955 1 P 0 ;0,1=261,2=270.000000
L 4.642 2.395 4.642 2.485 1 P 0 
L 4.642 2.485 4.598 2.485 1 P 0 
L 4.598 2.485 4.598 2.395 1 P 0 
L 4.598 2.395 4.642 2.395 1 P 0 
L 4.6655 2.51583317 4.6345 2.51583317 1 P 0 ;0,1=262,2=270.000000
L 4.6345 2.51583317 4.6345 2.52541654 1 P 0 ;0,1=262,2=270.000000
L 4.6345 2.52541654 4.63605069 2.52848327 1 P 0 ;0,1=262,2=270.000000
L 4.63605069 2.52848327 4.63811693 2.5304002 1 P 0 ;0,1=262,2=270.000000
L 4.63811693 2.5304002 4.6422503 2.53116673 1 P 0 ;0,1=262,2=270.000000
L 4.6422503 2.53116673 4.64638366 2.5304002 1 P 0 ;0,1=262,2=270.000000
L 4.64638366 2.5304002 4.64896644 2.5281 1 P 0 ;0,1=262,2=270.000000
L 4.64896644 2.5281 4.65051713 2.52541654 1 P 0 ;0,1=262,2=270.000000
L 4.65051713 2.52541654 4.65051713 2.51583317 1 P 0 ;0,1=262,2=270.000000
L 4.65051713 2.52541654 4.6655 2.53116673 1 P 0 ;0,1=262,2=270.000000
L 4.65930039 2.54606663 4.66291722 2.54836614 1 P 0 ;0,1=262,2=270.000000
L 4.66291722 2.54836614 4.66498346 2.55143287 1 P 0 ;0,1=262,2=270.000000
L 4.66498346 2.55143287 4.6655 2.55488356 1 P 0 ;0,1=262,2=270.000000
L 4.6655 2.55488356 4.66498346 2.5579503 1 P 0 ;0,1=262,2=270.000000
L 4.66498346 2.5579503 4.66240069 2.56101703 1 P 0 ;0,1=262,2=270.000000
L 4.66240069 2.56101703 4.65930039 2.56293327 1 P 0 ;0,1=262,2=270.000000
L 4.65930039 2.56293327 4.6562001 2.56331654 1 P 0 ;0,1=262,2=270.000000
L 4.6562001 2.56331654 4.65258425 2.56255 1 P 0 ;0,1=262,2=270.000000
L 4.65258425 2.56255 4.65000049 2.55986654 1 P 0 ;0,1=262,2=270.000000
L 4.65000049 2.55986654 4.64896644 2.55718307 1 P 0 ;0,1=262,2=270.000000
L 4.64896644 2.55718307 4.64896644 2.55373307 1 P 0 ;0,1=262,2=270.000000
L 4.64896644 2.55718307 4.64741683 2.55948327 1 P 0 ;0,1=262,2=270.000000
L 4.64741683 2.55948327 4.64483406 2.5614002 1 P 0 ;0,1=262,2=270.000000
L 4.64483406 2.5614002 4.64173376 2.56216673 1 P 0 ;0,1=262,2=270.000000
L 4.64173376 2.56216673 4.63863346 2.5614002 1 P 0 ;0,1=262,2=270.000000
L 4.63863346 2.5614002 4.63605069 2.55948327 1 P 0 ;0,1=262,2=270.000000
L 4.63605069 2.55948327 4.6345 2.55603327 1 P 0 ;0,1=262,2=270.000000
L 4.6345 2.55603327 4.63501663 2.55258337 1 P 0 ;0,1=262,2=270.000000
L 4.63501663 2.55258337 4.63708376 2.54913337 1 P 0 ;0,1=262,2=270.000000
L 4.6655 2.5901 4.6345 2.5901 1 P 0 ;0,1=262,2=270.000000
L 4.6345 2.5901 4.65671673 2.57591624 1 P 0 ;0,1=262,2=270.000000
L 4.65671673 2.57591624 4.65671673 2.59508366 1 P 0 ;0,1=262,2=270.000000
L 4.6655 2.61649961 4.66498346 2.61918307 1 P 0 ;0,1=262,2=270.000000
L 4.66498346 2.61918307 4.66343386 2.6222498 1 P 0 ;0,1=262,2=270.000000
L 4.66343386 2.6222498 4.66085108 2.62416673 1 P 0 ;0,1=262,2=270.000000
L 4.66085108 2.62416673 4.65723327 2.62493327 1 P 0 ;0,1=262,2=270.000000
L 4.65723327 2.62493327 4.65361732 2.62416673 1 P 0 ;0,1=262,2=270.000000
L 4.65361732 2.62416673 4.65051713 2.62186654 1 P 0 ;0,1=262,2=270.000000
L 4.65051713 2.62186654 4.64896644 2.61841654 1 P 0 ;0,1=262,2=270.000000
L 4.64896644 2.61841654 4.64896644 2.61458337 1 P 0 ;0,1=262,2=270.000000
L 4.64896644 2.61458337 4.64793337 2.61228317 1 P 0 ;0,1=262,2=270.000000
L 4.64793337 2.61228317 4.64535059 2.61036614 1 P 0 ;0,1=262,2=270.000000
L 4.64535059 2.61036614 4.64173376 2.6095997 1 P 0 ;0,1=262,2=270.000000
L 4.64173376 2.6095997 4.63811693 2.6107501 1 P 0 ;0,1=262,2=270.000000
L 4.63811693 2.6107501 4.63553317 2.61343287 1 P 0 ;0,1=262,2=270.000000
L 4.63553317 2.61343287 4.6345 2.61649961 1 P 0 ;0,1=262,2=270.000000
L 4.6345 2.61649961 4.63553317 2.61956634 1 P 0 ;0,1=262,2=270.000000
L 4.63553317 2.61956634 4.63811693 2.6222498 1 P 0 ;0,1=262,2=270.000000
L 4.63811693 2.6222498 4.64173376 2.6234002 1 P 0 ;0,1=262,2=270.000000
L 4.64173376 2.6234002 4.64535059 2.62263307 1 P 0 ;0,1=262,2=270.000000
L 4.64535059 2.62263307 4.64793337 2.62071673 1 P 0 ;0,1=262,2=270.000000
L 4.64793337 2.62071673 4.64896644 2.61841654 1 P 0 ;0,1=262,2=270.000000
L 4.64896644 2.61841654 4.64896644 2.61458337 1 P 0 ;0,1=262,2=270.000000
L 4.64896644 2.61458337 4.65051713 2.61113337 1 P 0 ;0,1=262,2=270.000000
L 4.65051713 2.61113337 4.65361732 2.60883317 1 P 0 ;0,1=262,2=270.000000
L 4.65361732 2.60883317 4.65723327 2.60806663 1 P 0 ;0,1=262,2=270.000000
L 4.65723327 2.60806663 4.66085108 2.60883317 1 P 0 ;0,1=262,2=270.000000
L 4.66085108 2.60883317 4.66343386 2.6107501 1 P 0 ;0,1=262,2=270.000000
L 4.66343386 2.6107501 4.66498346 2.61381683 1 P 0 ;0,1=262,2=270.000000
L 4.66498346 2.61381683 4.6655 2.61649961 1 P 0 ;0,1=262,2=270.000000
L 4.552 2.395 4.552 2.485 1 P 0 
L 4.552 2.485 4.508 2.485 1 P 0 
L 4.508 2.485 4.508 2.395 1 P 0 
L 4.508 2.395 4.552 2.395 1 P 0 
L 4.5555 2.51583317 4.5245 2.51583317 1 P 0 ;0,1=263,2=270.000000
L 4.5245 2.51583317 4.5245 2.52541654 1 P 0 ;0,1=263,2=270.000000
L 4.5245 2.52541654 4.52605069 2.52848327 1 P 0 ;0,1=263,2=270.000000
L 4.52605069 2.52848327 4.52811693 2.5304002 1 P 0 ;0,1=263,2=270.000000
L 4.52811693 2.5304002 4.5322503 2.53116673 1 P 0 ;0,1=263,2=270.000000
L 4.5322503 2.53116673 4.53638366 2.5304002 1 P 0 ;0,1=263,2=270.000000
L 4.53638366 2.5304002 4.53896644 2.5281 1 P 0 ;0,1=263,2=270.000000
L 4.53896644 2.5281 4.54051713 2.52541654 1 P 0 ;0,1=263,2=270.000000
L 4.54051713 2.52541654 4.54051713 2.51583317 1 P 0 ;0,1=263,2=270.000000
L 4.54051713 2.52541654 4.5555 2.53116673 1 P 0 ;0,1=263,2=270.000000
L 4.54930039 2.54606663 4.55291722 2.54836614 1 P 0 ;0,1=263,2=270.000000
L 4.55291722 2.54836614 4.55498346 2.55143287 1 P 0 ;0,1=263,2=270.000000
L 4.55498346 2.55143287 4.5555 2.55488356 1 P 0 ;0,1=263,2=270.000000
L 4.5555 2.55488356 4.55498346 2.5579503 1 P 0 ;0,1=263,2=270.000000
L 4.55498346 2.5579503 4.55240069 2.56101703 1 P 0 ;0,1=263,2=270.000000
L 4.55240069 2.56101703 4.54930039 2.56293327 1 P 0 ;0,1=263,2=270.000000
L 4.54930039 2.56293327 4.5462001 2.56331654 1 P 0 ;0,1=263,2=270.000000
L 4.5462001 2.56331654 4.54258425 2.56255 1 P 0 ;0,1=263,2=270.000000
L 4.54258425 2.56255 4.54000049 2.55986654 1 P 0 ;0,1=263,2=270.000000
L 4.54000049 2.55986654 4.53896644 2.55718307 1 P 0 ;0,1=263,2=270.000000
L 4.53896644 2.55718307 4.53896644 2.55373307 1 P 0 ;0,1=263,2=270.000000
L 4.53896644 2.55718307 4.53741683 2.55948327 1 P 0 ;0,1=263,2=270.000000
L 4.53741683 2.55948327 4.53483406 2.5614002 1 P 0 ;0,1=263,2=270.000000
L 4.53483406 2.5614002 4.53173376 2.56216673 1 P 0 ;0,1=263,2=270.000000
L 4.53173376 2.56216673 4.52863346 2.5614002 1 P 0 ;0,1=263,2=270.000000
L 4.52863346 2.5614002 4.52605069 2.55948327 1 P 0 ;0,1=263,2=270.000000
L 4.52605069 2.55948327 4.5245 2.55603327 1 P 0 ;0,1=263,2=270.000000
L 4.5245 2.55603327 4.52501663 2.55258337 1 P 0 ;0,1=263,2=270.000000
L 4.52501663 2.55258337 4.52708376 2.54913337 1 P 0 ;0,1=263,2=270.000000
L 4.54930039 2.57706663 4.55291722 2.57936614 1 P 0 ;0,1=263,2=270.000000
L 4.55291722 2.57936614 4.55498346 2.58243287 1 P 0 ;0,1=263,2=270.000000
L 4.55498346 2.58243287 4.5555 2.58588356 1 P 0 ;0,1=263,2=270.000000
L 4.5555 2.58588356 4.55498346 2.5889503 1 P 0 ;0,1=263,2=270.000000
L 4.55498346 2.5889503 4.55240069 2.59201703 1 P 0 ;0,1=263,2=270.000000
L 4.55240069 2.59201703 4.54930039 2.59393327 1 P 0 ;0,1=263,2=270.000000
L 4.54930039 2.59393327 4.5462001 2.59431654 1 P 0 ;0,1=263,2=270.000000
L 4.5462001 2.59431654 4.54258425 2.59355 1 P 0 ;0,1=263,2=270.000000
L 4.54258425 2.59355 4.54000049 2.59086654 1 P 0 ;0,1=263,2=270.000000
L 4.54000049 2.59086654 4.53896644 2.58818307 1 P 0 ;0,1=263,2=270.000000
L 4.53896644 2.58818307 4.53896644 2.58473307 1 P 0 ;0,1=263,2=270.000000
L 4.53896644 2.58818307 4.53741683 2.59048327 1 P 0 ;0,1=263,2=270.000000
L 4.53741683 2.59048327 4.53483406 2.5924002 1 P 0 ;0,1=263,2=270.000000
L 4.53483406 2.5924002 4.53173376 2.59316673 1 P 0 ;0,1=263,2=270.000000
L 4.53173376 2.59316673 4.52863346 2.5924002 1 P 0 ;0,1=263,2=270.000000
L 4.52863346 2.5924002 4.52605069 2.59048327 1 P 0 ;0,1=263,2=270.000000
L 4.52605069 2.59048327 4.5245 2.58703327 1 P 0 ;0,1=263,2=270.000000
L 4.5245 2.58703327 4.52501663 2.58358337 1 P 0 ;0,1=263,2=270.000000
L 4.52501663 2.58358337 4.52708376 2.58013337 1 P 0 ;0,1=263,2=270.000000
L 4.55188415 2.60998287 4.55446693 2.61266634 1 P 0 ;0,1=263,2=270.000000
L 4.55446693 2.61266634 4.5555 2.61573307 1 P 0 ;0,1=263,2=270.000000
L 4.5555 2.61573307 4.55446693 2.6187998 1 P 0 ;0,1=263,2=270.000000
L 4.55446693 2.6187998 4.55136762 2.62148327 1 P 0 ;0,1=263,2=270.000000
L 4.55136762 2.62148327 4.54671673 2.6234002 1 P 0 ;0,1=263,2=270.000000
L 4.54671673 2.6234002 4.54206673 2.62416673 1 P 0 ;0,1=263,2=270.000000
L 4.54206673 2.62416673 4.53638366 2.62416673 1 P 0 ;0,1=263,2=270.000000
L 4.53638366 2.62416673 4.53173376 2.6234002 1 P 0 ;0,1=263,2=270.000000
L 4.53173376 2.6234002 4.5276003 2.62148327 1 P 0 ;0,1=263,2=270.000000
L 4.5276003 2.62148327 4.52553317 2.61918307 1 P 0 ;0,1=263,2=270.000000
L 4.52553317 2.61918307 4.5245 2.61649961 1 P 0 ;0,1=263,2=270.000000
L 4.5245 2.61649961 4.52553317 2.61343287 1 P 0 ;0,1=263,2=270.000000
L 4.52553317 2.61343287 4.5276003 2.61113337 1 P 0 ;0,1=263,2=270.000000
L 4.5276003 2.61113337 4.5306997 2.6095997 1 P 0 ;0,1=263,2=270.000000
L 4.5306997 2.6095997 4.53483406 2.60883317 1 P 0 ;0,1=263,2=270.000000
L 4.53483406 2.60883317 4.5384499 2.6095997 1 P 0 ;0,1=263,2=270.000000
L 4.5384499 2.6095997 4.54206673 2.61151663 1 P 0 ;0,1=263,2=270.000000
L 4.54206673 2.61151663 4.54413396 2.61381683 1 P 0 ;0,1=263,2=270.000000
L 4.54413396 2.61381683 4.54465049 2.61649961 1 P 0 ;0,1=263,2=270.000000
L 4.54465049 2.61649961 4.54361732 2.61956634 1 P 0 ;0,1=263,2=270.000000
L 4.54361732 2.61956634 4.54103366 2.62186654 1 P 0 ;0,1=263,2=270.000000
L 4.54103366 2.62186654 4.53638366 2.62416673 1 P 0 ;0,1=263,2=270.000000
L 4.557 2.3 4.557 2.39 1 P 0 
L 4.557 2.39 4.513 2.39 1 P 0 
L 4.513 2.39 4.513 2.3 1 P 0 
L 4.513 2.3 4.557 2.3 1 P 0 
L 4.4755 2.26583317 4.4445 2.26583317 1 P 0 ;0,1=264,2=270.000000
L 4.4445 2.26583317 4.4445 2.27541654 1 P 0 ;0,1=264,2=270.000000
L 4.4445 2.27541654 4.44605069 2.27848327 1 P 0 ;0,1=264,2=270.000000
L 4.44605069 2.27848327 4.44811693 2.2804002 1 P 0 ;0,1=264,2=270.000000
L 4.44811693 2.2804002 4.4522503 2.28116673 1 P 0 ;0,1=264,2=270.000000
L 4.4522503 2.28116673 4.45638366 2.2804002 1 P 0 ;0,1=264,2=270.000000
L 4.45638366 2.2804002 4.45896644 2.2781 1 P 0 ;0,1=264,2=270.000000
L 4.45896644 2.2781 4.46051713 2.27541654 1 P 0 ;0,1=264,2=270.000000
L 4.46051713 2.27541654 4.46051713 2.26583317 1 P 0 ;0,1=264,2=270.000000
L 4.46051713 2.27541654 4.4755 2.28116673 1 P 0 ;0,1=264,2=270.000000
L 4.44966654 2.29721644 4.44656722 2.29951663 1 P 0 ;0,1=264,2=270.000000
L 4.44656722 2.29951663 4.44501663 2.3022001 1 P 0 ;0,1=264,2=270.000000
L 4.44501663 2.3022001 4.4445 2.30526683 1 P 0 ;0,1=264,2=270.000000
L 4.4445 2.30526683 4.44553317 2.3091 1 P 0 ;0,1=264,2=270.000000
L 4.44553317 2.3091 4.44811693 2.31178346 1 P 0 ;0,1=264,2=270.000000
L 4.44811693 2.31178346 4.45121624 2.31255 1 P 0 ;0,1=264,2=270.000000
L 4.45121624 2.31255 4.45431742 2.31216673 1 P 0 ;0,1=264,2=270.000000
L 4.45431742 2.31216673 4.4569002 2.31063307 1 P 0 ;0,1=264,2=270.000000
L 4.4569002 2.31063307 4.46206673 2.30296663 1 P 0 ;0,1=264,2=270.000000
L 4.46206673 2.30296663 4.46568356 2.29951663 1 P 0 ;0,1=264,2=270.000000
L 4.46568356 2.29951663 4.47085108 2.29721644 1 P 0 ;0,1=264,2=270.000000
L 4.47085108 2.29721644 4.4755 2.2964499 1 P 0 ;0,1=264,2=270.000000
L 4.4755 2.2964499 4.4755 2.31255 1 P 0 ;0,1=264,2=270.000000
L 4.46930039 2.32706663 4.47291722 2.32936614 1 P 0 ;0,1=264,2=270.000000
L 4.47291722 2.32936614 4.47498346 2.33243287 1 P 0 ;0,1=264,2=270.000000
L 4.47498346 2.33243287 4.4755 2.33588356 1 P 0 ;0,1=264,2=270.000000
L 4.4755 2.33588356 4.47498346 2.3389503 1 P 0 ;0,1=264,2=270.000000
L 4.47498346 2.3389503 4.47240069 2.34201703 1 P 0 ;0,1=264,2=270.000000
L 4.47240069 2.34201703 4.46930039 2.34393327 1 P 0 ;0,1=264,2=270.000000
L 4.46930039 2.34393327 4.4662001 2.34431654 1 P 0 ;0,1=264,2=270.000000
L 4.4662001 2.34431654 4.46258425 2.34355 1 P 0 ;0,1=264,2=270.000000
L 4.46258425 2.34355 4.46000049 2.34086654 1 P 0 ;0,1=264,2=270.000000
L 4.46000049 2.34086654 4.45896644 2.33818307 1 P 0 ;0,1=264,2=270.000000
L 4.45896644 2.33818307 4.45896644 2.33473307 1 P 0 ;0,1=264,2=270.000000
L 4.45896644 2.33818307 4.45741683 2.34048327 1 P 0 ;0,1=264,2=270.000000
L 4.45741683 2.34048327 4.45483406 2.3424002 1 P 0 ;0,1=264,2=270.000000
L 4.45483406 2.3424002 4.45173376 2.34316673 1 P 0 ;0,1=264,2=270.000000
L 4.45173376 2.34316673 4.44863346 2.3424002 1 P 0 ;0,1=264,2=270.000000
L 4.44863346 2.3424002 4.44605069 2.34048327 1 P 0 ;0,1=264,2=270.000000
L 4.44605069 2.34048327 4.4445 2.33703327 1 P 0 ;0,1=264,2=270.000000
L 4.4445 2.33703327 4.44501663 2.33358337 1 P 0 ;0,1=264,2=270.000000
L 4.44501663 2.33358337 4.44708376 2.33013337 1 P 0 ;0,1=264,2=270.000000
L 4.4755 2.36649961 4.47498346 2.36918307 1 P 0 ;0,1=264,2=270.000000
L 4.47498346 2.36918307 4.47343386 2.3722498 1 P 0 ;0,1=264,2=270.000000
L 4.47343386 2.3722498 4.47085108 2.37416673 1 P 0 ;0,1=264,2=270.000000
L 4.47085108 2.37416673 4.46723327 2.37493327 1 P 0 ;0,1=264,2=270.000000
L 4.46723327 2.37493327 4.46361732 2.37416673 1 P 0 ;0,1=264,2=270.000000
L 4.46361732 2.37416673 4.46051713 2.37186654 1 P 0 ;0,1=264,2=270.000000
L 4.46051713 2.37186654 4.45896644 2.36841654 1 P 0 ;0,1=264,2=270.000000
L 4.45896644 2.36841654 4.45896644 2.36458337 1 P 0 ;0,1=264,2=270.000000
L 4.45896644 2.36458337 4.45793337 2.36228317 1 P 0 ;0,1=264,2=270.000000
L 4.45793337 2.36228317 4.45535059 2.36036614 1 P 0 ;0,1=264,2=270.000000
L 4.45535059 2.36036614 4.45173376 2.3595997 1 P 0 ;0,1=264,2=270.000000
L 4.45173376 2.3595997 4.44811693 2.3607501 1 P 0 ;0,1=264,2=270.000000
L 4.44811693 2.3607501 4.44553317 2.36343287 1 P 0 ;0,1=264,2=270.000000
L 4.44553317 2.36343287 4.4445 2.36649961 1 P 0 ;0,1=264,2=270.000000
L 4.4445 2.36649961 4.44553317 2.36956634 1 P 0 ;0,1=264,2=270.000000
L 4.44553317 2.36956634 4.44811693 2.3722498 1 P 0 ;0,1=264,2=270.000000
L 4.44811693 2.3722498 4.45173376 2.3734002 1 P 0 ;0,1=264,2=270.000000
L 4.45173376 2.3734002 4.45535059 2.37263307 1 P 0 ;0,1=264,2=270.000000
L 4.45535059 2.37263307 4.45793337 2.37071673 1 P 0 ;0,1=264,2=270.000000
L 4.45793337 2.37071673 4.45896644 2.36841654 1 P 0 ;0,1=264,2=270.000000
L 4.45896644 2.36841654 4.45896644 2.36458337 1 P 0 ;0,1=264,2=270.000000
L 4.45896644 2.36458337 4.46051713 2.36113337 1 P 0 ;0,1=264,2=270.000000
L 4.46051713 2.36113337 4.46361732 2.35883317 1 P 0 ;0,1=264,2=270.000000
L 4.46361732 2.35883317 4.46723327 2.35806663 1 P 0 ;0,1=264,2=270.000000
L 4.46723327 2.35806663 4.47085108 2.35883317 1 P 0 ;0,1=264,2=270.000000
L 4.47085108 2.35883317 4.47343386 2.3607501 1 P 0 ;0,1=264,2=270.000000
L 4.47343386 2.3607501 4.47498346 2.36381683 1 P 0 ;0,1=264,2=270.000000
L 4.47498346 2.36381683 4.4755 2.36649961 1 P 0 ;0,1=264,2=270.000000
L 4.507 2.395 4.507 2.485 1 P 0 
L 4.507 2.485 4.463 2.485 1 P 0 
L 4.463 2.485 4.463 2.395 1 P 0 
L 4.463 2.395 4.507 2.395 1 P 0 
L 4.5105 2.51583317 4.4795 2.51583317 1 P 0 ;0,1=265,2=270.000000
L 4.4795 2.51583317 4.4795 2.52541654 1 P 0 ;0,1=265,2=270.000000
L 4.4795 2.52541654 4.48105069 2.52848327 1 P 0 ;0,1=265,2=270.000000
L 4.48105069 2.52848327 4.48311693 2.5304002 1 P 0 ;0,1=265,2=270.000000
L 4.48311693 2.5304002 4.4872503 2.53116673 1 P 0 ;0,1=265,2=270.000000
L 4.4872503 2.53116673 4.49138366 2.5304002 1 P 0 ;0,1=265,2=270.000000
L 4.49138366 2.5304002 4.49396644 2.5281 1 P 0 ;0,1=265,2=270.000000
L 4.49396644 2.5281 4.49551713 2.52541654 1 P 0 ;0,1=265,2=270.000000
L 4.49551713 2.52541654 4.49551713 2.51583317 1 P 0 ;0,1=265,2=270.000000
L 4.49551713 2.52541654 4.5105 2.53116673 1 P 0 ;0,1=265,2=270.000000
L 4.48466654 2.54721644 4.48156722 2.54951663 1 P 0 ;0,1=265,2=270.000000
L 4.48156722 2.54951663 4.48001663 2.5522001 1 P 0 ;0,1=265,2=270.000000
L 4.48001663 2.5522001 4.4795 2.55526683 1 P 0 ;0,1=265,2=270.000000
L 4.4795 2.55526683 4.48053317 2.5591 1 P 0 ;0,1=265,2=270.000000
L 4.48053317 2.5591 4.48311693 2.56178346 1 P 0 ;0,1=265,2=270.000000
L 4.48311693 2.56178346 4.48621624 2.56255 1 P 0 ;0,1=265,2=270.000000
L 4.48621624 2.56255 4.48931742 2.56216673 1 P 0 ;0,1=265,2=270.000000
L 4.48931742 2.56216673 4.4919002 2.56063307 1 P 0 ;0,1=265,2=270.000000
L 4.4919002 2.56063307 4.49706673 2.55296663 1 P 0 ;0,1=265,2=270.000000
L 4.49706673 2.55296663 4.50068356 2.54951663 1 P 0 ;0,1=265,2=270.000000
L 4.50068356 2.54951663 4.50585108 2.54721644 1 P 0 ;0,1=265,2=270.000000
L 4.50585108 2.54721644 4.5105 2.5464499 1 P 0 ;0,1=265,2=270.000000
L 4.5105 2.5464499 4.5105 2.56255 1 P 0 ;0,1=265,2=270.000000
L 4.50430039 2.57706663 4.50791722 2.57936614 1 P 0 ;0,1=265,2=270.000000
L 4.50791722 2.57936614 4.50998346 2.58243287 1 P 0 ;0,1=265,2=270.000000
L 4.50998346 2.58243287 4.5105 2.58588356 1 P 0 ;0,1=265,2=270.000000
L 4.5105 2.58588356 4.50998346 2.5889503 1 P 0 ;0,1=265,2=270.000000
L 4.50998346 2.5889503 4.50740069 2.59201703 1 P 0 ;0,1=265,2=270.000000
L 4.50740069 2.59201703 4.50430039 2.59393327 1 P 0 ;0,1=265,2=270.000000
L 4.50430039 2.59393327 4.5012001 2.59431654 1 P 0 ;0,1=265,2=270.000000
L 4.5012001 2.59431654 4.49758425 2.59355 1 P 0 ;0,1=265,2=270.000000
L 4.49758425 2.59355 4.49500049 2.59086654 1 P 0 ;0,1=265,2=270.000000
L 4.49500049 2.59086654 4.49396644 2.58818307 1 P 0 ;0,1=265,2=270.000000
L 4.49396644 2.58818307 4.49396644 2.58473307 1 P 0 ;0,1=265,2=270.000000
L 4.49396644 2.58818307 4.49241683 2.59048327 1 P 0 ;0,1=265,2=270.000000
L 4.49241683 2.59048327 4.48983406 2.5924002 1 P 0 ;0,1=265,2=270.000000
L 4.48983406 2.5924002 4.48673376 2.59316673 1 P 0 ;0,1=265,2=270.000000
L 4.48673376 2.59316673 4.48363346 2.5924002 1 P 0 ;0,1=265,2=270.000000
L 4.48363346 2.5924002 4.48105069 2.59048327 1 P 0 ;0,1=265,2=270.000000
L 4.48105069 2.59048327 4.4795 2.58703327 1 P 0 ;0,1=265,2=270.000000
L 4.4795 2.58703327 4.48001663 2.58358337 1 P 0 ;0,1=265,2=270.000000
L 4.48001663 2.58358337 4.48208376 2.58013337 1 P 0 ;0,1=265,2=270.000000
L 4.5105 2.6211 4.4795 2.6211 1 P 0 ;0,1=265,2=270.000000
L 4.4795 2.6211 4.50171673 2.60691624 1 P 0 ;0,1=265,2=270.000000
L 4.50171673 2.60691624 4.50171673 2.62608366 1 P 0 ;0,1=265,2=270.000000
L 3.665 2.688 3.755 2.688 1 P 0 
L 3.755 2.688 3.755 2.732 1 P 0 
L 3.755 2.732 3.665 2.732 1 P 0 
L 3.665 2.732 3.665 2.688 1 P 0 
L 2.55083317 3.4595 2.55083317 3.4905 1 P 0 ;0,1=266,2=0.000000
L 2.55083317 3.4905 2.56041654 3.4905 1 P 0 ;0,1=266,2=0.000000
L 2.56041654 3.4905 2.56348327 3.48894931 1 P 0 ;0,1=266,2=0.000000
L 2.56348327 3.48894931 2.5654002 3.48688307 1 P 0 ;0,1=266,2=0.000000
L 2.5654002 3.48688307 2.56616673 3.4827497 1 P 0 ;0,1=266,2=0.000000
L 2.56616673 3.4827497 2.5654002 3.47861634 1 P 0 ;0,1=266,2=0.000000
L 2.5654002 3.47861634 2.5631 3.47603356 1 P 0 ;0,1=266,2=0.000000
L 2.5631 3.47603356 2.56041654 3.47448287 1 P 0 ;0,1=266,2=0.000000
L 2.56041654 3.47448287 2.55083317 3.47448287 1 P 0 ;0,1=266,2=0.000000
L 2.56041654 3.47448287 2.56616673 3.4595 1 P 0 ;0,1=266,2=0.000000
L 2.58949961 3.4595 2.58949961 3.4905 1 P 0 ;0,1=266,2=0.000000
L 2.58949961 3.4905 2.5848999 3.4843003 1 P 0 ;0,1=266,2=0.000000
L 2.5848999 3.4595 2.59409931 3.4595 1 P 0 ;0,1=266,2=0.000000
L 2.61321644 3.47241575 2.6158999 3.47603356 1 P 0 ;0,1=266,2=0.000000
L 2.6158999 3.47603356 2.6182001 3.4780998 1 P 0 ;0,1=266,2=0.000000
L 2.6182001 3.4780998 2.62126683 3.47913287 1 P 0 ;0,1=266,2=0.000000
L 2.62126683 3.47913287 2.6239503 3.4780998 1 P 0 ;0,1=266,2=0.000000
L 2.6239503 3.4780998 2.62586654 3.47603356 1 P 0 ;0,1=266,2=0.000000
L 2.62586654 3.47603356 2.6274002 3.47293327 1 P 0 ;0,1=266,2=0.000000
L 2.6274002 3.47293327 2.62778346 3.46931644 1 P 0 ;0,1=266,2=0.000000
L 2.62778346 3.46931644 2.6274002 3.46621614 1 P 0 ;0,1=266,2=0.000000
L 2.6274002 3.46621614 2.62586654 3.46311585 1 P 0 ;0,1=266,2=0.000000
L 2.62586654 3.46311585 2.62356634 3.46053307 1 P 0 ;0,1=266,2=0.000000
L 2.62356634 3.46053307 2.62088356 3.4595 1 P 0 ;0,1=266,2=0.000000
L 2.62088356 3.4595 2.61781683 3.46053307 1 P 0 ;0,1=266,2=0.000000
L 2.61781683 3.46053307 2.61513337 3.46363238 1 P 0 ;0,1=266,2=0.000000
L 2.61513337 3.46363238 2.6135997 3.46828327 1 P 0 ;0,1=266,2=0.000000
L 2.6135997 3.46828327 2.61321644 3.4734498 1 P 0 ;0,1=266,2=0.000000
L 2.61321644 3.4734498 2.61398287 3.48016594 1 P 0 ;0,1=266,2=0.000000
L 2.61398287 3.48016594 2.61513337 3.48378376 1 P 0 ;0,1=266,2=0.000000
L 2.61513337 3.48378376 2.61704961 3.4873997 1 P 0 ;0,1=266,2=0.000000
L 2.61704961 3.4873997 2.61973307 3.48998337 1 P 0 ;0,1=266,2=0.000000
L 2.61973307 3.48998337 2.62241654 3.4905 1 P 0 ;0,1=266,2=0.000000
L 2.62241654 3.4905 2.6251 3.48946683 1 P 0 ;0,1=266,2=0.000000
L 2.6251 3.48946683 2.62701703 3.48688307 1 P 0 ;0,1=266,2=0.000000
L 2.65073307 3.4595 2.65149961 3.46621614 1 P 0 ;0,1=266,2=0.000000
L 2.65149961 3.46621614 2.6526501 3.47189921 1 P 0 ;0,1=266,2=0.000000
L 2.6526501 3.47189921 2.65418307 3.47706663 1 P 0 ;0,1=266,2=0.000000
L 2.65418307 3.47706663 2.6561 3.4827497 1 P 0 ;0,1=266,2=0.000000
L 2.6561 3.4827497 2.65916673 3.4905 1 P 0 ;0,1=266,2=0.000000
L 2.65916673 3.4905 2.64383317 3.4905 1 P 0 ;0,1=266,2=0.000000
L 3.782 2.36 3.782 2.45 1 P 0 
L 3.782 2.45 3.738 2.45 1 P 0 
L 3.738 2.45 3.738 2.36 1 P 0 
L 3.738 2.36 3.782 2.36 1 P 0 
L 3.7705 2.24583317 3.7395 2.24583317 1 P 0 ;0,1=267,2=270.000000
L 3.7395 2.24583317 3.7395 2.25541654 1 P 0 ;0,1=267,2=270.000000
L 3.7395 2.25541654 3.74105069 2.25848327 1 P 0 ;0,1=267,2=270.000000
L 3.74105069 2.25848327 3.74311693 2.2604002 1 P 0 ;0,1=267,2=270.000000
L 3.74311693 2.2604002 3.7472503 2.26116673 1 P 0 ;0,1=267,2=270.000000
L 3.7472503 2.26116673 3.75138366 2.2604002 1 P 0 ;0,1=267,2=270.000000
L 3.75138366 2.2604002 3.75396644 2.2581 1 P 0 ;0,1=267,2=270.000000
L 3.75396644 2.2581 3.75551713 2.25541654 1 P 0 ;0,1=267,2=270.000000
L 3.75551713 2.25541654 3.75551713 2.24583317 1 P 0 ;0,1=267,2=270.000000
L 3.75551713 2.25541654 3.7705 2.26116673 1 P 0 ;0,1=267,2=270.000000
L 3.7705 2.28449961 3.7395 2.28449961 1 P 0 ;0,1=267,2=270.000000
L 3.7395 2.28449961 3.7456997 2.2798999 1 P 0 ;0,1=267,2=270.000000
L 3.7705 2.2798999 3.7705 2.28909931 1 P 0 ;0,1=267,2=270.000000
L 3.75758425 2.30821644 3.75396644 2.3108999 1 P 0 ;0,1=267,2=270.000000
L 3.75396644 2.3108999 3.7519002 2.3132001 1 P 0 ;0,1=267,2=270.000000
L 3.7519002 2.3132001 3.75086713 2.31626683 1 P 0 ;0,1=267,2=270.000000
L 3.75086713 2.31626683 3.7519002 2.3189503 1 P 0 ;0,1=267,2=270.000000
L 3.7519002 2.3189503 3.75396644 2.32086654 1 P 0 ;0,1=267,2=270.000000
L 3.75396644 2.32086654 3.75706673 2.3224002 1 P 0 ;0,1=267,2=270.000000
L 3.75706673 2.3224002 3.76068356 2.32278346 1 P 0 ;0,1=267,2=270.000000
L 3.76068356 2.32278346 3.76378386 2.3224002 1 P 0 ;0,1=267,2=270.000000
L 3.76378386 2.3224002 3.76688415 2.32086654 1 P 0 ;0,1=267,2=270.000000
L 3.76688415 2.32086654 3.76946693 2.31856634 1 P 0 ;0,1=267,2=270.000000
L 3.76946693 2.31856634 3.7705 2.31588356 1 P 0 ;0,1=267,2=270.000000
L 3.7705 2.31588356 3.76946693 2.31281683 1 P 0 ;0,1=267,2=270.000000
L 3.76946693 2.31281683 3.76636762 2.31013337 1 P 0 ;0,1=267,2=270.000000
L 3.76636762 2.31013337 3.76171673 2.3085997 1 P 0 ;0,1=267,2=270.000000
L 3.76171673 2.3085997 3.7565502 2.30821644 1 P 0 ;0,1=267,2=270.000000
L 3.7565502 2.30821644 3.74983406 2.30898287 1 P 0 ;0,1=267,2=270.000000
L 3.74983406 2.30898287 3.74621624 2.31013337 1 P 0 ;0,1=267,2=270.000000
L 3.74621624 2.31013337 3.7426003 2.31204961 1 P 0 ;0,1=267,2=270.000000
L 3.7426003 2.31204961 3.74001663 2.31473307 1 P 0 ;0,1=267,2=270.000000
L 3.74001663 2.31473307 3.7395 2.31741654 1 P 0 ;0,1=267,2=270.000000
L 3.7395 2.31741654 3.74053317 2.3201 1 P 0 ;0,1=267,2=270.000000
L 3.74053317 2.3201 3.74311693 2.32201703 1 P 0 ;0,1=267,2=270.000000
L 3.7705 2.3511 3.7395 2.3511 1 P 0 ;0,1=267,2=270.000000
L 3.7395 2.3511 3.76171673 2.33691624 1 P 0 ;0,1=267,2=270.000000
L 3.76171673 2.33691624 3.76171673 2.35608366 1 P 0 ;0,1=267,2=270.000000
L 0.433 1.244 0.433 1.154 1 P 0 
L 0.433 1.154 0.477 1.154 1 P 0 
L 0.477 1.154 0.477 1.244 1 P 0 
L 0.477 1.244 0.433 1.244 1 P 0 
L 0.3855 1.15083317 0.3545 1.15083317 1 P 0 ;0,1=268,2=270.000000
L 0.3545 1.15083317 0.3545 1.16041654 1 P 0 ;0,1=268,2=270.000000
L 0.3545 1.16041654 0.35605069 1.16348327 1 P 0 ;0,1=268,2=270.000000
L 0.35605069 1.16348327 0.35811693 1.1654002 1 P 0 ;0,1=268,2=270.000000
L 0.35811693 1.1654002 0.3622503 1.16616673 1 P 0 ;0,1=268,2=270.000000
L 0.3622503 1.16616673 0.36638366 1.1654002 1 P 0 ;0,1=268,2=270.000000
L 0.36638366 1.1654002 0.36896644 1.1631 1 P 0 ;0,1=268,2=270.000000
L 0.36896644 1.1631 0.37051713 1.16041654 1 P 0 ;0,1=268,2=270.000000
L 0.37051713 1.16041654 0.37051713 1.15083317 1 P 0 ;0,1=268,2=270.000000
L 0.37051713 1.16041654 0.3855 1.16616673 1 P 0 ;0,1=268,2=270.000000
L 0.3855 1.1941 0.3545 1.1941 1 P 0 ;0,1=268,2=270.000000
L 0.3545 1.1941 0.37671673 1.17991624 1 P 0 ;0,1=268,2=270.000000
L 0.37671673 1.17991624 0.37671673 1.19908366 1 P 0 ;0,1=268,2=270.000000
L 0.38188415 1.21398287 0.38446693 1.21666634 1 P 0 ;0,1=268,2=270.000000
L 0.38446693 1.21666634 0.3855 1.21973307 1 P 0 ;0,1=268,2=270.000000
L 0.3855 1.21973307 0.38446693 1.2227998 1 P 0 ;0,1=268,2=270.000000
L 0.38446693 1.2227998 0.38136762 1.22548327 1 P 0 ;0,1=268,2=270.000000
L 0.38136762 1.22548327 0.37671673 1.2274002 1 P 0 ;0,1=268,2=270.000000
L 0.37671673 1.2274002 0.37206673 1.22816673 1 P 0 ;0,1=268,2=270.000000
L 0.37206673 1.22816673 0.36638366 1.22816673 1 P 0 ;0,1=268,2=270.000000
L 0.36638366 1.22816673 0.36173376 1.2274002 1 P 0 ;0,1=268,2=270.000000
L 0.36173376 1.2274002 0.3576003 1.22548327 1 P 0 ;0,1=268,2=270.000000
L 0.3576003 1.22548327 0.35553317 1.22318307 1 P 0 ;0,1=268,2=270.000000
L 0.35553317 1.22318307 0.3545 1.22049961 1 P 0 ;0,1=268,2=270.000000
L 0.3545 1.22049961 0.35553317 1.21743287 1 P 0 ;0,1=268,2=270.000000
L 0.35553317 1.21743287 0.3576003 1.21513337 1 P 0 ;0,1=268,2=270.000000
L 0.3576003 1.21513337 0.3606997 1.2135997 1 P 0 ;0,1=268,2=270.000000
L 0.3606997 1.2135997 0.36483406 1.21283317 1 P 0 ;0,1=268,2=270.000000
L 0.36483406 1.21283317 0.3684499 1.2135997 1 P 0 ;0,1=268,2=270.000000
L 0.3684499 1.2135997 0.37206673 1.21551663 1 P 0 ;0,1=268,2=270.000000
L 0.37206673 1.21551663 0.37413396 1.21781683 1 P 0 ;0,1=268,2=270.000000
L 0.37413396 1.21781683 0.37465049 1.22049961 1 P 0 ;0,1=268,2=270.000000
L 0.37465049 1.22049961 0.37361732 1.22356634 1 P 0 ;0,1=268,2=270.000000
L 0.37361732 1.22356634 0.37103366 1.22586654 1 P 0 ;0,1=268,2=270.000000
L 0.37103366 1.22586654 0.36638366 1.22816673 1 P 0 ;0,1=268,2=270.000000
L 0.37258425 1.24421644 0.36896644 1.2468999 1 P 0 ;0,1=268,2=270.000000
L 0.36896644 1.2468999 0.3669002 1.2492001 1 P 0 ;0,1=268,2=270.000000
L 0.3669002 1.2492001 0.36586713 1.25226683 1 P 0 ;0,1=268,2=270.000000
L 0.36586713 1.25226683 0.3669002 1.2549503 1 P 0 ;0,1=268,2=270.000000
L 0.3669002 1.2549503 0.36896644 1.25686654 1 P 0 ;0,1=268,2=270.000000
L 0.36896644 1.25686654 0.37206673 1.2584002 1 P 0 ;0,1=268,2=270.000000
L 0.37206673 1.2584002 0.37568356 1.25878346 1 P 0 ;0,1=268,2=270.000000
L 0.37568356 1.25878346 0.37878386 1.2584002 1 P 0 ;0,1=268,2=270.000000
L 0.37878386 1.2584002 0.38188415 1.25686654 1 P 0 ;0,1=268,2=270.000000
L 0.38188415 1.25686654 0.38446693 1.25456634 1 P 0 ;0,1=268,2=270.000000
L 0.38446693 1.25456634 0.3855 1.25188356 1 P 0 ;0,1=268,2=270.000000
L 0.3855 1.25188356 0.38446693 1.24881683 1 P 0 ;0,1=268,2=270.000000
L 0.38446693 1.24881683 0.38136762 1.24613337 1 P 0 ;0,1=268,2=270.000000
L 0.38136762 1.24613337 0.37671673 1.2445997 1 P 0 ;0,1=268,2=270.000000
L 0.37671673 1.2445997 0.3715502 1.24421644 1 P 0 ;0,1=268,2=270.000000
L 0.3715502 1.24421644 0.36483406 1.24498287 1 P 0 ;0,1=268,2=270.000000
L 0.36483406 1.24498287 0.36121624 1.24613337 1 P 0 ;0,1=268,2=270.000000
L 0.36121624 1.24613337 0.3576003 1.24804961 1 P 0 ;0,1=268,2=270.000000
L 0.3576003 1.24804961 0.35501663 1.25073307 1 P 0 ;0,1=268,2=270.000000
L 0.35501663 1.25073307 0.3545 1.25341654 1 P 0 ;0,1=268,2=270.000000
L 0.3545 1.25341654 0.35553317 1.2561 1 P 0 ;0,1=268,2=270.000000
L 0.35553317 1.2561 0.35811693 1.25801703 1 P 0 ;0,1=268,2=270.000000
L 0.421 0.713 0.421 0.623 1 P 0 
L 0.421 0.623 0.465 0.623 1 P 0 
L 0.465 0.623 0.465 0.713 1 P 0 
L 0.465 0.713 0.421 0.713 1 P 0 
L 0.4155 0.61583317 0.3845 0.61583317 1 P 0 ;0,1=269,2=270.000000
L 0.3845 0.61583317 0.3845 0.62541654 1 P 0 ;0,1=269,2=270.000000
L 0.3845 0.62541654 0.38605069 0.62848327 1 P 0 ;0,1=269,2=270.000000
L 0.38605069 0.62848327 0.38811693 0.6304002 1 P 0 ;0,1=269,2=270.000000
L 0.38811693 0.6304002 0.3922503 0.63116673 1 P 0 ;0,1=269,2=270.000000
L 0.3922503 0.63116673 0.39638366 0.6304002 1 P 0 ;0,1=269,2=270.000000
L 0.39638366 0.6304002 0.39896644 0.6281 1 P 0 ;0,1=269,2=270.000000
L 0.39896644 0.6281 0.40051713 0.62541654 1 P 0 ;0,1=269,2=270.000000
L 0.40051713 0.62541654 0.40051713 0.61583317 1 P 0 ;0,1=269,2=270.000000
L 0.40051713 0.62541654 0.4155 0.63116673 1 P 0 ;0,1=269,2=270.000000
L 0.4155 0.6591 0.3845 0.6591 1 P 0 ;0,1=269,2=270.000000
L 0.3845 0.6591 0.40671673 0.64491624 1 P 0 ;0,1=269,2=270.000000
L 0.40671673 0.64491624 0.40671673 0.66408366 1 P 0 ;0,1=269,2=270.000000
L 0.41188415 0.67898287 0.41446693 0.68166634 1 P 0 ;0,1=269,2=270.000000
L 0.41446693 0.68166634 0.4155 0.68473307 1 P 0 ;0,1=269,2=270.000000
L 0.4155 0.68473307 0.41446693 0.6877998 1 P 0 ;0,1=269,2=270.000000
L 0.41446693 0.6877998 0.41136762 0.69048327 1 P 0 ;0,1=269,2=270.000000
L 0.41136762 0.69048327 0.40671673 0.6924002 1 P 0 ;0,1=269,2=270.000000
L 0.40671673 0.6924002 0.40206673 0.69316673 1 P 0 ;0,1=269,2=270.000000
L 0.40206673 0.69316673 0.39638366 0.69316673 1 P 0 ;0,1=269,2=270.000000
L 0.39638366 0.69316673 0.39173376 0.6924002 1 P 0 ;0,1=269,2=270.000000
L 0.39173376 0.6924002 0.3876003 0.69048327 1 P 0 ;0,1=269,2=270.000000
L 0.3876003 0.69048327 0.38553317 0.68818307 1 P 0 ;0,1=269,2=270.000000
L 0.38553317 0.68818307 0.3845 0.68549961 1 P 0 ;0,1=269,2=270.000000
L 0.3845 0.68549961 0.38553317 0.68243287 1 P 0 ;0,1=269,2=270.000000
L 0.38553317 0.68243287 0.3876003 0.68013337 1 P 0 ;0,1=269,2=270.000000
L 0.3876003 0.68013337 0.3906997 0.6785997 1 P 0 ;0,1=269,2=270.000000
L 0.3906997 0.6785997 0.39483406 0.67783317 1 P 0 ;0,1=269,2=270.000000
L 0.39483406 0.67783317 0.3984499 0.6785997 1 P 0 ;0,1=269,2=270.000000
L 0.3984499 0.6785997 0.40206673 0.68051663 1 P 0 ;0,1=269,2=270.000000
L 0.40206673 0.68051663 0.40413396 0.68281683 1 P 0 ;0,1=269,2=270.000000
L 0.40413396 0.68281683 0.40465049 0.68549961 1 P 0 ;0,1=269,2=270.000000
L 0.40465049 0.68549961 0.40361732 0.68856634 1 P 0 ;0,1=269,2=270.000000
L 0.40361732 0.68856634 0.40103366 0.69086654 1 P 0 ;0,1=269,2=270.000000
L 0.40103366 0.69086654 0.39638366 0.69316673 1 P 0 ;0,1=269,2=270.000000
L 0.4155 0.71573307 0.40878386 0.71649961 1 P 0 ;0,1=269,2=270.000000
L 0.40878386 0.71649961 0.40310079 0.7176501 1 P 0 ;0,1=269,2=270.000000
L 0.40310079 0.7176501 0.39793337 0.71918307 1 P 0 ;0,1=269,2=270.000000
L 0.39793337 0.71918307 0.3922503 0.7211 1 P 0 ;0,1=269,2=270.000000
L 0.3922503 0.7211 0.3845 0.72416673 1 P 0 ;0,1=269,2=270.000000
L 0.3845 0.72416673 0.3845 0.70883317 1 P 0 ;0,1=269,2=270.000000
L 0.474 2.392 0.43 2.392 1 P 0 
L 0.43 2.392 0.43 2.302 1 P 0 
L 0.43 2.302 0.474 2.302 1 P 0 
L 0.474 2.302 0.474 2.392 1 P 0 
L 0.4105 2.31583317 0.3795 2.31583317 1 P 0 ;0,1=270,2=270.000000
L 0.3795 2.31583317 0.3795 2.32541654 1 P 0 ;0,1=270,2=270.000000
L 0.3795 2.32541654 0.38105069 2.32848327 1 P 0 ;0,1=270,2=270.000000
L 0.38105069 2.32848327 0.38311693 2.3304002 1 P 0 ;0,1=270,2=270.000000
L 0.38311693 2.3304002 0.3872503 2.33116673 1 P 0 ;0,1=270,2=270.000000
L 0.3872503 2.33116673 0.39138366 2.3304002 1 P 0 ;0,1=270,2=270.000000
L 0.39138366 2.3304002 0.39396644 2.3281 1 P 0 ;0,1=270,2=270.000000
L 0.39396644 2.3281 0.39551713 2.32541654 1 P 0 ;0,1=270,2=270.000000
L 0.39551713 2.32541654 0.39551713 2.31583317 1 P 0 ;0,1=270,2=270.000000
L 0.39551713 2.32541654 0.4105 2.33116673 1 P 0 ;0,1=270,2=270.000000
L 0.4105 2.3591 0.3795 2.3591 1 P 0 ;0,1=270,2=270.000000
L 0.3795 2.3591 0.40171673 2.34491624 1 P 0 ;0,1=270,2=270.000000
L 0.40171673 2.34491624 0.40171673 2.36408366 1 P 0 ;0,1=270,2=270.000000
L 0.40688415 2.37898287 0.40946693 2.38166634 1 P 0 ;0,1=270,2=270.000000
L 0.40946693 2.38166634 0.4105 2.38473307 1 P 0 ;0,1=270,2=270.000000
L 0.4105 2.38473307 0.40946693 2.3877998 1 P 0 ;0,1=270,2=270.000000
L 0.40946693 2.3877998 0.40636762 2.39048327 1 P 0 ;0,1=270,2=270.000000
L 0.40636762 2.39048327 0.40171673 2.3924002 1 P 0 ;0,1=270,2=270.000000
L 0.40171673 2.3924002 0.39706673 2.39316673 1 P 0 ;0,1=270,2=270.000000
L 0.39706673 2.39316673 0.39138366 2.39316673 1 P 0 ;0,1=270,2=270.000000
L 0.39138366 2.39316673 0.38673376 2.3924002 1 P 0 ;0,1=270,2=270.000000
L 0.38673376 2.3924002 0.3826003 2.39048327 1 P 0 ;0,1=270,2=270.000000
L 0.3826003 2.39048327 0.38053317 2.38818307 1 P 0 ;0,1=270,2=270.000000
L 0.38053317 2.38818307 0.3795 2.38549961 1 P 0 ;0,1=270,2=270.000000
L 0.3795 2.38549961 0.38053317 2.38243287 1 P 0 ;0,1=270,2=270.000000
L 0.38053317 2.38243287 0.3826003 2.38013337 1 P 0 ;0,1=270,2=270.000000
L 0.3826003 2.38013337 0.3856997 2.3785997 1 P 0 ;0,1=270,2=270.000000
L 0.3856997 2.3785997 0.38983406 2.37783317 1 P 0 ;0,1=270,2=270.000000
L 0.38983406 2.37783317 0.3934499 2.3785997 1 P 0 ;0,1=270,2=270.000000
L 0.3934499 2.3785997 0.39706673 2.38051663 1 P 0 ;0,1=270,2=270.000000
L 0.39706673 2.38051663 0.39913396 2.38281683 1 P 0 ;0,1=270,2=270.000000
L 0.39913396 2.38281683 0.39965049 2.38549961 1 P 0 ;0,1=270,2=270.000000
L 0.39965049 2.38549961 0.39861732 2.38856634 1 P 0 ;0,1=270,2=270.000000
L 0.39861732 2.38856634 0.39603366 2.39086654 1 P 0 ;0,1=270,2=270.000000
L 0.39603366 2.39086654 0.39138366 2.39316673 1 P 0 ;0,1=270,2=270.000000
L 0.4105 2.41649961 0.40998346 2.41918307 1 P 0 ;0,1=270,2=270.000000
L 0.40998346 2.41918307 0.40843386 2.4222498 1 P 0 ;0,1=270,2=270.000000
L 0.40843386 2.4222498 0.40585108 2.42416673 1 P 0 ;0,1=270,2=270.000000
L 0.40585108 2.42416673 0.40223327 2.42493327 1 P 0 ;0,1=270,2=270.000000
L 0.40223327 2.42493327 0.39861732 2.42416673 1 P 0 ;0,1=270,2=270.000000
L 0.39861732 2.42416673 0.39551713 2.42186654 1 P 0 ;0,1=270,2=270.000000
L 0.39551713 2.42186654 0.39396644 2.41841654 1 P 0 ;0,1=270,2=270.000000
L 0.39396644 2.41841654 0.39396644 2.41458337 1 P 0 ;0,1=270,2=270.000000
L 0.39396644 2.41458337 0.39293337 2.41228317 1 P 0 ;0,1=270,2=270.000000
L 0.39293337 2.41228317 0.39035059 2.41036614 1 P 0 ;0,1=270,2=270.000000
L 0.39035059 2.41036614 0.38673376 2.4095997 1 P 0 ;0,1=270,2=270.000000
L 0.38673376 2.4095997 0.38311693 2.4107501 1 P 0 ;0,1=270,2=270.000000
L 0.38311693 2.4107501 0.38053317 2.41343287 1 P 0 ;0,1=270,2=270.000000
L 0.38053317 2.41343287 0.3795 2.41649961 1 P 0 ;0,1=270,2=270.000000
L 0.3795 2.41649961 0.38053317 2.41956634 1 P 0 ;0,1=270,2=270.000000
L 0.38053317 2.41956634 0.38311693 2.4222498 1 P 0 ;0,1=270,2=270.000000
L 0.38311693 2.4222498 0.38673376 2.4234002 1 P 0 ;0,1=270,2=270.000000
L 0.38673376 2.4234002 0.39035059 2.42263307 1 P 0 ;0,1=270,2=270.000000
L 0.39035059 2.42263307 0.39293337 2.42071673 1 P 0 ;0,1=270,2=270.000000
L 0.39293337 2.42071673 0.39396644 2.41841654 1 P 0 ;0,1=270,2=270.000000
L 0.39396644 2.41841654 0.39396644 2.41458337 1 P 0 ;0,1=270,2=270.000000
L 0.39396644 2.41458337 0.39551713 2.41113337 1 P 0 ;0,1=270,2=270.000000
L 0.39551713 2.41113337 0.39861732 2.40883317 1 P 0 ;0,1=270,2=270.000000
L 0.39861732 2.40883317 0.40223327 2.40806663 1 P 0 ;0,1=270,2=270.000000
L 0.40223327 2.40806663 0.40585108 2.40883317 1 P 0 ;0,1=270,2=270.000000
L 0.40585108 2.40883317 0.40843386 2.4107501 1 P 0 ;0,1=270,2=270.000000
L 0.40843386 2.4107501 0.40998346 2.41381683 1 P 0 ;0,1=270,2=270.000000
L 0.40998346 2.41381683 0.4105 2.41649961 1 P 0 ;0,1=270,2=270.000000
L 0.477 1.71 0.433 1.71 1 P 0 
L 0.477 1.62 0.477 1.71 1 P 0 
L 0.433 1.71 0.433 1.62 1 P 0 
L 0.433 1.62 0.477 1.62 1 P 0 
L 0.4205 1.62666654 0.3955 1.62666654 1 P 0 ;0,1=271,2=270.000000
L 0.3955 1.62666654 0.3955 1.63333327 1 P 0 ;0,1=271,2=270.000000
L 0.3955 1.63333327 0.39675059 1.63546663 1 P 0 ;0,1=271,2=270.000000
L 0.39675059 1.63546663 0.39841683 1.6368001 1 P 0 ;0,1=271,2=270.000000
L 0.39841683 1.6368001 0.4017502 1.63733337 1 P 0 ;0,1=271,2=270.000000
L 0.4017502 1.63733337 0.40508366 1.6368001 1 P 0 ;0,1=271,2=270.000000
L 0.40508366 1.6368001 0.40716654 1.6352 1 P 0 ;0,1=271,2=270.000000
L 0.40716654 1.6352 0.40841703 1.63333327 1 P 0 ;0,1=271,2=270.000000
L 0.40841703 1.63333327 0.40841703 1.62666654 1 P 0 ;0,1=271,2=270.000000
L 0.40841703 1.63333327 0.4205 1.63733337 1 P 0 ;0,1=271,2=270.000000
L 0.4205 1.6572 0.3955 1.6572 1 P 0 ;0,1=271,2=270.000000
L 0.3955 1.6572 0.41341673 1.64733297 1 P 0 ;0,1=271,2=270.000000
L 0.41341673 1.64733297 0.41341673 1.66066693 1 P 0 ;0,1=271,2=270.000000
L 0.41758396 1.67146634 0.41966693 1.67333317 1 P 0 ;0,1=271,2=270.000000
L 0.41966693 1.67333317 0.4205 1.67546654 1 P 0 ;0,1=271,2=270.000000
L 0.4205 1.67546654 0.41966693 1.6775999 1 P 0 ;0,1=271,2=270.000000
L 0.41966693 1.6775999 0.41716742 1.67946663 1 P 0 ;0,1=271,2=270.000000
L 0.41716742 1.67946663 0.41341673 1.6808001 1 P 0 ;0,1=271,2=270.000000
L 0.41341673 1.6808001 0.40966673 1.68133337 1 P 0 ;0,1=271,2=270.000000
L 0.40966673 1.68133337 0.40508366 1.68133337 1 P 0 ;0,1=271,2=270.000000
L 0.40508366 1.68133337 0.40133366 1.6808001 1 P 0 ;0,1=271,2=270.000000
L 0.40133366 1.6808001 0.3980003 1.67946663 1 P 0 ;0,1=271,2=270.000000
L 0.3980003 1.67946663 0.39633317 1.67786644 1 P 0 ;0,1=271,2=270.000000
L 0.39633317 1.67786644 0.3955 1.6759997 1 P 0 ;0,1=271,2=270.000000
L 0.3955 1.6759997 0.39633317 1.67386634 1 P 0 ;0,1=271,2=270.000000
L 0.39633317 1.67386634 0.3980003 1.67226663 1 P 0 ;0,1=271,2=270.000000
L 0.3980003 1.67226663 0.4004997 1.6711998 1 P 0 ;0,1=271,2=270.000000
L 0.4004997 1.6711998 0.40383386 1.67066654 1 P 0 ;0,1=271,2=270.000000
L 0.40383386 1.67066654 0.4067499 1.6711998 1 P 0 ;0,1=271,2=270.000000
L 0.4067499 1.6711998 0.40966673 1.67253327 1 P 0 ;0,1=271,2=270.000000
L 0.40966673 1.67253327 0.41133386 1.67413346 1 P 0 ;0,1=271,2=270.000000
L 0.41133386 1.67413346 0.41175039 1.6759997 1 P 0 ;0,1=271,2=270.000000
L 0.41175039 1.6759997 0.41091722 1.67813307 1 P 0 ;0,1=271,2=270.000000
L 0.41091722 1.67813307 0.40883356 1.67973327 1 P 0 ;0,1=271,2=270.000000
L 0.40883356 1.67973327 0.40508366 1.68133337 1 P 0 ;0,1=271,2=270.000000
L 0.41758396 1.69346634 0.41966693 1.69533317 1 P 0 ;0,1=271,2=270.000000
L 0.41966693 1.69533317 0.4205 1.69746654 1 P 0 ;0,1=271,2=270.000000
L 0.4205 1.69746654 0.41966693 1.6995999 1 P 0 ;0,1=271,2=270.000000
L 0.41966693 1.6995999 0.41716742 1.70146663 1 P 0 ;0,1=271,2=270.000000
L 0.41716742 1.70146663 0.41341673 1.7028001 1 P 0 ;0,1=271,2=270.000000
L 0.41341673 1.7028001 0.40966673 1.70333337 1 P 0 ;0,1=271,2=270.000000
L 0.40966673 1.70333337 0.40508366 1.70333337 1 P 0 ;0,1=271,2=270.000000
L 0.40508366 1.70333337 0.40133366 1.7028001 1 P 0 ;0,1=271,2=270.000000
L 0.40133366 1.7028001 0.3980003 1.70146663 1 P 0 ;0,1=271,2=270.000000
L 0.3980003 1.70146663 0.39633317 1.69986644 1 P 0 ;0,1=271,2=270.000000
L 0.39633317 1.69986644 0.3955 1.6979997 1 P 0 ;0,1=271,2=270.000000
L 0.3955 1.6979997 0.39633317 1.69586634 1 P 0 ;0,1=271,2=270.000000
L 0.39633317 1.69586634 0.3980003 1.69426663 1 P 0 ;0,1=271,2=270.000000
L 0.3980003 1.69426663 0.4004997 1.6931998 1 P 0 ;0,1=271,2=270.000000
L 0.4004997 1.6931998 0.40383386 1.69266654 1 P 0 ;0,1=271,2=270.000000
L 0.40383386 1.69266654 0.4067499 1.6931998 1 P 0 ;0,1=271,2=270.000000
L 0.4067499 1.6931998 0.40966673 1.69453327 1 P 0 ;0,1=271,2=270.000000
L 0.40966673 1.69453327 0.41133386 1.69613346 1 P 0 ;0,1=271,2=270.000000
L 0.41133386 1.69613346 0.41175039 1.6979997 1 P 0 ;0,1=271,2=270.000000
L 0.41175039 1.6979997 0.41091722 1.70013307 1 P 0 ;0,1=271,2=270.000000
L 0.41091722 1.70013307 0.40883356 1.70173327 1 P 0 ;0,1=271,2=270.000000
L 0.40883356 1.70173327 0.40508366 1.70333337 1 P 0 ;0,1=271,2=270.000000
L 1.813 3.005 1.813 2.915 1 P 0 
L 1.813 2.915 1.857 2.915 1 P 0 
L 1.857 2.915 1.857 3.005 1 P 0 
L 1.857 3.005 1.813 3.005 1 P 0 
L 1.9455 2.89083317 1.9145 2.89083317 1 P 0 ;0,1=272,2=270.000000
L 1.9145 2.89083317 1.9145 2.90041654 1 P 0 ;0,1=272,2=270.000000
L 1.9145 2.90041654 1.91605069 2.90348327 1 P 0 ;0,1=272,2=270.000000
L 1.91605069 2.90348327 1.91811693 2.9054002 1 P 0 ;0,1=272,2=270.000000
L 1.91811693 2.9054002 1.9222503 2.90616673 1 P 0 ;0,1=272,2=270.000000
L 1.9222503 2.90616673 1.92638366 2.9054002 1 P 0 ;0,1=272,2=270.000000
L 1.92638366 2.9054002 1.92896644 2.9031 1 P 0 ;0,1=272,2=270.000000
L 1.92896644 2.9031 1.93051713 2.90041654 1 P 0 ;0,1=272,2=270.000000
L 1.93051713 2.90041654 1.93051713 2.89083317 1 P 0 ;0,1=272,2=270.000000
L 1.93051713 2.90041654 1.9455 2.90616673 1 P 0 ;0,1=272,2=270.000000
L 1.9455 2.9341 1.9145 2.9341 1 P 0 ;0,1=272,2=270.000000
L 1.9145 2.9341 1.93671673 2.91991624 1 P 0 ;0,1=272,2=270.000000
L 1.93671673 2.91991624 1.93671673 2.93908366 1 P 0 ;0,1=272,2=270.000000
L 1.9455 2.96049961 1.94498346 2.96318307 1 P 0 ;0,1=272,2=270.000000
L 1.94498346 2.96318307 1.94343386 2.9662498 1 P 0 ;0,1=272,2=270.000000
L 1.94343386 2.9662498 1.94085108 2.96816673 1 P 0 ;0,1=272,2=270.000000
L 1.94085108 2.96816673 1.93723327 2.96893327 1 P 0 ;0,1=272,2=270.000000
L 1.93723327 2.96893327 1.93361732 2.96816673 1 P 0 ;0,1=272,2=270.000000
L 1.93361732 2.96816673 1.93051713 2.96586654 1 P 0 ;0,1=272,2=270.000000
L 1.93051713 2.96586654 1.92896644 2.96241654 1 P 0 ;0,1=272,2=270.000000
L 1.92896644 2.96241654 1.92896644 2.95858337 1 P 0 ;0,1=272,2=270.000000
L 1.92896644 2.95858337 1.92793337 2.95628317 1 P 0 ;0,1=272,2=270.000000
L 1.92793337 2.95628317 1.92535059 2.95436614 1 P 0 ;0,1=272,2=270.000000
L 1.92535059 2.95436614 1.92173376 2.9535997 1 P 0 ;0,1=272,2=270.000000
L 1.92173376 2.9535997 1.91811693 2.9547501 1 P 0 ;0,1=272,2=270.000000
L 1.91811693 2.9547501 1.91553317 2.95743287 1 P 0 ;0,1=272,2=270.000000
L 1.91553317 2.95743287 1.9145 2.96049961 1 P 0 ;0,1=272,2=270.000000
L 1.9145 2.96049961 1.91553317 2.96356634 1 P 0 ;0,1=272,2=270.000000
L 1.91553317 2.96356634 1.91811693 2.9662498 1 P 0 ;0,1=272,2=270.000000
L 1.91811693 2.9662498 1.92173376 2.9674002 1 P 0 ;0,1=272,2=270.000000
L 1.92173376 2.9674002 1.92535059 2.96663307 1 P 0 ;0,1=272,2=270.000000
L 1.92535059 2.96663307 1.92793337 2.96471673 1 P 0 ;0,1=272,2=270.000000
L 1.92793337 2.96471673 1.92896644 2.96241654 1 P 0 ;0,1=272,2=270.000000
L 1.92896644 2.96241654 1.92896644 2.95858337 1 P 0 ;0,1=272,2=270.000000
L 1.92896644 2.95858337 1.93051713 2.95513337 1 P 0 ;0,1=272,2=270.000000
L 1.93051713 2.95513337 1.93361732 2.95283317 1 P 0 ;0,1=272,2=270.000000
L 1.93361732 2.95283317 1.93723327 2.95206663 1 P 0 ;0,1=272,2=270.000000
L 1.93723327 2.95206663 1.94085108 2.95283317 1 P 0 ;0,1=272,2=270.000000
L 1.94085108 2.95283317 1.94343386 2.9547501 1 P 0 ;0,1=272,2=270.000000
L 1.94343386 2.9547501 1.94498346 2.95781683 1 P 0 ;0,1=272,2=270.000000
L 1.94498346 2.95781683 1.9455 2.96049961 1 P 0 ;0,1=272,2=270.000000
L 1.9455 2.99073307 1.93878386 2.99149961 1 P 0 ;0,1=272,2=270.000000
L 1.93878386 2.99149961 1.93310079 2.9926501 1 P 0 ;0,1=272,2=270.000000
L 1.93310079 2.9926501 1.92793337 2.99418307 1 P 0 ;0,1=272,2=270.000000
L 1.92793337 2.99418307 1.9222503 2.9961 1 P 0 ;0,1=272,2=270.000000
L 1.9222503 2.9961 1.9145 2.99916673 1 P 0 ;0,1=272,2=270.000000
L 1.9145 2.99916673 1.9145 2.98383317 1 P 0 ;0,1=272,2=270.000000
L 4.36 3.678 4.45 3.678 1 P 0 
L 4.45 3.678 4.45 3.722 1 P 0 
L 4.45 3.722 4.36 3.722 1 P 0 
L 4.36 3.722 4.36 3.678 1 P 0 
L 4.47583317 3.6895 4.47583317 3.7205 1 P 0 ;0,1=273,2=0.000000
L 4.47583317 3.7205 4.48541654 3.7205 1 P 0 ;0,1=273,2=0.000000
L 4.48541654 3.7205 4.48848327 3.71894931 1 P 0 ;0,1=273,2=0.000000
L 4.48848327 3.71894931 4.4904002 3.71688307 1 P 0 ;0,1=273,2=0.000000
L 4.4904002 3.71688307 4.49116673 3.7127497 1 P 0 ;0,1=273,2=0.000000
L 4.49116673 3.7127497 4.4904002 3.70861634 1 P 0 ;0,1=273,2=0.000000
L 4.4904002 3.70861634 4.4881 3.70603356 1 P 0 ;0,1=273,2=0.000000
L 4.4881 3.70603356 4.48541654 3.70448287 1 P 0 ;0,1=273,2=0.000000
L 4.48541654 3.70448287 4.47583317 3.70448287 1 P 0 ;0,1=273,2=0.000000
L 4.48541654 3.70448287 4.49116673 3.6895 1 P 0 ;0,1=273,2=0.000000
L 4.5191 3.6895 4.5191 3.7205 1 P 0 ;0,1=273,2=0.000000
L 4.5191 3.7205 4.50491624 3.69828327 1 P 0 ;0,1=273,2=0.000000
L 4.50491624 3.69828327 4.52408366 3.69828327 1 P 0 ;0,1=273,2=0.000000
L 4.53706663 3.69414892 4.53936614 3.69156614 1 P 0 ;0,1=273,2=0.000000
L 4.53936614 3.69156614 4.54204961 3.69001654 1 P 0 ;0,1=273,2=0.000000
L 4.54204961 3.69001654 4.54549961 3.6895 1 P 0 ;0,1=273,2=0.000000
L 4.54549961 3.6895 4.5489503 3.69053307 1 P 0 ;0,1=273,2=0.000000
L 4.5489503 3.69053307 4.55163307 3.69259931 1 P 0 ;0,1=273,2=0.000000
L 4.55163307 3.69259931 4.55355 3.69621614 1 P 0 ;0,1=273,2=0.000000
L 4.55355 3.69621614 4.55393327 3.70034951 1 P 0 ;0,1=273,2=0.000000
L 4.55393327 3.70034951 4.55316673 3.70448287 1 P 0 ;0,1=273,2=0.000000
L 4.55316673 3.70448287 4.5512498 3.70706663 1 P 0 ;0,1=273,2=0.000000
L 4.5512498 3.70706663 4.54856634 3.70913287 1 P 0 ;0,1=273,2=0.000000
L 4.54856634 3.70913287 4.54588356 3.70964941 1 P 0 ;0,1=273,2=0.000000
L 4.54588356 3.70964941 4.5432001 3.70913287 1 P 0 ;0,1=273,2=0.000000
L 4.5432001 3.70913287 4.5397501 3.70706663 1 P 0 ;0,1=273,2=0.000000
L 4.5397501 3.70706663 4.5408999 3.7205 1 P 0 ;0,1=273,2=0.000000
L 4.5408999 3.7205 4.5512498 3.7205 1 P 0 ;0,1=273,2=0.000000
L 4.56921644 3.71533346 4.57151663 3.71843278 1 P 0 ;0,1=273,2=0.000000
L 4.57151663 3.71843278 4.5742001 3.71998337 1 P 0 ;0,1=273,2=0.000000
L 4.5742001 3.71998337 4.57726683 3.7205 1 P 0 ;0,1=273,2=0.000000
L 4.57726683 3.7205 4.5811 3.71946683 1 P 0 ;0,1=273,2=0.000000
L 4.5811 3.71946683 4.58378346 3.71688307 1 P 0 ;0,1=273,2=0.000000
L 4.58378346 3.71688307 4.58455 3.71378376 1 P 0 ;0,1=273,2=0.000000
L 4.58455 3.71378376 4.58416673 3.71068258 1 P 0 ;0,1=273,2=0.000000
L 4.58416673 3.71068258 4.58263307 3.7080998 1 P 0 ;0,1=273,2=0.000000
L 4.58263307 3.7080998 4.57496663 3.70293327 1 P 0 ;0,1=273,2=0.000000
L 4.57496663 3.70293327 4.57151663 3.69931644 1 P 0 ;0,1=273,2=0.000000
L 4.57151663 3.69931644 4.56921644 3.69414892 1 P 0 ;0,1=273,2=0.000000
L 4.56921644 3.69414892 4.5684499 3.6895 1 P 0 ;0,1=273,2=0.000000
L 4.5684499 3.6895 4.58455 3.6895 1 P 0 ;0,1=273,2=0.000000
L 4.76 0.893 4.76 0.937 1 P 0 
L 4.76 0.937 4.67 0.937 1 P 0 
L 4.67 0.893 4.76 0.893 1 P 0 
L 4.67 0.937 4.67 0.893 1 P 0 
L 4.55083317 0.8795 4.55083317 0.9105 1 P 0 ;0,1=274,2=0.000000
L 4.55083317 0.9105 4.56041654 0.9105 1 P 0 ;0,1=274,2=0.000000
L 4.56041654 0.9105 4.56348327 0.90894931 1 P 0 ;0,1=274,2=0.000000
L 4.56348327 0.90894931 4.5654002 0.90688307 1 P 0 ;0,1=274,2=0.000000
L 4.5654002 0.90688307 4.56616673 0.9027497 1 P 0 ;0,1=274,2=0.000000
L 4.56616673 0.9027497 4.5654002 0.89861634 1 P 0 ;0,1=274,2=0.000000
L 4.5654002 0.89861634 4.5631 0.89603356 1 P 0 ;0,1=274,2=0.000000
L 4.5631 0.89603356 4.56041654 0.89448287 1 P 0 ;0,1=274,2=0.000000
L 4.56041654 0.89448287 4.55083317 0.89448287 1 P 0 ;0,1=274,2=0.000000
L 4.56041654 0.89448287 4.56616673 0.8795 1 P 0 ;0,1=274,2=0.000000
L 4.5941 0.8795 4.5941 0.9105 1 P 0 ;0,1=274,2=0.000000
L 4.5941 0.9105 4.57991624 0.88828327 1 P 0 ;0,1=274,2=0.000000
L 4.57991624 0.88828327 4.59908366 0.88828327 1 P 0 ;0,1=274,2=0.000000
L 4.62049961 0.8795 4.62318307 0.88001654 1 P 0 ;0,1=274,2=0.000000
L 4.62318307 0.88001654 4.6262498 0.88156614 1 P 0 ;0,1=274,2=0.000000
L 4.6262498 0.88156614 4.62816673 0.88414892 1 P 0 ;0,1=274,2=0.000000
L 4.62816673 0.88414892 4.62893327 0.88776673 1 P 0 ;0,1=274,2=0.000000
L 4.62893327 0.88776673 4.62816673 0.89138268 1 P 0 ;0,1=274,2=0.000000
L 4.62816673 0.89138268 4.62586654 0.89448287 1 P 0 ;0,1=274,2=0.000000
L 4.62586654 0.89448287 4.62241654 0.89603356 1 P 0 ;0,1=274,2=0.000000
L 4.62241654 0.89603356 4.61858337 0.89603356 1 P 0 ;0,1=274,2=0.000000
L 4.61858337 0.89603356 4.61628317 0.89706663 1 P 0 ;0,1=274,2=0.000000
L 4.61628317 0.89706663 4.61436614 0.89964941 1 P 0 ;0,1=274,2=0.000000
L 4.61436614 0.89964941 4.6135997 0.90326624 1 P 0 ;0,1=274,2=0.000000
L 4.6135997 0.90326624 4.6147501 0.90688307 1 P 0 ;0,1=274,2=0.000000
L 4.6147501 0.90688307 4.61743287 0.90946683 1 P 0 ;0,1=274,2=0.000000
L 4.61743287 0.90946683 4.62049961 0.9105 1 P 0 ;0,1=274,2=0.000000
L 4.62049961 0.9105 4.62356634 0.90946683 1 P 0 ;0,1=274,2=0.000000
L 4.62356634 0.90946683 4.6262498 0.90688307 1 P 0 ;0,1=274,2=0.000000
L 4.6262498 0.90688307 4.6274002 0.90326624 1 P 0 ;0,1=274,2=0.000000
L 4.6274002 0.90326624 4.62663307 0.89964941 1 P 0 ;0,1=274,2=0.000000
L 4.62663307 0.89964941 4.62471673 0.89706663 1 P 0 ;0,1=274,2=0.000000
L 4.62471673 0.89706663 4.62241654 0.89603356 1 P 0 ;0,1=274,2=0.000000
L 4.62241654 0.89603356 4.61858337 0.89603356 1 P 0 ;0,1=274,2=0.000000
L 4.61858337 0.89603356 4.61513337 0.89448287 1 P 0 ;0,1=274,2=0.000000
L 4.61513337 0.89448287 4.61283317 0.89138268 1 P 0 ;0,1=274,2=0.000000
L 4.61283317 0.89138268 4.61206663 0.88776673 1 P 0 ;0,1=274,2=0.000000
L 4.61206663 0.88776673 4.61283317 0.88414892 1 P 0 ;0,1=274,2=0.000000
L 4.61283317 0.88414892 4.6147501 0.88156614 1 P 0 ;0,1=274,2=0.000000
L 4.6147501 0.88156614 4.61781683 0.88001654 1 P 0 ;0,1=274,2=0.000000
L 4.61781683 0.88001654 4.62049961 0.8795 1 P 0 ;0,1=274,2=0.000000
L 4.64421644 0.89241575 4.6468999 0.89603356 1 P 0 ;0,1=274,2=0.000000
L 4.6468999 0.89603356 4.6492001 0.8980998 1 P 0 ;0,1=274,2=0.000000
L 4.6492001 0.8980998 4.65226683 0.89913287 1 P 0 ;0,1=274,2=0.000000
L 4.65226683 0.89913287 4.6549503 0.8980998 1 P 0 ;0,1=274,2=0.000000
L 4.6549503 0.8980998 4.65686654 0.89603356 1 P 0 ;0,1=274,2=0.000000
L 4.65686654 0.89603356 4.6584002 0.89293327 1 P 0 ;0,1=274,2=0.000000
L 4.6584002 0.89293327 4.65878346 0.88931644 1 P 0 ;0,1=274,2=0.000000
L 4.65878346 0.88931644 4.6584002 0.88621614 1 P 0 ;0,1=274,2=0.000000
L 4.6584002 0.88621614 4.65686654 0.88311585 1 P 0 ;0,1=274,2=0.000000
L 4.65686654 0.88311585 4.65456634 0.88053307 1 P 0 ;0,1=274,2=0.000000
L 4.65456634 0.88053307 4.65188356 0.8795 1 P 0 ;0,1=274,2=0.000000
L 4.65188356 0.8795 4.64881683 0.88053307 1 P 0 ;0,1=274,2=0.000000
L 4.64881683 0.88053307 4.64613337 0.88363238 1 P 0 ;0,1=274,2=0.000000
L 4.64613337 0.88363238 4.6445997 0.88828327 1 P 0 ;0,1=274,2=0.000000
L 4.6445997 0.88828327 4.64421644 0.8934498 1 P 0 ;0,1=274,2=0.000000
L 4.64421644 0.8934498 4.64498287 0.90016594 1 P 0 ;0,1=274,2=0.000000
L 4.64498287 0.90016594 4.64613337 0.90378376 1 P 0 ;0,1=274,2=0.000000
L 4.64613337 0.90378376 4.64804961 0.9073997 1 P 0 ;0,1=274,2=0.000000
L 4.64804961 0.9073997 4.65073307 0.90998337 1 P 0 ;0,1=274,2=0.000000
L 4.65073307 0.90998337 4.65341654 0.9105 1 P 0 ;0,1=274,2=0.000000
L 4.65341654 0.9105 4.6561 0.90946683 1 P 0 ;0,1=274,2=0.000000
L 4.6561 0.90946683 4.65801703 0.90688307 1 P 0 ;0,1=274,2=0.000000
L 4.76 0.943 4.76 0.987 1 P 0 
L 4.67 0.943 4.76 0.943 1 P 0 
L 4.76 0.987 4.67 0.987 1 P 0 
L 4.67 0.987 4.67 0.943 1 P 0 
L 4.55083317 0.9545 4.55083317 0.9855 1 P 0 ;0,1=275,2=0.000000
L 4.55083317 0.9855 4.56041654 0.9855 1 P 0 ;0,1=275,2=0.000000
L 4.56041654 0.9855 4.56348327 0.98394931 1 P 0 ;0,1=275,2=0.000000
L 4.56348327 0.98394931 4.5654002 0.98188307 1 P 0 ;0,1=275,2=0.000000
L 4.5654002 0.98188307 4.56616673 0.9777497 1 P 0 ;0,1=275,2=0.000000
L 4.56616673 0.9777497 4.5654002 0.97361634 1 P 0 ;0,1=275,2=0.000000
L 4.5654002 0.97361634 4.5631 0.97103356 1 P 0 ;0,1=275,2=0.000000
L 4.5631 0.97103356 4.56041654 0.96948287 1 P 0 ;0,1=275,2=0.000000
L 4.56041654 0.96948287 4.55083317 0.96948287 1 P 0 ;0,1=275,2=0.000000
L 4.56041654 0.96948287 4.56616673 0.9545 1 P 0 ;0,1=275,2=0.000000
L 4.5941 0.9545 4.5941 0.9855 1 P 0 ;0,1=275,2=0.000000
L 4.5941 0.9855 4.57991624 0.96328327 1 P 0 ;0,1=275,2=0.000000
L 4.57991624 0.96328327 4.59908366 0.96328327 1 P 0 ;0,1=275,2=0.000000
L 4.62049961 0.9545 4.62318307 0.95501654 1 P 0 ;0,1=275,2=0.000000
L 4.62318307 0.95501654 4.6262498 0.95656614 1 P 0 ;0,1=275,2=0.000000
L 4.6262498 0.95656614 4.62816673 0.95914892 1 P 0 ;0,1=275,2=0.000000
L 4.62816673 0.95914892 4.62893327 0.96276673 1 P 0 ;0,1=275,2=0.000000
L 4.62893327 0.96276673 4.62816673 0.96638268 1 P 0 ;0,1=275,2=0.000000
L 4.62816673 0.96638268 4.62586654 0.96948287 1 P 0 ;0,1=275,2=0.000000
L 4.62586654 0.96948287 4.62241654 0.97103356 1 P 0 ;0,1=275,2=0.000000
L 4.62241654 0.97103356 4.61858337 0.97103356 1 P 0 ;0,1=275,2=0.000000
L 4.61858337 0.97103356 4.61628317 0.97206663 1 P 0 ;0,1=275,2=0.000000
L 4.61628317 0.97206663 4.61436614 0.97464941 1 P 0 ;0,1=275,2=0.000000
L 4.61436614 0.97464941 4.6135997 0.97826624 1 P 0 ;0,1=275,2=0.000000
L 4.6135997 0.97826624 4.6147501 0.98188307 1 P 0 ;0,1=275,2=0.000000
L 4.6147501 0.98188307 4.61743287 0.98446683 1 P 0 ;0,1=275,2=0.000000
L 4.61743287 0.98446683 4.62049961 0.9855 1 P 0 ;0,1=275,2=0.000000
L 4.62049961 0.9855 4.62356634 0.98446683 1 P 0 ;0,1=275,2=0.000000
L 4.62356634 0.98446683 4.6262498 0.98188307 1 P 0 ;0,1=275,2=0.000000
L 4.6262498 0.98188307 4.6274002 0.97826624 1 P 0 ;0,1=275,2=0.000000
L 4.6274002 0.97826624 4.62663307 0.97464941 1 P 0 ;0,1=275,2=0.000000
L 4.62663307 0.97464941 4.62471673 0.97206663 1 P 0 ;0,1=275,2=0.000000
L 4.62471673 0.97206663 4.62241654 0.97103356 1 P 0 ;0,1=275,2=0.000000
L 4.62241654 0.97103356 4.61858337 0.97103356 1 P 0 ;0,1=275,2=0.000000
L 4.61858337 0.97103356 4.61513337 0.96948287 1 P 0 ;0,1=275,2=0.000000
L 4.61513337 0.96948287 4.61283317 0.96638268 1 P 0 ;0,1=275,2=0.000000
L 4.61283317 0.96638268 4.61206663 0.96276673 1 P 0 ;0,1=275,2=0.000000
L 4.61206663 0.96276673 4.61283317 0.95914892 1 P 0 ;0,1=275,2=0.000000
L 4.61283317 0.95914892 4.6147501 0.95656614 1 P 0 ;0,1=275,2=0.000000
L 4.6147501 0.95656614 4.61781683 0.95501654 1 P 0 ;0,1=275,2=0.000000
L 4.61781683 0.95501654 4.62049961 0.9545 1 P 0 ;0,1=275,2=0.000000
L 4.64306663 0.95914892 4.64536614 0.95656614 1 P 0 ;0,1=275,2=0.000000
L 4.64536614 0.95656614 4.64804961 0.95501654 1 P 0 ;0,1=275,2=0.000000
L 4.64804961 0.95501654 4.65149961 0.9545 1 P 0 ;0,1=275,2=0.000000
L 4.65149961 0.9545 4.6549503 0.95553307 1 P 0 ;0,1=275,2=0.000000
L 4.6549503 0.95553307 4.65763307 0.95759931 1 P 0 ;0,1=275,2=0.000000
L 4.65763307 0.95759931 4.65955 0.96121614 1 P 0 ;0,1=275,2=0.000000
L 4.65955 0.96121614 4.65993327 0.96534951 1 P 0 ;0,1=275,2=0.000000
L 4.65993327 0.96534951 4.65916673 0.96948287 1 P 0 ;0,1=275,2=0.000000
L 4.65916673 0.96948287 4.6572498 0.97206663 1 P 0 ;0,1=275,2=0.000000
L 4.6572498 0.97206663 4.65456634 0.97413287 1 P 0 ;0,1=275,2=0.000000
L 4.65456634 0.97413287 4.65188356 0.97464941 1 P 0 ;0,1=275,2=0.000000
L 4.65188356 0.97464941 4.6492001 0.97413287 1 P 0 ;0,1=275,2=0.000000
L 4.6492001 0.97413287 4.6457501 0.97206663 1 P 0 ;0,1=275,2=0.000000
L 4.6457501 0.97206663 4.6468999 0.9855 1 P 0 ;0,1=275,2=0.000000
L 4.6468999 0.9855 4.6572498 0.9855 1 P 0 ;0,1=275,2=0.000000
L 0.77 3.222 0.68 3.222 1 P 0 
L 0.77 3.178 0.77 3.222 1 P 0 
L 0.68 3.178 0.77 3.178 1 P 0 
L 0.68 3.222 0.68 3.178 1 P 0 
L 0.64583317 3.0945 0.64583317 3.1255 1 P 0 ;0,1=276,2=0.000000
L 0.64583317 3.1255 0.65541654 3.1255 1 P 0 ;0,1=276,2=0.000000
L 0.65541654 3.1255 0.65848327 3.12394931 1 P 0 ;0,1=276,2=0.000000
L 0.65848327 3.12394931 0.6604002 3.12188307 1 P 0 ;0,1=276,2=0.000000
L 0.6604002 3.12188307 0.66116673 3.1177497 1 P 0 ;0,1=276,2=0.000000
L 0.66116673 3.1177497 0.6604002 3.11361634 1 P 0 ;0,1=276,2=0.000000
L 0.6604002 3.11361634 0.6581 3.11103356 1 P 0 ;0,1=276,2=0.000000
L 0.6581 3.11103356 0.65541654 3.10948287 1 P 0 ;0,1=276,2=0.000000
L 0.65541654 3.10948287 0.64583317 3.10948287 1 P 0 ;0,1=276,2=0.000000
L 0.65541654 3.10948287 0.66116673 3.0945 1 P 0 ;0,1=276,2=0.000000
L 0.6891 3.0945 0.6891 3.1255 1 P 0 ;0,1=276,2=0.000000
L 0.6891 3.1255 0.67491624 3.10328327 1 P 0 ;0,1=276,2=0.000000
L 0.67491624 3.10328327 0.69408366 3.10328327 1 P 0 ;0,1=276,2=0.000000
L 0.71473307 3.0945 0.71549961 3.10121614 1 P 0 ;0,1=276,2=0.000000
L 0.71549961 3.10121614 0.7166501 3.10689921 1 P 0 ;0,1=276,2=0.000000
L 0.7166501 3.10689921 0.71818307 3.11206663 1 P 0 ;0,1=276,2=0.000000
L 0.71818307 3.11206663 0.7201 3.1177497 1 P 0 ;0,1=276,2=0.000000
L 0.7201 3.1177497 0.72316673 3.1255 1 P 0 ;0,1=276,2=0.000000
L 0.72316673 3.1255 0.70783317 3.1255 1 P 0 ;0,1=276,2=0.000000
L 0.73921644 3.12033346 0.74151663 3.12343278 1 P 0 ;0,1=276,2=0.000000
L 0.74151663 3.12343278 0.7442001 3.12498337 1 P 0 ;0,1=276,2=0.000000
L 0.7442001 3.12498337 0.74726683 3.1255 1 P 0 ;0,1=276,2=0.000000
L 0.74726683 3.1255 0.7511 3.12446683 1 P 0 ;0,1=276,2=0.000000
L 0.7511 3.12446683 0.75378346 3.12188307 1 P 0 ;0,1=276,2=0.000000
L 0.75378346 3.12188307 0.75455 3.11878376 1 P 0 ;0,1=276,2=0.000000
L 0.75455 3.11878376 0.75416673 3.11568258 1 P 0 ;0,1=276,2=0.000000
L 0.75416673 3.11568258 0.75263307 3.1130998 1 P 0 ;0,1=276,2=0.000000
L 0.75263307 3.1130998 0.74496663 3.10793327 1 P 0 ;0,1=276,2=0.000000
L 0.74496663 3.10793327 0.74151663 3.10431644 1 P 0 ;0,1=276,2=0.000000
L 0.74151663 3.10431644 0.73921644 3.09914892 1 P 0 ;0,1=276,2=0.000000
L 0.73921644 3.09914892 0.7384499 3.0945 1 P 0 ;0,1=276,2=0.000000
L 0.7384499 3.0945 0.75455 3.0945 1 P 0 ;0,1=276,2=0.000000
L 0.77 3.223 0.77 3.267 1 P 0 
L 0.68 3.223 0.77 3.223 1 P 0 
L 0.68 3.267 0.68 3.223 1 P 0 
L 0.77 3.267 0.68 3.267 1 P 0 
L 0.64583317 3.1395 0.64583317 3.1705 1 P 0 ;0,1=277,2=0.000000
L 0.64583317 3.1705 0.65541654 3.1705 1 P 0 ;0,1=277,2=0.000000
L 0.65541654 3.1705 0.65848327 3.16894931 1 P 0 ;0,1=277,2=0.000000
L 0.65848327 3.16894931 0.6604002 3.16688307 1 P 0 ;0,1=277,2=0.000000
L 0.6604002 3.16688307 0.66116673 3.1627497 1 P 0 ;0,1=277,2=0.000000
L 0.66116673 3.1627497 0.6604002 3.15861634 1 P 0 ;0,1=277,2=0.000000
L 0.6604002 3.15861634 0.6581 3.15603356 1 P 0 ;0,1=277,2=0.000000
L 0.6581 3.15603356 0.65541654 3.15448287 1 P 0 ;0,1=277,2=0.000000
L 0.65541654 3.15448287 0.64583317 3.15448287 1 P 0 ;0,1=277,2=0.000000
L 0.65541654 3.15448287 0.66116673 3.1395 1 P 0 ;0,1=277,2=0.000000
L 0.6891 3.1395 0.6891 3.1705 1 P 0 ;0,1=277,2=0.000000
L 0.6891 3.1705 0.67491624 3.14828327 1 P 0 ;0,1=277,2=0.000000
L 0.67491624 3.14828327 0.69408366 3.14828327 1 P 0 ;0,1=277,2=0.000000
L 0.71473307 3.1395 0.71549961 3.14621614 1 P 0 ;0,1=277,2=0.000000
L 0.71549961 3.14621614 0.7166501 3.15189921 1 P 0 ;0,1=277,2=0.000000
L 0.7166501 3.15189921 0.71818307 3.15706663 1 P 0 ;0,1=277,2=0.000000
L 0.71818307 3.15706663 0.7201 3.1627497 1 P 0 ;0,1=277,2=0.000000
L 0.7201 3.1627497 0.72316673 3.1705 1 P 0 ;0,1=277,2=0.000000
L 0.72316673 3.1705 0.70783317 3.1705 1 P 0 ;0,1=277,2=0.000000
L 0.74649961 3.1395 0.74649961 3.1705 1 P 0 ;0,1=277,2=0.000000
L 0.74649961 3.1705 0.7418999 3.1643003 1 P 0 ;0,1=277,2=0.000000
L 0.7418999 3.1395 0.75109931 3.1395 1 P 0 ;0,1=277,2=0.000000
L 4.039 3.217 4.039 3.261 1 P 0 
L 3.949 3.217 4.039 3.217 1 P 0 
L 4.039 3.261 3.949 3.261 1 P 0 
L 3.949 3.261 3.949 3.217 1 P 0 
L 3.83583317 3.1945 3.83583317 3.2255 1 P 0 ;0,1=278,2=0.000000
L 3.83583317 3.2255 3.84541654 3.2255 1 P 0 ;0,1=278,2=0.000000
L 3.84541654 3.2255 3.84848327 3.22394931 1 P 0 ;0,1=278,2=0.000000
L 3.84848327 3.22394931 3.8504002 3.22188307 1 P 0 ;0,1=278,2=0.000000
L 3.8504002 3.22188307 3.85116673 3.2177497 1 P 0 ;0,1=278,2=0.000000
L 3.85116673 3.2177497 3.8504002 3.21361634 1 P 0 ;0,1=278,2=0.000000
L 3.8504002 3.21361634 3.8481 3.21103356 1 P 0 ;0,1=278,2=0.000000
L 3.8481 3.21103356 3.84541654 3.20948287 1 P 0 ;0,1=278,2=0.000000
L 3.84541654 3.20948287 3.83583317 3.20948287 1 P 0 ;0,1=278,2=0.000000
L 3.84541654 3.20948287 3.85116673 3.1945 1 P 0 ;0,1=278,2=0.000000
L 3.8791 3.1945 3.8791 3.2255 1 P 0 ;0,1=278,2=0.000000
L 3.8791 3.2255 3.86491624 3.20328327 1 P 0 ;0,1=278,2=0.000000
L 3.86491624 3.20328327 3.88408366 3.20328327 1 P 0 ;0,1=278,2=0.000000
L 3.89821644 3.20741575 3.9008999 3.21103356 1 P 0 ;0,1=278,2=0.000000
L 3.9008999 3.21103356 3.9032001 3.2130998 1 P 0 ;0,1=278,2=0.000000
L 3.9032001 3.2130998 3.90626683 3.21413287 1 P 0 ;0,1=278,2=0.000000
L 3.90626683 3.21413287 3.9089503 3.2130998 1 P 0 ;0,1=278,2=0.000000
L 3.9089503 3.2130998 3.91086654 3.21103356 1 P 0 ;0,1=278,2=0.000000
L 3.91086654 3.21103356 3.9124002 3.20793327 1 P 0 ;0,1=278,2=0.000000
L 3.9124002 3.20793327 3.91278346 3.20431644 1 P 0 ;0,1=278,2=0.000000
L 3.91278346 3.20431644 3.9124002 3.20121614 1 P 0 ;0,1=278,2=0.000000
L 3.9124002 3.20121614 3.91086654 3.19811585 1 P 0 ;0,1=278,2=0.000000
L 3.91086654 3.19811585 3.90856634 3.19553307 1 P 0 ;0,1=278,2=0.000000
L 3.90856634 3.19553307 3.90588356 3.1945 1 P 0 ;0,1=278,2=0.000000
L 3.90588356 3.1945 3.90281683 3.19553307 1 P 0 ;0,1=278,2=0.000000
L 3.90281683 3.19553307 3.90013337 3.19863238 1 P 0 ;0,1=278,2=0.000000
L 3.90013337 3.19863238 3.8985997 3.20328327 1 P 0 ;0,1=278,2=0.000000
L 3.8985997 3.20328327 3.89821644 3.2084498 1 P 0 ;0,1=278,2=0.000000
L 3.89821644 3.2084498 3.89898287 3.21516594 1 P 0 ;0,1=278,2=0.000000
L 3.89898287 3.21516594 3.90013337 3.21878376 1 P 0 ;0,1=278,2=0.000000
L 3.90013337 3.21878376 3.90204961 3.2223997 1 P 0 ;0,1=278,2=0.000000
L 3.90204961 3.2223997 3.90473307 3.22498337 1 P 0 ;0,1=278,2=0.000000
L 3.90473307 3.22498337 3.90741654 3.2255 1 P 0 ;0,1=278,2=0.000000
L 3.90741654 3.2255 3.9101 3.22446683 1 P 0 ;0,1=278,2=0.000000
L 3.9101 3.22446683 3.91201703 3.22188307 1 P 0 ;0,1=278,2=0.000000
L 3.92921644 3.22033346 3.93151663 3.22343278 1 P 0 ;0,1=278,2=0.000000
L 3.93151663 3.22343278 3.9342001 3.22498337 1 P 0 ;0,1=278,2=0.000000
L 3.9342001 3.22498337 3.93726683 3.2255 1 P 0 ;0,1=278,2=0.000000
L 3.93726683 3.2255 3.9411 3.22446683 1 P 0 ;0,1=278,2=0.000000
L 3.9411 3.22446683 3.94378346 3.22188307 1 P 0 ;0,1=278,2=0.000000
L 3.94378346 3.22188307 3.94455 3.21878376 1 P 0 ;0,1=278,2=0.000000
L 3.94455 3.21878376 3.94416673 3.21568258 1 P 0 ;0,1=278,2=0.000000
L 3.94416673 3.21568258 3.94263307 3.2130998 1 P 0 ;0,1=278,2=0.000000
L 3.94263307 3.2130998 3.93496663 3.20793327 1 P 0 ;0,1=278,2=0.000000
L 3.93496663 3.20793327 3.93151663 3.20431644 1 P 0 ;0,1=278,2=0.000000
L 3.93151663 3.20431644 3.92921644 3.19914892 1 P 0 ;0,1=278,2=0.000000
L 3.92921644 3.19914892 3.9284499 3.1945 1 P 0 ;0,1=278,2=0.000000
L 3.9284499 3.1945 3.94455 3.1945 1 P 0 ;0,1=278,2=0.000000
L 4.039 3.269 4.039 3.313 1 P 0 
L 3.949 3.269 4.039 3.269 1 P 0 
L 4.039 3.313 3.949 3.313 1 P 0 
L 3.949 3.313 3.949 3.269 1 P 0 
L 3.84083317 3.3045 3.84083317 3.3355 1 P 0 ;0,1=279,2=0.000000
L 3.84083317 3.3355 3.85041654 3.3355 1 P 0 ;0,1=279,2=0.000000
L 3.85041654 3.3355 3.85348327 3.33394931 1 P 0 ;0,1=279,2=0.000000
L 3.85348327 3.33394931 3.8554002 3.33188307 1 P 0 ;0,1=279,2=0.000000
L 3.8554002 3.33188307 3.85616673 3.3277497 1 P 0 ;0,1=279,2=0.000000
L 3.85616673 3.3277497 3.8554002 3.32361634 1 P 0 ;0,1=279,2=0.000000
L 3.8554002 3.32361634 3.8531 3.32103356 1 P 0 ;0,1=279,2=0.000000
L 3.8531 3.32103356 3.85041654 3.31948287 1 P 0 ;0,1=279,2=0.000000
L 3.85041654 3.31948287 3.84083317 3.31948287 1 P 0 ;0,1=279,2=0.000000
L 3.85041654 3.31948287 3.85616673 3.3045 1 P 0 ;0,1=279,2=0.000000
L 3.8841 3.3045 3.8841 3.3355 1 P 0 ;0,1=279,2=0.000000
L 3.8841 3.3355 3.86991624 3.31328327 1 P 0 ;0,1=279,2=0.000000
L 3.86991624 3.31328327 3.88908366 3.31328327 1 P 0 ;0,1=279,2=0.000000
L 3.90321644 3.31741575 3.9058999 3.32103356 1 P 0 ;0,1=279,2=0.000000
L 3.9058999 3.32103356 3.9082001 3.3230998 1 P 0 ;0,1=279,2=0.000000
L 3.9082001 3.3230998 3.91126683 3.32413287 1 P 0 ;0,1=279,2=0.000000
L 3.91126683 3.32413287 3.9139503 3.3230998 1 P 0 ;0,1=279,2=0.000000
L 3.9139503 3.3230998 3.91586654 3.32103356 1 P 0 ;0,1=279,2=0.000000
L 3.91586654 3.32103356 3.9174002 3.31793327 1 P 0 ;0,1=279,2=0.000000
L 3.9174002 3.31793327 3.91778346 3.31431644 1 P 0 ;0,1=279,2=0.000000
L 3.91778346 3.31431644 3.9174002 3.31121614 1 P 0 ;0,1=279,2=0.000000
L 3.9174002 3.31121614 3.91586654 3.30811585 1 P 0 ;0,1=279,2=0.000000
L 3.91586654 3.30811585 3.91356634 3.30553307 1 P 0 ;0,1=279,2=0.000000
L 3.91356634 3.30553307 3.91088356 3.3045 1 P 0 ;0,1=279,2=0.000000
L 3.91088356 3.3045 3.90781683 3.30553307 1 P 0 ;0,1=279,2=0.000000
L 3.90781683 3.30553307 3.90513337 3.30863238 1 P 0 ;0,1=279,2=0.000000
L 3.90513337 3.30863238 3.9035997 3.31328327 1 P 0 ;0,1=279,2=0.000000
L 3.9035997 3.31328327 3.90321644 3.3184498 1 P 0 ;0,1=279,2=0.000000
L 3.90321644 3.3184498 3.90398287 3.32516594 1 P 0 ;0,1=279,2=0.000000
L 3.90398287 3.32516594 3.90513337 3.32878376 1 P 0 ;0,1=279,2=0.000000
L 3.90513337 3.32878376 3.90704961 3.3323997 1 P 0 ;0,1=279,2=0.000000
L 3.90704961 3.3323997 3.90973307 3.33498337 1 P 0 ;0,1=279,2=0.000000
L 3.90973307 3.33498337 3.91241654 3.3355 1 P 0 ;0,1=279,2=0.000000
L 3.91241654 3.3355 3.9151 3.33446683 1 P 0 ;0,1=279,2=0.000000
L 3.9151 3.33446683 3.91701703 3.33188307 1 P 0 ;0,1=279,2=0.000000
L 3.94149961 3.3045 3.94149961 3.3355 1 P 0 ;0,1=279,2=0.000000
L 3.94149961 3.3355 3.9368999 3.3293003 1 P 0 ;0,1=279,2=0.000000
L 3.9368999 3.3045 3.94609931 3.3045 1 P 0 ;0,1=279,2=0.000000
L 3.905 3.736 3.905 3.78 1 P 0 
L 3.905 3.78 3.815 3.78 1 P 0 
L 3.815 3.78 3.815 3.736 1 P 0 
L 3.815 3.736 3.905 3.736 1 P 0 
L 3.76083317 3.8645 3.76083317 3.8955 1 P 0 ;0,1=280,2=0.000000
L 3.76083317 3.8955 3.77041654 3.8955 1 P 0 ;0,1=280,2=0.000000
L 3.77041654 3.8955 3.77348327 3.89394931 1 P 0 ;0,1=280,2=0.000000
L 3.77348327 3.89394931 3.7754002 3.89188307 1 P 0 ;0,1=280,2=0.000000
L 3.7754002 3.89188307 3.77616673 3.8877497 1 P 0 ;0,1=280,2=0.000000
L 3.77616673 3.8877497 3.7754002 3.88361634 1 P 0 ;0,1=280,2=0.000000
L 3.7754002 3.88361634 3.7731 3.88103356 1 P 0 ;0,1=280,2=0.000000
L 3.7731 3.88103356 3.77041654 3.87948287 1 P 0 ;0,1=280,2=0.000000
L 3.77041654 3.87948287 3.76083317 3.87948287 1 P 0 ;0,1=280,2=0.000000
L 3.77041654 3.87948287 3.77616673 3.8645 1 P 0 ;0,1=280,2=0.000000
L 3.8041 3.8645 3.8041 3.8955 1 P 0 ;0,1=280,2=0.000000
L 3.8041 3.8955 3.78991624 3.87328327 1 P 0 ;0,1=280,2=0.000000
L 3.78991624 3.87328327 3.80908366 3.87328327 1 P 0 ;0,1=280,2=0.000000
L 3.8351 3.8645 3.8351 3.8955 1 P 0 ;0,1=280,2=0.000000
L 3.8351 3.8955 3.82091624 3.87328327 1 P 0 ;0,1=280,2=0.000000
L 3.82091624 3.87328327 3.84008366 3.87328327 1 P 0 ;0,1=280,2=0.000000
L 3.85498287 3.86811585 3.85766634 3.86553307 1 P 0 ;0,1=280,2=0.000000
L 3.85766634 3.86553307 3.86073307 3.8645 1 P 0 ;0,1=280,2=0.000000
L 3.86073307 3.8645 3.8637998 3.86553307 1 P 0 ;0,1=280,2=0.000000
L 3.8637998 3.86553307 3.86648327 3.86863238 1 P 0 ;0,1=280,2=0.000000
L 3.86648327 3.86863238 3.8684002 3.87328327 1 P 0 ;0,1=280,2=0.000000
L 3.8684002 3.87328327 3.86916673 3.87793327 1 P 0 ;0,1=280,2=0.000000
L 3.86916673 3.87793327 3.86916673 3.88361634 1 P 0 ;0,1=280,2=0.000000
L 3.86916673 3.88361634 3.8684002 3.88826624 1 P 0 ;0,1=280,2=0.000000
L 3.8684002 3.88826624 3.86648327 3.8923997 1 P 0 ;0,1=280,2=0.000000
L 3.86648327 3.8923997 3.86418307 3.89446683 1 P 0 ;0,1=280,2=0.000000
L 3.86418307 3.89446683 3.86149961 3.8955 1 P 0 ;0,1=280,2=0.000000
L 3.86149961 3.8955 3.85843287 3.89446683 1 P 0 ;0,1=280,2=0.000000
L 3.85843287 3.89446683 3.85613337 3.8923997 1 P 0 ;0,1=280,2=0.000000
L 3.85613337 3.8923997 3.8545997 3.8893003 1 P 0 ;0,1=280,2=0.000000
L 3.8545997 3.8893003 3.85383317 3.88516594 1 P 0 ;0,1=280,2=0.000000
L 3.85383317 3.88516594 3.8545997 3.8815501 1 P 0 ;0,1=280,2=0.000000
L 3.8545997 3.8815501 3.85651663 3.87793327 1 P 0 ;0,1=280,2=0.000000
L 3.85651663 3.87793327 3.85881683 3.87586604 1 P 0 ;0,1=280,2=0.000000
L 3.85881683 3.87586604 3.86149961 3.87534951 1 P 0 ;0,1=280,2=0.000000
L 3.86149961 3.87534951 3.86456634 3.87638268 1 P 0 ;0,1=280,2=0.000000
L 3.86456634 3.87638268 3.86686654 3.87896634 1 P 0 ;0,1=280,2=0.000000
L 3.86686654 3.87896634 3.86916673 3.88361634 1 P 0 ;0,1=280,2=0.000000
L 3.905 3.788 3.905 3.832 1 P 0 
L 3.905 3.832 3.815 3.832 1 P 0 
L 3.815 3.832 3.815 3.788 1 P 0 
L 3.815 3.788 3.905 3.788 1 P 0 
L 3.76083317 3.9045 3.76083317 3.9355 1 P 0 ;0,1=281,2=0.000000
L 3.76083317 3.9355 3.77041654 3.9355 1 P 0 ;0,1=281,2=0.000000
L 3.77041654 3.9355 3.77348327 3.93394931 1 P 0 ;0,1=281,2=0.000000
L 3.77348327 3.93394931 3.7754002 3.93188307 1 P 0 ;0,1=281,2=0.000000
L 3.7754002 3.93188307 3.77616673 3.9277497 1 P 0 ;0,1=281,2=0.000000
L 3.77616673 3.9277497 3.7754002 3.92361634 1 P 0 ;0,1=281,2=0.000000
L 3.7754002 3.92361634 3.7731 3.92103356 1 P 0 ;0,1=281,2=0.000000
L 3.7731 3.92103356 3.77041654 3.91948287 1 P 0 ;0,1=281,2=0.000000
L 3.77041654 3.91948287 3.76083317 3.91948287 1 P 0 ;0,1=281,2=0.000000
L 3.77041654 3.91948287 3.77616673 3.9045 1 P 0 ;0,1=281,2=0.000000
L 3.8041 3.9045 3.8041 3.9355 1 P 0 ;0,1=281,2=0.000000
L 3.8041 3.9355 3.78991624 3.91328327 1 P 0 ;0,1=281,2=0.000000
L 3.78991624 3.91328327 3.80908366 3.91328327 1 P 0 ;0,1=281,2=0.000000
L 3.8351 3.9045 3.8351 3.9355 1 P 0 ;0,1=281,2=0.000000
L 3.8351 3.9355 3.82091624 3.91328327 1 P 0 ;0,1=281,2=0.000000
L 3.82091624 3.91328327 3.84008366 3.91328327 1 P 0 ;0,1=281,2=0.000000
L 3.86149961 3.9045 3.86418307 3.90501654 1 P 0 ;0,1=281,2=0.000000
L 3.86418307 3.90501654 3.8672498 3.90656614 1 P 0 ;0,1=281,2=0.000000
L 3.8672498 3.90656614 3.86916673 3.90914892 1 P 0 ;0,1=281,2=0.000000
L 3.86916673 3.90914892 3.86993327 3.91276673 1 P 0 ;0,1=281,2=0.000000
L 3.86993327 3.91276673 3.86916673 3.91638268 1 P 0 ;0,1=281,2=0.000000
L 3.86916673 3.91638268 3.86686654 3.91948287 1 P 0 ;0,1=281,2=0.000000
L 3.86686654 3.91948287 3.86341654 3.92103356 1 P 0 ;0,1=281,2=0.000000
L 3.86341654 3.92103356 3.85958337 3.92103356 1 P 0 ;0,1=281,2=0.000000
L 3.85958337 3.92103356 3.85728317 3.92206663 1 P 0 ;0,1=281,2=0.000000
L 3.85728317 3.92206663 3.85536614 3.92464941 1 P 0 ;0,1=281,2=0.000000
L 3.85536614 3.92464941 3.8545997 3.92826624 1 P 0 ;0,1=281,2=0.000000
L 3.8545997 3.92826624 3.8557501 3.93188307 1 P 0 ;0,1=281,2=0.000000
L 3.8557501 3.93188307 3.85843287 3.93446683 1 P 0 ;0,1=281,2=0.000000
L 3.85843287 3.93446683 3.86149961 3.9355 1 P 0 ;0,1=281,2=0.000000
L 3.86149961 3.9355 3.86456634 3.93446683 1 P 0 ;0,1=281,2=0.000000
L 3.86456634 3.93446683 3.8672498 3.93188307 1 P 0 ;0,1=281,2=0.000000
L 3.8672498 3.93188307 3.8684002 3.92826624 1 P 0 ;0,1=281,2=0.000000
L 3.8684002 3.92826624 3.86763307 3.92464941 1 P 0 ;0,1=281,2=0.000000
L 3.86763307 3.92464941 3.86571673 3.92206663 1 P 0 ;0,1=281,2=0.000000
L 3.86571673 3.92206663 3.86341654 3.92103356 1 P 0 ;0,1=281,2=0.000000
L 3.86341654 3.92103356 3.85958337 3.92103356 1 P 0 ;0,1=281,2=0.000000
L 3.85958337 3.92103356 3.85613337 3.91948287 1 P 0 ;0,1=281,2=0.000000
L 3.85613337 3.91948287 3.85383317 3.91638268 1 P 0 ;0,1=281,2=0.000000
L 3.85383317 3.91638268 3.85306663 3.91276673 1 P 0 ;0,1=281,2=0.000000
L 3.85306663 3.91276673 3.85383317 3.90914892 1 P 0 ;0,1=281,2=0.000000
L 3.85383317 3.90914892 3.8557501 3.90656614 1 P 0 ;0,1=281,2=0.000000
L 3.8557501 3.90656614 3.85881683 3.90501654 1 P 0 ;0,1=281,2=0.000000
L 3.85881683 3.90501654 3.86149961 3.9045 1 P 0 ;0,1=281,2=0.000000
L 5.315 0.848 5.315 0.892 1 P 0 
L 5.315 0.892 5.225 0.892 1 P 0 
L 5.225 0.892 5.225 0.848 1 P 0 
L 5.225 0.848 5.315 0.848 1 P 0 
L 5.21083317 1.0545 5.21083317 1.0855 1 P 0 ;0,1=282,2=0.000000
L 5.21083317 1.0855 5.22041654 1.0855 1 P 0 ;0,1=282,2=0.000000
L 5.22041654 1.0855 5.22348327 1.08394931 1 P 0 ;0,1=282,2=0.000000
L 5.22348327 1.08394931 5.2254002 1.08188307 1 P 0 ;0,1=282,2=0.000000
L 5.2254002 1.08188307 5.22616673 1.0777497 1 P 0 ;0,1=282,2=0.000000
L 5.22616673 1.0777497 5.2254002 1.07361634 1 P 0 ;0,1=282,2=0.000000
L 5.2254002 1.07361634 5.2231 1.07103356 1 P 0 ;0,1=282,2=0.000000
L 5.2231 1.07103356 5.22041654 1.06948287 1 P 0 ;0,1=282,2=0.000000
L 5.22041654 1.06948287 5.21083317 1.06948287 1 P 0 ;0,1=282,2=0.000000
L 5.22041654 1.06948287 5.22616673 1.0545 1 P 0 ;0,1=282,2=0.000000
L 5.2541 1.0545 5.2541 1.0855 1 P 0 ;0,1=282,2=0.000000
L 5.2541 1.0855 5.23991624 1.06328327 1 P 0 ;0,1=282,2=0.000000
L 5.23991624 1.06328327 5.25908366 1.06328327 1 P 0 ;0,1=282,2=0.000000
L 5.28049961 1.0545 5.28318307 1.05501654 1 P 0 ;0,1=282,2=0.000000
L 5.28318307 1.05501654 5.2862498 1.05656614 1 P 0 ;0,1=282,2=0.000000
L 5.2862498 1.05656614 5.28816673 1.05914892 1 P 0 ;0,1=282,2=0.000000
L 5.28816673 1.05914892 5.28893327 1.06276673 1 P 0 ;0,1=282,2=0.000000
L 5.28893327 1.06276673 5.28816673 1.06638268 1 P 0 ;0,1=282,2=0.000000
L 5.28816673 1.06638268 5.28586654 1.06948287 1 P 0 ;0,1=282,2=0.000000
L 5.28586654 1.06948287 5.28241654 1.07103356 1 P 0 ;0,1=282,2=0.000000
L 5.28241654 1.07103356 5.27858337 1.07103356 1 P 0 ;0,1=282,2=0.000000
L 5.27858337 1.07103356 5.27628317 1.07206663 1 P 0 ;0,1=282,2=0.000000
L 5.27628317 1.07206663 5.27436614 1.07464941 1 P 0 ;0,1=282,2=0.000000
L 5.27436614 1.07464941 5.2735997 1.07826624 1 P 0 ;0,1=282,2=0.000000
L 5.2735997 1.07826624 5.2747501 1.08188307 1 P 0 ;0,1=282,2=0.000000
L 5.2747501 1.08188307 5.27743287 1.08446683 1 P 0 ;0,1=282,2=0.000000
L 5.27743287 1.08446683 5.28049961 1.0855 1 P 0 ;0,1=282,2=0.000000
L 5.28049961 1.0855 5.28356634 1.08446683 1 P 0 ;0,1=282,2=0.000000
L 5.28356634 1.08446683 5.2862498 1.08188307 1 P 0 ;0,1=282,2=0.000000
L 5.2862498 1.08188307 5.2874002 1.07826624 1 P 0 ;0,1=282,2=0.000000
L 5.2874002 1.07826624 5.28663307 1.07464941 1 P 0 ;0,1=282,2=0.000000
L 5.28663307 1.07464941 5.28471673 1.07206663 1 P 0 ;0,1=282,2=0.000000
L 5.28471673 1.07206663 5.28241654 1.07103356 1 P 0 ;0,1=282,2=0.000000
L 5.28241654 1.07103356 5.27858337 1.07103356 1 P 0 ;0,1=282,2=0.000000
L 5.27858337 1.07103356 5.27513337 1.06948287 1 P 0 ;0,1=282,2=0.000000
L 5.27513337 1.06948287 5.27283317 1.06638268 1 P 0 ;0,1=282,2=0.000000
L 5.27283317 1.06638268 5.27206663 1.06276673 1 P 0 ;0,1=282,2=0.000000
L 5.27206663 1.06276673 5.27283317 1.05914892 1 P 0 ;0,1=282,2=0.000000
L 5.27283317 1.05914892 5.2747501 1.05656614 1 P 0 ;0,1=282,2=0.000000
L 5.2747501 1.05656614 5.27781683 1.05501654 1 P 0 ;0,1=282,2=0.000000
L 5.27781683 1.05501654 5.28049961 1.0545 1 P 0 ;0,1=282,2=0.000000
L 5.3161 1.0545 5.3161 1.0855 1 P 0 ;0,1=282,2=0.000000
L 5.3161 1.0855 5.30191624 1.06328327 1 P 0 ;0,1=282,2=0.000000
L 5.30191624 1.06328327 5.32108366 1.06328327 1 P 0 ;0,1=282,2=0.000000
L 4.578 3.198 4.578 3.242 1 P 0 
L 4.578 3.242 4.488 3.242 1 P 0 
L 4.488 3.242 4.488 3.198 1 P 0 
L 4.488 3.198 4.578 3.198 1 P 0 
L 4.49583317 3.1595 4.49583317 3.1905 1 P 0 ;0,1=283,2=0.000000
L 4.49583317 3.1905 4.50541654 3.1905 1 P 0 ;0,1=283,2=0.000000
L 4.50541654 3.1905 4.50848327 3.18894931 1 P 0 ;0,1=283,2=0.000000
L 4.50848327 3.18894931 4.5104002 3.18688307 1 P 0 ;0,1=283,2=0.000000
L 4.5104002 3.18688307 4.51116673 3.1827497 1 P 0 ;0,1=283,2=0.000000
L 4.51116673 3.1827497 4.5104002 3.17861634 1 P 0 ;0,1=283,2=0.000000
L 4.5104002 3.17861634 4.5081 3.17603356 1 P 0 ;0,1=283,2=0.000000
L 4.5081 3.17603356 4.50541654 3.17448287 1 P 0 ;0,1=283,2=0.000000
L 4.50541654 3.17448287 4.49583317 3.17448287 1 P 0 ;0,1=283,2=0.000000
L 4.50541654 3.17448287 4.51116673 3.1595 1 P 0 ;0,1=283,2=0.000000
L 4.5391 3.1595 4.5391 3.1905 1 P 0 ;0,1=283,2=0.000000
L 4.5391 3.1905 4.52491624 3.16828327 1 P 0 ;0,1=283,2=0.000000
L 4.52491624 3.16828327 4.54408366 3.16828327 1 P 0 ;0,1=283,2=0.000000
L 4.55706663 3.16414892 4.55936614 3.16156614 1 P 0 ;0,1=283,2=0.000000
L 4.55936614 3.16156614 4.56204961 3.16001654 1 P 0 ;0,1=283,2=0.000000
L 4.56204961 3.16001654 4.56549961 3.1595 1 P 0 ;0,1=283,2=0.000000
L 4.56549961 3.1595 4.5689503 3.16053307 1 P 0 ;0,1=283,2=0.000000
L 4.5689503 3.16053307 4.57163307 3.16259931 1 P 0 ;0,1=283,2=0.000000
L 4.57163307 3.16259931 4.57355 3.16621614 1 P 0 ;0,1=283,2=0.000000
L 4.57355 3.16621614 4.57393327 3.17034951 1 P 0 ;0,1=283,2=0.000000
L 4.57393327 3.17034951 4.57316673 3.17448287 1 P 0 ;0,1=283,2=0.000000
L 4.57316673 3.17448287 4.5712498 3.17706663 1 P 0 ;0,1=283,2=0.000000
L 4.5712498 3.17706663 4.56856634 3.17913287 1 P 0 ;0,1=283,2=0.000000
L 4.56856634 3.17913287 4.56588356 3.17964941 1 P 0 ;0,1=283,2=0.000000
L 4.56588356 3.17964941 4.5632001 3.17913287 1 P 0 ;0,1=283,2=0.000000
L 4.5632001 3.17913287 4.5597501 3.17706663 1 P 0 ;0,1=283,2=0.000000
L 4.5597501 3.17706663 4.5608999 3.1905 1 P 0 ;0,1=283,2=0.000000
L 4.5608999 3.1905 4.5712498 3.1905 1 P 0 ;0,1=283,2=0.000000
L 4.58998287 3.16311585 4.59266634 3.16053307 1 P 0 ;0,1=283,2=0.000000
L 4.59266634 3.16053307 4.59573307 3.1595 1 P 0 ;0,1=283,2=0.000000
L 4.59573307 3.1595 4.5987998 3.16053307 1 P 0 ;0,1=283,2=0.000000
L 4.5987998 3.16053307 4.60148327 3.16363238 1 P 0 ;0,1=283,2=0.000000
L 4.60148327 3.16363238 4.6034002 3.16828327 1 P 0 ;0,1=283,2=0.000000
L 4.6034002 3.16828327 4.60416673 3.17293327 1 P 0 ;0,1=283,2=0.000000
L 4.60416673 3.17293327 4.60416673 3.17861634 1 P 0 ;0,1=283,2=0.000000
L 4.60416673 3.17861634 4.6034002 3.18326624 1 P 0 ;0,1=283,2=0.000000
L 4.6034002 3.18326624 4.60148327 3.1873997 1 P 0 ;0,1=283,2=0.000000
L 4.60148327 3.1873997 4.59918307 3.18946683 1 P 0 ;0,1=283,2=0.000000
L 4.59918307 3.18946683 4.59649961 3.1905 1 P 0 ;0,1=283,2=0.000000
L 4.59649961 3.1905 4.59343287 3.18946683 1 P 0 ;0,1=283,2=0.000000
L 4.59343287 3.18946683 4.59113337 3.1873997 1 P 0 ;0,1=283,2=0.000000
L 4.59113337 3.1873997 4.5895997 3.1843003 1 P 0 ;0,1=283,2=0.000000
L 4.5895997 3.1843003 4.58883317 3.18016594 1 P 0 ;0,1=283,2=0.000000
L 4.58883317 3.18016594 4.5895997 3.1765501 1 P 0 ;0,1=283,2=0.000000
L 4.5895997 3.1765501 4.59151663 3.17293327 1 P 0 ;0,1=283,2=0.000000
L 4.59151663 3.17293327 4.59381683 3.17086604 1 P 0 ;0,1=283,2=0.000000
L 4.59381683 3.17086604 4.59649961 3.17034951 1 P 0 ;0,1=283,2=0.000000
L 4.59649961 3.17034951 4.59956634 3.17138268 1 P 0 ;0,1=283,2=0.000000
L 4.59956634 3.17138268 4.60186654 3.17396634 1 P 0 ;0,1=283,2=0.000000
L 4.60186654 3.17396634 4.60416673 3.17861634 1 P 0 ;0,1=283,2=0.000000
L 4.45 3.767 4.36 3.767 1 P 0 
L 4.36 3.723 4.45 3.723 1 P 0 
L 4.45 3.723 4.45 3.767 1 P 0 
L 4.36 3.767 4.36 3.723 1 P 0 
L 4.47583317 3.7295 4.47583317 3.7605 1 P 0 ;0,1=284,2=0.000000
L 4.47583317 3.7605 4.48541654 3.7605 1 P 0 ;0,1=284,2=0.000000
L 4.48541654 3.7605 4.48848327 3.75894931 1 P 0 ;0,1=284,2=0.000000
L 4.48848327 3.75894931 4.4904002 3.75688307 1 P 0 ;0,1=284,2=0.000000
L 4.4904002 3.75688307 4.49116673 3.7527497 1 P 0 ;0,1=284,2=0.000000
L 4.49116673 3.7527497 4.4904002 3.74861634 1 P 0 ;0,1=284,2=0.000000
L 4.4904002 3.74861634 4.4881 3.74603356 1 P 0 ;0,1=284,2=0.000000
L 4.4881 3.74603356 4.48541654 3.74448287 1 P 0 ;0,1=284,2=0.000000
L 4.48541654 3.74448287 4.47583317 3.74448287 1 P 0 ;0,1=284,2=0.000000
L 4.48541654 3.74448287 4.49116673 3.7295 1 P 0 ;0,1=284,2=0.000000
L 4.5191 3.7295 4.5191 3.7605 1 P 0 ;0,1=284,2=0.000000
L 4.5191 3.7605 4.50491624 3.73828327 1 P 0 ;0,1=284,2=0.000000
L 4.50491624 3.73828327 4.52408366 3.73828327 1 P 0 ;0,1=284,2=0.000000
L 4.53706663 3.73414892 4.53936614 3.73156614 1 P 0 ;0,1=284,2=0.000000
L 4.53936614 3.73156614 4.54204961 3.73001654 1 P 0 ;0,1=284,2=0.000000
L 4.54204961 3.73001654 4.54549961 3.7295 1 P 0 ;0,1=284,2=0.000000
L 4.54549961 3.7295 4.5489503 3.73053307 1 P 0 ;0,1=284,2=0.000000
L 4.5489503 3.73053307 4.55163307 3.73259931 1 P 0 ;0,1=284,2=0.000000
L 4.55163307 3.73259931 4.55355 3.73621614 1 P 0 ;0,1=284,2=0.000000
L 4.55355 3.73621614 4.55393327 3.74034951 1 P 0 ;0,1=284,2=0.000000
L 4.55393327 3.74034951 4.55316673 3.74448287 1 P 0 ;0,1=284,2=0.000000
L 4.55316673 3.74448287 4.5512498 3.74706663 1 P 0 ;0,1=284,2=0.000000
L 4.5512498 3.74706663 4.54856634 3.74913287 1 P 0 ;0,1=284,2=0.000000
L 4.54856634 3.74913287 4.54588356 3.74964941 1 P 0 ;0,1=284,2=0.000000
L 4.54588356 3.74964941 4.5432001 3.74913287 1 P 0 ;0,1=284,2=0.000000
L 4.5432001 3.74913287 4.5397501 3.74706663 1 P 0 ;0,1=284,2=0.000000
L 4.5397501 3.74706663 4.5408999 3.7605 1 P 0 ;0,1=284,2=0.000000
L 4.5408999 3.7605 4.5512498 3.7605 1 P 0 ;0,1=284,2=0.000000
L 4.56806663 3.73569961 4.57036614 3.73208278 1 P 0 ;0,1=284,2=0.000000
L 4.57036614 3.73208278 4.57343287 3.73001654 1 P 0 ;0,1=284,2=0.000000
L 4.57343287 3.73001654 4.57688356 3.7295 1 P 0 ;0,1=284,2=0.000000
L 4.57688356 3.7295 4.5799503 3.73001654 1 P 0 ;0,1=284,2=0.000000
L 4.5799503 3.73001654 4.58301703 3.73259931 1 P 0 ;0,1=284,2=0.000000
L 4.58301703 3.73259931 4.58493327 3.73569961 1 P 0 ;0,1=284,2=0.000000
L 4.58493327 3.73569961 4.58531654 3.7387999 1 P 0 ;0,1=284,2=0.000000
L 4.58531654 3.7387999 4.58455 3.74241575 1 P 0 ;0,1=284,2=0.000000
L 4.58455 3.74241575 4.58186654 3.74499951 1 P 0 ;0,1=284,2=0.000000
L 4.58186654 3.74499951 4.57918307 3.74603356 1 P 0 ;0,1=284,2=0.000000
L 4.57918307 3.74603356 4.57573307 3.74603356 1 P 0 ;0,1=284,2=0.000000
L 4.57918307 3.74603356 4.58148327 3.74758317 1 P 0 ;0,1=284,2=0.000000
L 4.58148327 3.74758317 4.5834002 3.75016594 1 P 0 ;0,1=284,2=0.000000
L 4.5834002 3.75016594 4.58416673 3.75326624 1 P 0 ;0,1=284,2=0.000000
L 4.58416673 3.75326624 4.5834002 3.75636654 1 P 0 ;0,1=284,2=0.000000
L 4.5834002 3.75636654 4.58148327 3.75894931 1 P 0 ;0,1=284,2=0.000000
L 4.58148327 3.75894931 4.57803327 3.7605 1 P 0 ;0,1=284,2=0.000000
L 4.57803327 3.7605 4.57458337 3.75998337 1 P 0 ;0,1=284,2=0.000000
L 4.57458337 3.75998337 4.57113337 3.75791624 1 P 0 ;0,1=284,2=0.000000
L 1.077 3.755 1.033 3.755 1 P 0 
L 1.033 3.755 1.033 3.665 1 P 0 
L 1.033 3.665 1.077 3.665 1 P 0 
L 1.077 3.665 1.077 3.755 1 P 0 
L 1.0555 3.85083317 1.0245 3.85083317 1 P 0 ;0,1=285,2=270.000000
L 1.0245 3.85083317 1.0245 3.86041654 1 P 0 ;0,1=285,2=270.000000
L 1.0245 3.86041654 1.02605069 3.86348327 1 P 0 ;0,1=285,2=270.000000
L 1.02605069 3.86348327 1.02811693 3.8654002 1 P 0 ;0,1=285,2=270.000000
L 1.02811693 3.8654002 1.0322503 3.86616673 1 P 0 ;0,1=285,2=270.000000
L 1.0322503 3.86616673 1.03638366 3.8654002 1 P 0 ;0,1=285,2=270.000000
L 1.03638366 3.8654002 1.03896644 3.8631 1 P 0 ;0,1=285,2=270.000000
L 1.03896644 3.8631 1.04051713 3.86041654 1 P 0 ;0,1=285,2=270.000000
L 1.04051713 3.86041654 1.04051713 3.85083317 1 P 0 ;0,1=285,2=270.000000
L 1.04051713 3.86041654 1.0555 3.86616673 1 P 0 ;0,1=285,2=270.000000
L 1.0555 3.8941 1.0245 3.8941 1 P 0 ;0,1=285,2=270.000000
L 1.0245 3.8941 1.04671673 3.87991624 1 P 0 ;0,1=285,2=270.000000
L 1.04671673 3.87991624 1.04671673 3.89908366 1 P 0 ;0,1=285,2=270.000000
L 1.05085108 3.91206663 1.05343386 3.91436614 1 P 0 ;0,1=285,2=270.000000
L 1.05343386 3.91436614 1.05498346 3.91704961 1 P 0 ;0,1=285,2=270.000000
L 1.05498346 3.91704961 1.0555 3.92049961 1 P 0 ;0,1=285,2=270.000000
L 1.0555 3.92049961 1.05446693 3.9239503 1 P 0 ;0,1=285,2=270.000000
L 1.05446693 3.9239503 1.05240069 3.92663307 1 P 0 ;0,1=285,2=270.000000
L 1.05240069 3.92663307 1.04878386 3.92855 1 P 0 ;0,1=285,2=270.000000
L 1.04878386 3.92855 1.04465049 3.92893327 1 P 0 ;0,1=285,2=270.000000
L 1.04465049 3.92893327 1.04051713 3.92816673 1 P 0 ;0,1=285,2=270.000000
L 1.04051713 3.92816673 1.03793337 3.9262498 1 P 0 ;0,1=285,2=270.000000
L 1.03793337 3.9262498 1.03586713 3.92356634 1 P 0 ;0,1=285,2=270.000000
L 1.03586713 3.92356634 1.03535059 3.92088356 1 P 0 ;0,1=285,2=270.000000
L 1.03535059 3.92088356 1.03586713 3.9182001 1 P 0 ;0,1=285,2=270.000000
L 1.03586713 3.9182001 1.03793337 3.9147501 1 P 0 ;0,1=285,2=270.000000
L 1.03793337 3.9147501 1.0245 3.9158999 1 P 0 ;0,1=285,2=270.000000
L 1.0245 3.9158999 1.0245 3.9262498 1 P 0 ;0,1=285,2=270.000000
L 1.04258425 3.94421644 1.03896644 3.9468999 1 P 0 ;0,1=285,2=270.000000
L 1.03896644 3.9468999 1.0369002 3.9492001 1 P 0 ;0,1=285,2=270.000000
L 1.0369002 3.9492001 1.03586713 3.95226683 1 P 0 ;0,1=285,2=270.000000
L 1.03586713 3.95226683 1.0369002 3.9549503 1 P 0 ;0,1=285,2=270.000000
L 1.0369002 3.9549503 1.03896644 3.95686654 1 P 0 ;0,1=285,2=270.000000
L 1.03896644 3.95686654 1.04206673 3.9584002 1 P 0 ;0,1=285,2=270.000000
L 1.04206673 3.9584002 1.04568356 3.95878346 1 P 0 ;0,1=285,2=270.000000
L 1.04568356 3.95878346 1.04878386 3.9584002 1 P 0 ;0,1=285,2=270.000000
L 1.04878386 3.9584002 1.05188415 3.95686654 1 P 0 ;0,1=285,2=270.000000
L 1.05188415 3.95686654 1.05446693 3.95456634 1 P 0 ;0,1=285,2=270.000000
L 1.05446693 3.95456634 1.0555 3.95188356 1 P 0 ;0,1=285,2=270.000000
L 1.0555 3.95188356 1.05446693 3.94881683 1 P 0 ;0,1=285,2=270.000000
L 1.05446693 3.94881683 1.05136762 3.94613337 1 P 0 ;0,1=285,2=270.000000
L 1.05136762 3.94613337 1.04671673 3.9445997 1 P 0 ;0,1=285,2=270.000000
L 1.04671673 3.9445997 1.0415502 3.94421644 1 P 0 ;0,1=285,2=270.000000
L 1.0415502 3.94421644 1.03483406 3.94498287 1 P 0 ;0,1=285,2=270.000000
L 1.03483406 3.94498287 1.03121624 3.94613337 1 P 0 ;0,1=285,2=270.000000
L 1.03121624 3.94613337 1.0276003 3.94804961 1 P 0 ;0,1=285,2=270.000000
L 1.0276003 3.94804961 1.02501663 3.95073307 1 P 0 ;0,1=285,2=270.000000
L 1.02501663 3.95073307 1.0245 3.95341654 1 P 0 ;0,1=285,2=270.000000
L 1.0245 3.95341654 1.02553317 3.9561 1 P 0 ;0,1=285,2=270.000000
L 1.02553317 3.9561 1.02811693 3.95801703 1 P 0 ;0,1=285,2=270.000000
L 4.362 3.43 4.362 3.52 1 P 0 
L 4.318 3.52 4.318 3.43 1 P 0 
L 4.318 3.43 4.362 3.43 1 P 0 
L 4.362 3.52 4.318 3.52 1 P 0 
L 4.3605 3.31083317 4.3295 3.31083317 1 P 0 ;0,1=286,2=270.000000
L 4.3295 3.31083317 4.3295 3.32041654 1 P 0 ;0,1=286,2=270.000000
L 4.3295 3.32041654 4.33105069 3.32348327 1 P 0 ;0,1=286,2=270.000000
L 4.33105069 3.32348327 4.33311693 3.3254002 1 P 0 ;0,1=286,2=270.000000
L 4.33311693 3.3254002 4.3372503 3.32616673 1 P 0 ;0,1=286,2=270.000000
L 4.3372503 3.32616673 4.34138366 3.3254002 1 P 0 ;0,1=286,2=270.000000
L 4.34138366 3.3254002 4.34396644 3.3231 1 P 0 ;0,1=286,2=270.000000
L 4.34396644 3.3231 4.34551713 3.32041654 1 P 0 ;0,1=286,2=270.000000
L 4.34551713 3.32041654 4.34551713 3.31083317 1 P 0 ;0,1=286,2=270.000000
L 4.34551713 3.32041654 4.3605 3.32616673 1 P 0 ;0,1=286,2=270.000000
L 4.3605 3.3541 4.3295 3.3541 1 P 0 ;0,1=286,2=270.000000
L 4.3295 3.3541 4.35171673 3.33991624 1 P 0 ;0,1=286,2=270.000000
L 4.35171673 3.33991624 4.35171673 3.35908366 1 P 0 ;0,1=286,2=270.000000
L 4.3605 3.3851 4.3295 3.3851 1 P 0 ;0,1=286,2=270.000000
L 4.3295 3.3851 4.35171673 3.37091624 1 P 0 ;0,1=286,2=270.000000
L 4.35171673 3.37091624 4.35171673 3.39008366 1 P 0 ;0,1=286,2=270.000000
L 4.35430039 3.40306663 4.35791722 3.40536614 1 P 0 ;0,1=286,2=270.000000
L 4.35791722 3.40536614 4.35998346 3.40843287 1 P 0 ;0,1=286,2=270.000000
L 4.35998346 3.40843287 4.3605 3.41188356 1 P 0 ;0,1=286,2=270.000000
L 4.3605 3.41188356 4.35998346 3.4149503 1 P 0 ;0,1=286,2=270.000000
L 4.35998346 3.4149503 4.35740069 3.41801703 1 P 0 ;0,1=286,2=270.000000
L 4.35740069 3.41801703 4.35430039 3.41993327 1 P 0 ;0,1=286,2=270.000000
L 4.35430039 3.41993327 4.3512001 3.42031654 1 P 0 ;0,1=286,2=270.000000
L 4.3512001 3.42031654 4.34758425 3.41955 1 P 0 ;0,1=286,2=270.000000
L 4.34758425 3.41955 4.34500049 3.41686654 1 P 0 ;0,1=286,2=270.000000
L 4.34500049 3.41686654 4.34396644 3.41418307 1 P 0 ;0,1=286,2=270.000000
L 4.34396644 3.41418307 4.34396644 3.41073307 1 P 0 ;0,1=286,2=270.000000
L 4.34396644 3.41418307 4.34241683 3.41648327 1 P 0 ;0,1=286,2=270.000000
L 4.34241683 3.41648327 4.33983406 3.4184002 1 P 0 ;0,1=286,2=270.000000
L 4.33983406 3.4184002 4.33673376 3.41916673 1 P 0 ;0,1=286,2=270.000000
L 4.33673376 3.41916673 4.33363346 3.4184002 1 P 0 ;0,1=286,2=270.000000
L 4.33363346 3.4184002 4.33105069 3.41648327 1 P 0 ;0,1=286,2=270.000000
L 4.33105069 3.41648327 4.3295 3.41303327 1 P 0 ;0,1=286,2=270.000000
L 4.3295 3.41303327 4.33001663 3.40958337 1 P 0 ;0,1=286,2=270.000000
L 4.33001663 3.40958337 4.33208376 3.40613337 1 P 0 ;0,1=286,2=270.000000
L 4.102 3.405 4.102 3.495 1 P 0 
L 4.102 3.495 4.058 3.495 1 P 0 
L 4.058 3.495 4.058 3.405 1 P 0 
L 4.058 3.405 4.102 3.405 1 P 0 
L 4.2755 3.34083317 4.2445 3.34083317 1 P 0 ;0,1=287,2=270.000000
L 4.2445 3.34083317 4.2445 3.35041654 1 P 0 ;0,1=287,2=270.000000
L 4.2445 3.35041654 4.24605069 3.35348327 1 P 0 ;0,1=287,2=270.000000
L 4.24605069 3.35348327 4.24811693 3.3554002 1 P 0 ;0,1=287,2=270.000000
L 4.24811693 3.3554002 4.2522503 3.35616673 1 P 0 ;0,1=287,2=270.000000
L 4.2522503 3.35616673 4.25638366 3.3554002 1 P 0 ;0,1=287,2=270.000000
L 4.25638366 3.3554002 4.25896644 3.3531 1 P 0 ;0,1=287,2=270.000000
L 4.25896644 3.3531 4.26051713 3.35041654 1 P 0 ;0,1=287,2=270.000000
L 4.26051713 3.35041654 4.26051713 3.34083317 1 P 0 ;0,1=287,2=270.000000
L 4.26051713 3.35041654 4.2755 3.35616673 1 P 0 ;0,1=287,2=270.000000
L 4.2755 3.3841 4.2445 3.3841 1 P 0 ;0,1=287,2=270.000000
L 4.2445 3.3841 4.26671673 3.36991624 1 P 0 ;0,1=287,2=270.000000
L 4.26671673 3.36991624 4.26671673 3.38908366 1 P 0 ;0,1=287,2=270.000000
L 4.26258425 3.40321644 4.25896644 3.4058999 1 P 0 ;0,1=287,2=270.000000
L 4.25896644 3.4058999 4.2569002 3.4082001 1 P 0 ;0,1=287,2=270.000000
L 4.2569002 3.4082001 4.25586713 3.41126683 1 P 0 ;0,1=287,2=270.000000
L 4.25586713 3.41126683 4.2569002 3.4139503 1 P 0 ;0,1=287,2=270.000000
L 4.2569002 3.4139503 4.25896644 3.41586654 1 P 0 ;0,1=287,2=270.000000
L 4.25896644 3.41586654 4.26206673 3.4174002 1 P 0 ;0,1=287,2=270.000000
L 4.26206673 3.4174002 4.26568356 3.41778346 1 P 0 ;0,1=287,2=270.000000
L 4.26568356 3.41778346 4.26878386 3.4174002 1 P 0 ;0,1=287,2=270.000000
L 4.26878386 3.4174002 4.27188415 3.41586654 1 P 0 ;0,1=287,2=270.000000
L 4.27188415 3.41586654 4.27446693 3.41356634 1 P 0 ;0,1=287,2=270.000000
L 4.27446693 3.41356634 4.2755 3.41088356 1 P 0 ;0,1=287,2=270.000000
L 4.2755 3.41088356 4.27446693 3.40781683 1 P 0 ;0,1=287,2=270.000000
L 4.27446693 3.40781683 4.27136762 3.40513337 1 P 0 ;0,1=287,2=270.000000
L 4.27136762 3.40513337 4.26671673 3.4035997 1 P 0 ;0,1=287,2=270.000000
L 4.26671673 3.4035997 4.2615502 3.40321644 1 P 0 ;0,1=287,2=270.000000
L 4.2615502 3.40321644 4.25483406 3.40398287 1 P 0 ;0,1=287,2=270.000000
L 4.25483406 3.40398287 4.25121624 3.40513337 1 P 0 ;0,1=287,2=270.000000
L 4.25121624 3.40513337 4.2476003 3.40704961 1 P 0 ;0,1=287,2=270.000000
L 4.2476003 3.40704961 4.24501663 3.40973307 1 P 0 ;0,1=287,2=270.000000
L 4.24501663 3.40973307 4.2445 3.41241654 1 P 0 ;0,1=287,2=270.000000
L 4.2445 3.41241654 4.24553317 3.4151 1 P 0 ;0,1=287,2=270.000000
L 4.24553317 3.4151 4.24811693 3.41701703 1 P 0 ;0,1=287,2=270.000000
L 4.27085108 3.43306663 4.27343386 3.43536614 1 P 0 ;0,1=287,2=270.000000
L 4.27343386 3.43536614 4.27498346 3.43804961 1 P 0 ;0,1=287,2=270.000000
L 4.27498346 3.43804961 4.2755 3.44149961 1 P 0 ;0,1=287,2=270.000000
L 4.2755 3.44149961 4.27446693 3.4449503 1 P 0 ;0,1=287,2=270.000000
L 4.27446693 3.4449503 4.27240069 3.44763307 1 P 0 ;0,1=287,2=270.000000
L 4.27240069 3.44763307 4.26878386 3.44955 1 P 0 ;0,1=287,2=270.000000
L 4.26878386 3.44955 4.26465049 3.44993327 1 P 0 ;0,1=287,2=270.000000
L 4.26465049 3.44993327 4.26051713 3.44916673 1 P 0 ;0,1=287,2=270.000000
L 4.26051713 3.44916673 4.25793337 3.4472498 1 P 0 ;0,1=287,2=270.000000
L 4.25793337 3.4472498 4.25586713 3.44456634 1 P 0 ;0,1=287,2=270.000000
L 4.25586713 3.44456634 4.25535059 3.44188356 1 P 0 ;0,1=287,2=270.000000
L 4.25535059 3.44188356 4.25586713 3.4392001 1 P 0 ;0,1=287,2=270.000000
L 4.25586713 3.4392001 4.25793337 3.4357501 1 P 0 ;0,1=287,2=270.000000
L 4.25793337 3.4357501 4.2445 3.4368999 1 P 0 ;0,1=287,2=270.000000
L 4.2445 3.4368999 4.2445 3.4472498 1 P 0 ;0,1=287,2=270.000000
L 3.892 3.4 3.892 3.49 1 P 0 
L 3.892 3.49 3.848 3.49 1 P 0 
L 3.848 3.49 3.848 3.4 1 P 0 
L 3.848 3.4 3.892 3.4 1 P 0 
L 3.8605 3.50083317 3.8295 3.50083317 1 P 0 ;0,1=288,2=270.000000
L 3.8295 3.50083317 3.8295 3.51041654 1 P 0 ;0,1=288,2=270.000000
L 3.8295 3.51041654 3.83105069 3.51348327 1 P 0 ;0,1=288,2=270.000000
L 3.83105069 3.51348327 3.83311693 3.5154002 1 P 0 ;0,1=288,2=270.000000
L 3.83311693 3.5154002 3.8372503 3.51616673 1 P 0 ;0,1=288,2=270.000000
L 3.8372503 3.51616673 3.84138366 3.5154002 1 P 0 ;0,1=288,2=270.000000
L 3.84138366 3.5154002 3.84396644 3.5131 1 P 0 ;0,1=288,2=270.000000
L 3.84396644 3.5131 3.84551713 3.51041654 1 P 0 ;0,1=288,2=270.000000
L 3.84551713 3.51041654 3.84551713 3.50083317 1 P 0 ;0,1=288,2=270.000000
L 3.84551713 3.51041654 3.8605 3.51616673 1 P 0 ;0,1=288,2=270.000000
L 3.8605 3.5441 3.8295 3.5441 1 P 0 ;0,1=288,2=270.000000
L 3.8295 3.5441 3.85171673 3.52991624 1 P 0 ;0,1=288,2=270.000000
L 3.85171673 3.52991624 3.85171673 3.54908366 1 P 0 ;0,1=288,2=270.000000
L 3.84758425 3.56321644 3.84396644 3.5658999 1 P 0 ;0,1=288,2=270.000000
L 3.84396644 3.5658999 3.8419002 3.5682001 1 P 0 ;0,1=288,2=270.000000
L 3.8419002 3.5682001 3.84086713 3.57126683 1 P 0 ;0,1=288,2=270.000000
L 3.84086713 3.57126683 3.8419002 3.5739503 1 P 0 ;0,1=288,2=270.000000
L 3.8419002 3.5739503 3.84396644 3.57586654 1 P 0 ;0,1=288,2=270.000000
L 3.84396644 3.57586654 3.84706673 3.5774002 1 P 0 ;0,1=288,2=270.000000
L 3.84706673 3.5774002 3.85068356 3.57778346 1 P 0 ;0,1=288,2=270.000000
L 3.85068356 3.57778346 3.85378386 3.5774002 1 P 0 ;0,1=288,2=270.000000
L 3.85378386 3.5774002 3.85688415 3.57586654 1 P 0 ;0,1=288,2=270.000000
L 3.85688415 3.57586654 3.85946693 3.57356634 1 P 0 ;0,1=288,2=270.000000
L 3.85946693 3.57356634 3.8605 3.57088356 1 P 0 ;0,1=288,2=270.000000
L 3.8605 3.57088356 3.85946693 3.56781683 1 P 0 ;0,1=288,2=270.000000
L 3.85946693 3.56781683 3.85636762 3.56513337 1 P 0 ;0,1=288,2=270.000000
L 3.85636762 3.56513337 3.85171673 3.5635997 1 P 0 ;0,1=288,2=270.000000
L 3.85171673 3.5635997 3.8465502 3.56321644 1 P 0 ;0,1=288,2=270.000000
L 3.8465502 3.56321644 3.83983406 3.56398287 1 P 0 ;0,1=288,2=270.000000
L 3.83983406 3.56398287 3.83621624 3.56513337 1 P 0 ;0,1=288,2=270.000000
L 3.83621624 3.56513337 3.8326003 3.56704961 1 P 0 ;0,1=288,2=270.000000
L 3.8326003 3.56704961 3.83001663 3.56973307 1 P 0 ;0,1=288,2=270.000000
L 3.83001663 3.56973307 3.8295 3.57241654 1 P 0 ;0,1=288,2=270.000000
L 3.8295 3.57241654 3.83053317 3.5751 1 P 0 ;0,1=288,2=270.000000
L 3.83053317 3.5751 3.83311693 3.57701703 1 P 0 ;0,1=288,2=270.000000
L 3.8605 3.6061 3.8295 3.6061 1 P 0 ;0,1=288,2=270.000000
L 3.8295 3.6061 3.85171673 3.59191624 1 P 0 ;0,1=288,2=270.000000
L 3.85171673 3.59191624 3.85171673 3.61108366 1 P 0 ;0,1=288,2=270.000000
L 1.153 3.005 1.153 2.915 1 P 0 
L 1.153 2.915 1.197 2.915 1 P 0 
L 1.197 2.915 1.197 3.005 1 P 0 
L 1.197 3.005 1.153 3.005 1 P 0 
L 1.2755 2.92083317 1.2445 2.92083317 1 P 0 ;0,1=289,2=270.000000
L 1.2445 2.92083317 1.2445 2.93041654 1 P 0 ;0,1=289,2=270.000000
L 1.2445 2.93041654 1.24605069 2.93348327 1 P 0 ;0,1=289,2=270.000000
L 1.24605069 2.93348327 1.24811693 2.9354002 1 P 0 ;0,1=289,2=270.000000
L 1.24811693 2.9354002 1.2522503 2.93616673 1 P 0 ;0,1=289,2=270.000000
L 1.2522503 2.93616673 1.25638366 2.9354002 1 P 0 ;0,1=289,2=270.000000
L 1.25638366 2.9354002 1.25896644 2.9331 1 P 0 ;0,1=289,2=270.000000
L 1.25896644 2.9331 1.26051713 2.93041654 1 P 0 ;0,1=289,2=270.000000
L 1.26051713 2.93041654 1.26051713 2.92083317 1 P 0 ;0,1=289,2=270.000000
L 1.26051713 2.93041654 1.2755 2.93616673 1 P 0 ;0,1=289,2=270.000000
L 1.2755 2.9641 1.2445 2.9641 1 P 0 ;0,1=289,2=270.000000
L 1.2445 2.9641 1.26671673 2.94991624 1 P 0 ;0,1=289,2=270.000000
L 1.26671673 2.94991624 1.26671673 2.96908366 1 P 0 ;0,1=289,2=270.000000
L 1.2755 2.99049961 1.27498346 2.99318307 1 P 0 ;0,1=289,2=270.000000
L 1.27498346 2.99318307 1.27343386 2.9962498 1 P 0 ;0,1=289,2=270.000000
L 1.27343386 2.9962498 1.27085108 2.99816673 1 P 0 ;0,1=289,2=270.000000
L 1.27085108 2.99816673 1.26723327 2.99893327 1 P 0 ;0,1=289,2=270.000000
L 1.26723327 2.99893327 1.26361732 2.99816673 1 P 0 ;0,1=289,2=270.000000
L 1.26361732 2.99816673 1.26051713 2.99586654 1 P 0 ;0,1=289,2=270.000000
L 1.26051713 2.99586654 1.25896644 2.99241654 1 P 0 ;0,1=289,2=270.000000
L 1.25896644 2.99241654 1.25896644 2.98858337 1 P 0 ;0,1=289,2=270.000000
L 1.25896644 2.98858337 1.25793337 2.98628317 1 P 0 ;0,1=289,2=270.000000
L 1.25793337 2.98628317 1.25535059 2.98436614 1 P 0 ;0,1=289,2=270.000000
L 1.25535059 2.98436614 1.25173376 2.9835997 1 P 0 ;0,1=289,2=270.000000
L 1.25173376 2.9835997 1.24811693 2.9847501 1 P 0 ;0,1=289,2=270.000000
L 1.24811693 2.9847501 1.24553317 2.98743287 1 P 0 ;0,1=289,2=270.000000
L 1.24553317 2.98743287 1.2445 2.99049961 1 P 0 ;0,1=289,2=270.000000
L 1.2445 2.99049961 1.24553317 2.99356634 1 P 0 ;0,1=289,2=270.000000
L 1.24553317 2.99356634 1.24811693 2.9962498 1 P 0 ;0,1=289,2=270.000000
L 1.24811693 2.9962498 1.25173376 2.9974002 1 P 0 ;0,1=289,2=270.000000
L 1.25173376 2.9974002 1.25535059 2.99663307 1 P 0 ;0,1=289,2=270.000000
L 1.25535059 2.99663307 1.25793337 2.99471673 1 P 0 ;0,1=289,2=270.000000
L 1.25793337 2.99471673 1.25896644 2.99241654 1 P 0 ;0,1=289,2=270.000000
L 1.25896644 2.99241654 1.25896644 2.98858337 1 P 0 ;0,1=289,2=270.000000
L 1.25896644 2.98858337 1.26051713 2.98513337 1 P 0 ;0,1=289,2=270.000000
L 1.26051713 2.98513337 1.26361732 2.98283317 1 P 0 ;0,1=289,2=270.000000
L 1.26361732 2.98283317 1.26723327 2.98206663 1 P 0 ;0,1=289,2=270.000000
L 1.26723327 2.98206663 1.27085108 2.98283317 1 P 0 ;0,1=289,2=270.000000
L 1.27085108 2.98283317 1.27343386 2.9847501 1 P 0 ;0,1=289,2=270.000000
L 1.27343386 2.9847501 1.27498346 2.98781683 1 P 0 ;0,1=289,2=270.000000
L 1.27498346 2.98781683 1.2755 2.99049961 1 P 0 ;0,1=289,2=270.000000
L 1.2755 3.02149961 1.2445 3.02149961 1 P 0 ;0,1=289,2=270.000000
L 1.2445 3.02149961 1.2506997 3.0168999 1 P 0 ;0,1=289,2=270.000000
L 1.2755 3.0168999 1.2755 3.02609931 1 P 0 ;0,1=289,2=270.000000
L 1.047 2.915 1.047 3.005 1 P 0 
L 1.047 3.005 1.003 3.005 1 P 0 
L 1.003 3.005 1.003 2.915 1 P 0 
L 1.003 2.915 1.047 2.915 1 P 0 
L 1.0605 2.78083317 1.0295 2.78083317 1 P 0 ;0,1=290,2=270.000000
L 1.0295 2.78083317 1.0295 2.79041654 1 P 0 ;0,1=290,2=270.000000
L 1.0295 2.79041654 1.03105069 2.79348327 1 P 0 ;0,1=290,2=270.000000
L 1.03105069 2.79348327 1.03311693 2.7954002 1 P 0 ;0,1=290,2=270.000000
L 1.03311693 2.7954002 1.0372503 2.79616673 1 P 0 ;0,1=290,2=270.000000
L 1.0372503 2.79616673 1.04138366 2.7954002 1 P 0 ;0,1=290,2=270.000000
L 1.04138366 2.7954002 1.04396644 2.7931 1 P 0 ;0,1=290,2=270.000000
L 1.04396644 2.7931 1.04551713 2.79041654 1 P 0 ;0,1=290,2=270.000000
L 1.04551713 2.79041654 1.04551713 2.78083317 1 P 0 ;0,1=290,2=270.000000
L 1.04551713 2.79041654 1.0605 2.79616673 1 P 0 ;0,1=290,2=270.000000
L 1.0605 2.8241 1.0295 2.8241 1 P 0 ;0,1=290,2=270.000000
L 1.0295 2.8241 1.05171673 2.80991624 1 P 0 ;0,1=290,2=270.000000
L 1.05171673 2.80991624 1.05171673 2.82908366 1 P 0 ;0,1=290,2=270.000000
L 1.0605 2.85049961 1.05998346 2.85318307 1 P 0 ;0,1=290,2=270.000000
L 1.05998346 2.85318307 1.05843386 2.8562498 1 P 0 ;0,1=290,2=270.000000
L 1.05843386 2.8562498 1.05585108 2.85816673 1 P 0 ;0,1=290,2=270.000000
L 1.05585108 2.85816673 1.05223327 2.85893327 1 P 0 ;0,1=290,2=270.000000
L 1.05223327 2.85893327 1.04861732 2.85816673 1 P 0 ;0,1=290,2=270.000000
L 1.04861732 2.85816673 1.04551713 2.85586654 1 P 0 ;0,1=290,2=270.000000
L 1.04551713 2.85586654 1.04396644 2.85241654 1 P 0 ;0,1=290,2=270.000000
L 1.04396644 2.85241654 1.04396644 2.84858337 1 P 0 ;0,1=290,2=270.000000
L 1.04396644 2.84858337 1.04293337 2.84628317 1 P 0 ;0,1=290,2=270.000000
L 1.04293337 2.84628317 1.04035059 2.84436614 1 P 0 ;0,1=290,2=270.000000
L 1.04035059 2.84436614 1.03673376 2.8435997 1 P 0 ;0,1=290,2=270.000000
L 1.03673376 2.8435997 1.03311693 2.8447501 1 P 0 ;0,1=290,2=270.000000
L 1.03311693 2.8447501 1.03053317 2.84743287 1 P 0 ;0,1=290,2=270.000000
L 1.03053317 2.84743287 1.0295 2.85049961 1 P 0 ;0,1=290,2=270.000000
L 1.0295 2.85049961 1.03053317 2.85356634 1 P 0 ;0,1=290,2=270.000000
L 1.03053317 2.85356634 1.03311693 2.8562498 1 P 0 ;0,1=290,2=270.000000
L 1.03311693 2.8562498 1.03673376 2.8574002 1 P 0 ;0,1=290,2=270.000000
L 1.03673376 2.8574002 1.04035059 2.85663307 1 P 0 ;0,1=290,2=270.000000
L 1.04035059 2.85663307 1.04293337 2.85471673 1 P 0 ;0,1=290,2=270.000000
L 1.04293337 2.85471673 1.04396644 2.85241654 1 P 0 ;0,1=290,2=270.000000
L 1.04396644 2.85241654 1.04396644 2.84858337 1 P 0 ;0,1=290,2=270.000000
L 1.04396644 2.84858337 1.04551713 2.84513337 1 P 0 ;0,1=290,2=270.000000
L 1.04551713 2.84513337 1.04861732 2.84283317 1 P 0 ;0,1=290,2=270.000000
L 1.04861732 2.84283317 1.05223327 2.84206663 1 P 0 ;0,1=290,2=270.000000
L 1.05223327 2.84206663 1.05585108 2.84283317 1 P 0 ;0,1=290,2=270.000000
L 1.05585108 2.84283317 1.05843386 2.8447501 1 P 0 ;0,1=290,2=270.000000
L 1.05843386 2.8447501 1.05998346 2.84781683 1 P 0 ;0,1=290,2=270.000000
L 1.05998346 2.84781683 1.0605 2.85049961 1 P 0 ;0,1=290,2=270.000000
L 1.0295 2.88149961 1.03053317 2.87843287 1 P 0 ;0,1=290,2=270.000000
L 1.03053317 2.87843287 1.03311693 2.87613337 1 P 0 ;0,1=290,2=270.000000
L 1.03311693 2.87613337 1.03621624 2.8745997 1 P 0 ;0,1=290,2=270.000000
L 1.03621624 2.8745997 1.04035059 2.8734499 1 P 0 ;0,1=290,2=270.000000
L 1.04035059 2.8734499 1.04500049 2.87306663 1 P 0 ;0,1=290,2=270.000000
L 1.04500049 2.87306663 1.04965049 2.8734499 1 P 0 ;0,1=290,2=270.000000
L 1.04965049 2.8734499 1.05378386 2.8745997 1 P 0 ;0,1=290,2=270.000000
L 1.05378386 2.8745997 1.05688415 2.87613337 1 P 0 ;0,1=290,2=270.000000
L 1.05688415 2.87613337 1.05946693 2.87843287 1 P 0 ;0,1=290,2=270.000000
L 1.05946693 2.87843287 1.0605 2.88149961 1 P 0 ;0,1=290,2=270.000000
L 1.0605 2.88149961 1.05946693 2.88456634 1 P 0 ;0,1=290,2=270.000000
L 1.05946693 2.88456634 1.05688415 2.88686654 1 P 0 ;0,1=290,2=270.000000
L 1.05688415 2.88686654 1.05378386 2.8884002 1 P 0 ;0,1=290,2=270.000000
L 1.05378386 2.8884002 1.04965049 2.88955 1 P 0 ;0,1=290,2=270.000000
L 1.04965049 2.88955 1.04500049 2.88993327 1 P 0 ;0,1=290,2=270.000000
L 1.04500049 2.88993327 1.04035059 2.88955 1 P 0 ;0,1=290,2=270.000000
L 1.04035059 2.88955 1.03621624 2.8884002 1 P 0 ;0,1=290,2=270.000000
L 1.03621624 2.8884002 1.03311693 2.88686654 1 P 0 ;0,1=290,2=270.000000
L 1.03311693 2.88686654 1.03053317 2.88456634 1 P 0 ;0,1=290,2=270.000000
L 1.03053317 2.88456634 1.0295 2.88149961 1 P 0 ;0,1=290,2=270.000000
L 5.315 0.798 5.315 0.842 1 P 0 
L 5.315 0.842 5.225 0.842 1 P 0 
L 5.225 0.842 5.225 0.798 1 P 0 
L 5.225 0.798 5.315 0.798 1 P 0 
L 5.21083317 1.0145 5.21083317 1.0455 1 P 0 ;0,1=291,2=0.000000
L 5.21083317 1.0455 5.22041654 1.0455 1 P 0 ;0,1=291,2=0.000000
L 5.22041654 1.0455 5.22348327 1.04394931 1 P 0 ;0,1=291,2=0.000000
L 5.22348327 1.04394931 5.2254002 1.04188307 1 P 0 ;0,1=291,2=0.000000
L 5.2254002 1.04188307 5.22616673 1.0377497 1 P 0 ;0,1=291,2=0.000000
L 5.22616673 1.0377497 5.2254002 1.03361634 1 P 0 ;0,1=291,2=0.000000
L 5.2254002 1.03361634 5.2231 1.03103356 1 P 0 ;0,1=291,2=0.000000
L 5.2231 1.03103356 5.22041654 1.02948287 1 P 0 ;0,1=291,2=0.000000
L 5.22041654 1.02948287 5.21083317 1.02948287 1 P 0 ;0,1=291,2=0.000000
L 5.22041654 1.02948287 5.22616673 1.0145 1 P 0 ;0,1=291,2=0.000000
L 5.2541 1.0145 5.2541 1.0455 1 P 0 ;0,1=291,2=0.000000
L 5.2541 1.0455 5.23991624 1.02328327 1 P 0 ;0,1=291,2=0.000000
L 5.23991624 1.02328327 5.25908366 1.02328327 1 P 0 ;0,1=291,2=0.000000
L 5.27973307 1.0145 5.28049961 1.02121614 1 P 0 ;0,1=291,2=0.000000
L 5.28049961 1.02121614 5.2816501 1.02689921 1 P 0 ;0,1=291,2=0.000000
L 5.2816501 1.02689921 5.28318307 1.03206663 1 P 0 ;0,1=291,2=0.000000
L 5.28318307 1.03206663 5.2851 1.0377497 1 P 0 ;0,1=291,2=0.000000
L 5.2851 1.0377497 5.28816673 1.0455 1 P 0 ;0,1=291,2=0.000000
L 5.28816673 1.0455 5.27283317 1.0455 1 P 0 ;0,1=291,2=0.000000
L 5.31073307 1.0145 5.31149961 1.02121614 1 P 0 ;0,1=291,2=0.000000
L 5.31149961 1.02121614 5.3126501 1.02689921 1 P 0 ;0,1=291,2=0.000000
L 5.3126501 1.02689921 5.31418307 1.03206663 1 P 0 ;0,1=291,2=0.000000
L 5.31418307 1.03206663 5.3161 1.0377497 1 P 0 ;0,1=291,2=0.000000
L 5.3161 1.0377497 5.31916673 1.0455 1 P 0 ;0,1=291,2=0.000000
L 5.31916673 1.0455 5.30383317 1.0455 1 P 0 ;0,1=291,2=0.000000
L 5.315 0.738 5.315 0.782 1 P 0 
L 5.315 0.782 5.225 0.782 1 P 0 
L 5.225 0.782 5.225 0.738 1 P 0 
L 5.225 0.738 5.315 0.738 1 P 0 
L 5.21083317 0.9445 5.21083317 0.9755 1 P 0 ;0,1=292,2=0.000000
L 5.21083317 0.9755 5.22041654 0.9755 1 P 0 ;0,1=292,2=0.000000
L 5.22041654 0.9755 5.22348327 0.97394931 1 P 0 ;0,1=292,2=0.000000
L 5.22348327 0.97394931 5.2254002 0.97188307 1 P 0 ;0,1=292,2=0.000000
L 5.2254002 0.97188307 5.22616673 0.9677497 1 P 0 ;0,1=292,2=0.000000
L 5.22616673 0.9677497 5.2254002 0.96361634 1 P 0 ;0,1=292,2=0.000000
L 5.2254002 0.96361634 5.2231 0.96103356 1 P 0 ;0,1=292,2=0.000000
L 5.2231 0.96103356 5.22041654 0.95948287 1 P 0 ;0,1=292,2=0.000000
L 5.22041654 0.95948287 5.21083317 0.95948287 1 P 0 ;0,1=292,2=0.000000
L 5.22041654 0.95948287 5.22616673 0.9445 1 P 0 ;0,1=292,2=0.000000
L 5.2541 0.9445 5.2541 0.9755 1 P 0 ;0,1=292,2=0.000000
L 5.2541 0.9755 5.23991624 0.95328327 1 P 0 ;0,1=292,2=0.000000
L 5.23991624 0.95328327 5.25908366 0.95328327 1 P 0 ;0,1=292,2=0.000000
L 5.27973307 0.9445 5.28049961 0.95121614 1 P 0 ;0,1=292,2=0.000000
L 5.28049961 0.95121614 5.2816501 0.95689921 1 P 0 ;0,1=292,2=0.000000
L 5.2816501 0.95689921 5.28318307 0.96206663 1 P 0 ;0,1=292,2=0.000000
L 5.28318307 0.96206663 5.2851 0.9677497 1 P 0 ;0,1=292,2=0.000000
L 5.2851 0.9677497 5.28816673 0.9755 1 P 0 ;0,1=292,2=0.000000
L 5.28816673 0.9755 5.27283317 0.9755 1 P 0 ;0,1=292,2=0.000000
L 5.30421644 0.95741575 5.3068999 0.96103356 1 P 0 ;0,1=292,2=0.000000
L 5.3068999 0.96103356 5.3092001 0.9630998 1 P 0 ;0,1=292,2=0.000000
L 5.3092001 0.9630998 5.31226683 0.96413287 1 P 0 ;0,1=292,2=0.000000
L 5.31226683 0.96413287 5.3149503 0.9630998 1 P 0 ;0,1=292,2=0.000000
L 5.3149503 0.9630998 5.31686654 0.96103356 1 P 0 ;0,1=292,2=0.000000
L 5.31686654 0.96103356 5.3184002 0.95793327 1 P 0 ;0,1=292,2=0.000000
L 5.3184002 0.95793327 5.31878346 0.95431644 1 P 0 ;0,1=292,2=0.000000
L 5.31878346 0.95431644 5.3184002 0.95121614 1 P 0 ;0,1=292,2=0.000000
L 5.3184002 0.95121614 5.31686654 0.94811585 1 P 0 ;0,1=292,2=0.000000
L 5.31686654 0.94811585 5.31456634 0.94553307 1 P 0 ;0,1=292,2=0.000000
L 5.31456634 0.94553307 5.31188356 0.9445 1 P 0 ;0,1=292,2=0.000000
L 5.31188356 0.9445 5.30881683 0.94553307 1 P 0 ;0,1=292,2=0.000000
L 5.30881683 0.94553307 5.30613337 0.94863238 1 P 0 ;0,1=292,2=0.000000
L 5.30613337 0.94863238 5.3045997 0.95328327 1 P 0 ;0,1=292,2=0.000000
L 5.3045997 0.95328327 5.30421644 0.9584498 1 P 0 ;0,1=292,2=0.000000
L 5.30421644 0.9584498 5.30498287 0.96516594 1 P 0 ;0,1=292,2=0.000000
L 5.30498287 0.96516594 5.30613337 0.96878376 1 P 0 ;0,1=292,2=0.000000
L 5.30613337 0.96878376 5.30804961 0.9723997 1 P 0 ;0,1=292,2=0.000000
L 5.30804961 0.9723997 5.31073307 0.97498337 1 P 0 ;0,1=292,2=0.000000
L 5.31073307 0.97498337 5.31341654 0.9755 1 P 0 ;0,1=292,2=0.000000
L 5.31341654 0.9755 5.3161 0.97446683 1 P 0 ;0,1=292,2=0.000000
L 5.3161 0.97446683 5.31801703 0.97188307 1 P 0 ;0,1=292,2=0.000000
L 4.76 0.763 4.76 0.807 1 P 0 
L 4.67 0.763 4.76 0.763 1 P 0 
L 4.76 0.807 4.67 0.807 1 P 0 
L 4.67 0.807 4.67 0.763 1 P 0 
L 4.65583317 0.7245 4.65583317 0.7555 1 P 0 ;0,1=293,2=0.000000
L 4.65583317 0.7555 4.66541654 0.7555 1 P 0 ;0,1=293,2=0.000000
L 4.66541654 0.7555 4.66848327 0.75394931 1 P 0 ;0,1=293,2=0.000000
L 4.66848327 0.75394931 4.6704002 0.75188307 1 P 0 ;0,1=293,2=0.000000
L 4.6704002 0.75188307 4.67116673 0.7477497 1 P 0 ;0,1=293,2=0.000000
L 4.67116673 0.7477497 4.6704002 0.74361634 1 P 0 ;0,1=293,2=0.000000
L 4.6704002 0.74361634 4.6681 0.74103356 1 P 0 ;0,1=293,2=0.000000
L 4.6681 0.74103356 4.66541654 0.73948287 1 P 0 ;0,1=293,2=0.000000
L 4.66541654 0.73948287 4.65583317 0.73948287 1 P 0 ;0,1=293,2=0.000000
L 4.66541654 0.73948287 4.67116673 0.7245 1 P 0 ;0,1=293,2=0.000000
L 4.6991 0.7245 4.6991 0.7555 1 P 0 ;0,1=293,2=0.000000
L 4.6991 0.7555 4.68491624 0.73328327 1 P 0 ;0,1=293,2=0.000000
L 4.68491624 0.73328327 4.70408366 0.73328327 1 P 0 ;0,1=293,2=0.000000
L 4.72473307 0.7245 4.72549961 0.73121614 1 P 0 ;0,1=293,2=0.000000
L 4.72549961 0.73121614 4.7266501 0.73689921 1 P 0 ;0,1=293,2=0.000000
L 4.7266501 0.73689921 4.72818307 0.74206663 1 P 0 ;0,1=293,2=0.000000
L 4.72818307 0.74206663 4.7301 0.7477497 1 P 0 ;0,1=293,2=0.000000
L 4.7301 0.7477497 4.73316673 0.7555 1 P 0 ;0,1=293,2=0.000000
L 4.73316673 0.7555 4.71783317 0.7555 1 P 0 ;0,1=293,2=0.000000
L 4.74806663 0.72914892 4.75036614 0.72656614 1 P 0 ;0,1=293,2=0.000000
L 4.75036614 0.72656614 4.75304961 0.72501654 1 P 0 ;0,1=293,2=0.000000
L 4.75304961 0.72501654 4.75649961 0.7245 1 P 0 ;0,1=293,2=0.000000
L 4.75649961 0.7245 4.7599503 0.72553307 1 P 0 ;0,1=293,2=0.000000
L 4.7599503 0.72553307 4.76263307 0.72759931 1 P 0 ;0,1=293,2=0.000000
L 4.76263307 0.72759931 4.76455 0.73121614 1 P 0 ;0,1=293,2=0.000000
L 4.76455 0.73121614 4.76493327 0.73534951 1 P 0 ;0,1=293,2=0.000000
L 4.76493327 0.73534951 4.76416673 0.73948287 1 P 0 ;0,1=293,2=0.000000
L 4.76416673 0.73948287 4.7622498 0.74206663 1 P 0 ;0,1=293,2=0.000000
L 4.7622498 0.74206663 4.75956634 0.74413287 1 P 0 ;0,1=293,2=0.000000
L 4.75956634 0.74413287 4.75688356 0.74464941 1 P 0 ;0,1=293,2=0.000000
L 4.75688356 0.74464941 4.7542001 0.74413287 1 P 0 ;0,1=293,2=0.000000
L 4.7542001 0.74413287 4.7507501 0.74206663 1 P 0 ;0,1=293,2=0.000000
L 4.7507501 0.74206663 4.7518999 0.7555 1 P 0 ;0,1=293,2=0.000000
L 4.7518999 0.7555 4.7622498 0.7555 1 P 0 ;0,1=293,2=0.000000
L 4.76 0.843 4.76 0.887 1 P 0 
L 4.67 0.843 4.76 0.843 1 P 0 
L 4.76 0.887 4.67 0.887 1 P 0 
L 4.67 0.887 4.67 0.843 1 P 0 
L 4.55083317 0.8145 4.55083317 0.8455 1 P 0 ;0,1=294,2=0.000000
L 4.55083317 0.8455 4.56041654 0.8455 1 P 0 ;0,1=294,2=0.000000
L 4.56041654 0.8455 4.56348327 0.84394931 1 P 0 ;0,1=294,2=0.000000
L 4.56348327 0.84394931 4.5654002 0.84188307 1 P 0 ;0,1=294,2=0.000000
L 4.5654002 0.84188307 4.56616673 0.8377497 1 P 0 ;0,1=294,2=0.000000
L 4.56616673 0.8377497 4.5654002 0.83361634 1 P 0 ;0,1=294,2=0.000000
L 4.5654002 0.83361634 4.5631 0.83103356 1 P 0 ;0,1=294,2=0.000000
L 4.5631 0.83103356 4.56041654 0.82948287 1 P 0 ;0,1=294,2=0.000000
L 4.56041654 0.82948287 4.55083317 0.82948287 1 P 0 ;0,1=294,2=0.000000
L 4.56041654 0.82948287 4.56616673 0.8145 1 P 0 ;0,1=294,2=0.000000
L 4.5941 0.8145 4.5941 0.8455 1 P 0 ;0,1=294,2=0.000000
L 4.5941 0.8455 4.57991624 0.82328327 1 P 0 ;0,1=294,2=0.000000
L 4.57991624 0.82328327 4.59908366 0.82328327 1 P 0 ;0,1=294,2=0.000000
L 4.61973307 0.8145 4.62049961 0.82121614 1 P 0 ;0,1=294,2=0.000000
L 4.62049961 0.82121614 4.6216501 0.82689921 1 P 0 ;0,1=294,2=0.000000
L 4.6216501 0.82689921 4.62318307 0.83206663 1 P 0 ;0,1=294,2=0.000000
L 4.62318307 0.83206663 4.6251 0.8377497 1 P 0 ;0,1=294,2=0.000000
L 4.6251 0.8377497 4.62816673 0.8455 1 P 0 ;0,1=294,2=0.000000
L 4.62816673 0.8455 4.61283317 0.8455 1 P 0 ;0,1=294,2=0.000000
L 4.6561 0.8145 4.6561 0.8455 1 P 0 ;0,1=294,2=0.000000
L 4.6561 0.8455 4.64191624 0.82328327 1 P 0 ;0,1=294,2=0.000000
L 4.64191624 0.82328327 4.66108366 0.82328327 1 P 0 ;0,1=294,2=0.000000
L 4.597 2.395 4.597 2.485 1 P 0 
L 4.597 2.485 4.553 2.485 1 P 0 
L 4.553 2.485 4.553 2.395 1 P 0 
L 4.553 2.395 4.597 2.395 1 P 0 
L 4.6255 2.51583317 4.5945 2.51583317 1 P 0 ;0,1=295,2=270.000000
L 4.5945 2.51583317 4.5945 2.52541654 1 P 0 ;0,1=295,2=270.000000
L 4.5945 2.52541654 4.59605069 2.52848327 1 P 0 ;0,1=295,2=270.000000
L 4.59605069 2.52848327 4.59811693 2.5304002 1 P 0 ;0,1=295,2=270.000000
L 4.59811693 2.5304002 4.6022503 2.53116673 1 P 0 ;0,1=295,2=270.000000
L 4.6022503 2.53116673 4.60638366 2.5304002 1 P 0 ;0,1=295,2=270.000000
L 4.60638366 2.5304002 4.60896644 2.5281 1 P 0 ;0,1=295,2=270.000000
L 4.60896644 2.5281 4.61051713 2.52541654 1 P 0 ;0,1=295,2=270.000000
L 4.61051713 2.52541654 4.61051713 2.51583317 1 P 0 ;0,1=295,2=270.000000
L 4.61051713 2.52541654 4.6255 2.53116673 1 P 0 ;0,1=295,2=270.000000
L 4.6255 2.5591 4.5945 2.5591 1 P 0 ;0,1=295,2=270.000000
L 4.5945 2.5591 4.61671673 2.54491624 1 P 0 ;0,1=295,2=270.000000
L 4.61671673 2.54491624 4.61671673 2.56408366 1 P 0 ;0,1=295,2=270.000000
L 4.61930039 2.57706663 4.62291722 2.57936614 1 P 0 ;0,1=295,2=270.000000
L 4.62291722 2.57936614 4.62498346 2.58243287 1 P 0 ;0,1=295,2=270.000000
L 4.62498346 2.58243287 4.6255 2.58588356 1 P 0 ;0,1=295,2=270.000000
L 4.6255 2.58588356 4.62498346 2.5889503 1 P 0 ;0,1=295,2=270.000000
L 4.62498346 2.5889503 4.62240069 2.59201703 1 P 0 ;0,1=295,2=270.000000
L 4.62240069 2.59201703 4.61930039 2.59393327 1 P 0 ;0,1=295,2=270.000000
L 4.61930039 2.59393327 4.6162001 2.59431654 1 P 0 ;0,1=295,2=270.000000
L 4.6162001 2.59431654 4.61258425 2.59355 1 P 0 ;0,1=295,2=270.000000
L 4.61258425 2.59355 4.61000049 2.59086654 1 P 0 ;0,1=295,2=270.000000
L 4.61000049 2.59086654 4.60896644 2.58818307 1 P 0 ;0,1=295,2=270.000000
L 4.60896644 2.58818307 4.60896644 2.58473307 1 P 0 ;0,1=295,2=270.000000
L 4.60896644 2.58818307 4.60741683 2.59048327 1 P 0 ;0,1=295,2=270.000000
L 4.60741683 2.59048327 4.60483406 2.5924002 1 P 0 ;0,1=295,2=270.000000
L 4.60483406 2.5924002 4.60173376 2.59316673 1 P 0 ;0,1=295,2=270.000000
L 4.60173376 2.59316673 4.59863346 2.5924002 1 P 0 ;0,1=295,2=270.000000
L 4.59863346 2.5924002 4.59605069 2.59048327 1 P 0 ;0,1=295,2=270.000000
L 4.59605069 2.59048327 4.5945 2.58703327 1 P 0 ;0,1=295,2=270.000000
L 4.5945 2.58703327 4.59501663 2.58358337 1 P 0 ;0,1=295,2=270.000000
L 4.59501663 2.58358337 4.59708376 2.58013337 1 P 0 ;0,1=295,2=270.000000
L 4.62085108 2.60806663 4.62343386 2.61036614 1 P 0 ;0,1=295,2=270.000000
L 4.62343386 2.61036614 4.62498346 2.61304961 1 P 0 ;0,1=295,2=270.000000
L 4.62498346 2.61304961 4.6255 2.61649961 1 P 0 ;0,1=295,2=270.000000
L 4.6255 2.61649961 4.62446693 2.6199503 1 P 0 ;0,1=295,2=270.000000
L 4.62446693 2.6199503 4.62240069 2.62263307 1 P 0 ;0,1=295,2=270.000000
L 4.62240069 2.62263307 4.61878386 2.62455 1 P 0 ;0,1=295,2=270.000000
L 4.61878386 2.62455 4.61465049 2.62493327 1 P 0 ;0,1=295,2=270.000000
L 4.61465049 2.62493327 4.61051713 2.62416673 1 P 0 ;0,1=295,2=270.000000
L 4.61051713 2.62416673 4.60793337 2.6222498 1 P 0 ;0,1=295,2=270.000000
L 4.60793337 2.6222498 4.60586713 2.61956634 1 P 0 ;0,1=295,2=270.000000
L 4.60586713 2.61956634 4.60535059 2.61688356 1 P 0 ;0,1=295,2=270.000000
L 4.60535059 2.61688356 4.60586713 2.6142001 1 P 0 ;0,1=295,2=270.000000
L 4.60586713 2.6142001 4.60793337 2.6107501 1 P 0 ;0,1=295,2=270.000000
L 4.60793337 2.6107501 4.5945 2.6118999 1 P 0 ;0,1=295,2=270.000000
L 4.5945 2.6118999 4.5945 2.6222498 1 P 0 ;0,1=295,2=270.000000
L 1.552 2.98 1.552 3.07 1 P 0 
L 1.552 3.07 1.508 3.07 1 P 0 
L 1.508 3.07 1.508 2.98 1 P 0 
L 1.508 2.98 1.552 2.98 1 P 0 
L 1.3955 2.93583317 1.3645 2.93583317 1 P 0 ;0,1=296,2=270.000000
L 1.3645 2.93583317 1.3645 2.94541654 1 P 0 ;0,1=296,2=270.000000
L 1.3645 2.94541654 1.36605069 2.94848327 1 P 0 ;0,1=296,2=270.000000
L 1.36605069 2.94848327 1.36811693 2.9504002 1 P 0 ;0,1=296,2=270.000000
L 1.36811693 2.9504002 1.3722503 2.95116673 1 P 0 ;0,1=296,2=270.000000
L 1.3722503 2.95116673 1.37638366 2.9504002 1 P 0 ;0,1=296,2=270.000000
L 1.37638366 2.9504002 1.37896644 2.9481 1 P 0 ;0,1=296,2=270.000000
L 1.37896644 2.9481 1.38051713 2.94541654 1 P 0 ;0,1=296,2=270.000000
L 1.38051713 2.94541654 1.38051713 2.93583317 1 P 0 ;0,1=296,2=270.000000
L 1.38051713 2.94541654 1.3955 2.95116673 1 P 0 ;0,1=296,2=270.000000
L 1.3955 2.9791 1.3645 2.9791 1 P 0 ;0,1=296,2=270.000000
L 1.3645 2.9791 1.38671673 2.96491624 1 P 0 ;0,1=296,2=270.000000
L 1.38671673 2.96491624 1.38671673 2.98408366 1 P 0 ;0,1=296,2=270.000000
L 1.39188415 2.99898287 1.39446693 3.00166634 1 P 0 ;0,1=296,2=270.000000
L 1.39446693 3.00166634 1.3955 3.00473307 1 P 0 ;0,1=296,2=270.000000
L 1.3955 3.00473307 1.39446693 3.0077998 1 P 0 ;0,1=296,2=270.000000
L 1.39446693 3.0077998 1.39136762 3.01048327 1 P 0 ;0,1=296,2=270.000000
L 1.39136762 3.01048327 1.38671673 3.0124002 1 P 0 ;0,1=296,2=270.000000
L 1.38671673 3.0124002 1.38206673 3.01316673 1 P 0 ;0,1=296,2=270.000000
L 1.38206673 3.01316673 1.37638366 3.01316673 1 P 0 ;0,1=296,2=270.000000
L 1.37638366 3.01316673 1.37173376 3.0124002 1 P 0 ;0,1=296,2=270.000000
L 1.37173376 3.0124002 1.3676003 3.01048327 1 P 0 ;0,1=296,2=270.000000
L 1.3676003 3.01048327 1.36553317 3.00818307 1 P 0 ;0,1=296,2=270.000000
L 1.36553317 3.00818307 1.3645 3.00549961 1 P 0 ;0,1=296,2=270.000000
L 1.3645 3.00549961 1.36553317 3.00243287 1 P 0 ;0,1=296,2=270.000000
L 1.36553317 3.00243287 1.3676003 3.00013337 1 P 0 ;0,1=296,2=270.000000
L 1.3676003 3.00013337 1.3706997 2.9985997 1 P 0 ;0,1=296,2=270.000000
L 1.3706997 2.9985997 1.37483406 2.99783317 1 P 0 ;0,1=296,2=270.000000
L 1.37483406 2.99783317 1.3784499 2.9985997 1 P 0 ;0,1=296,2=270.000000
L 1.3784499 2.9985997 1.38206673 3.00051663 1 P 0 ;0,1=296,2=270.000000
L 1.38206673 3.00051663 1.38413396 3.00281683 1 P 0 ;0,1=296,2=270.000000
L 1.38413396 3.00281683 1.38465049 3.00549961 1 P 0 ;0,1=296,2=270.000000
L 1.38465049 3.00549961 1.38361732 3.00856634 1 P 0 ;0,1=296,2=270.000000
L 1.38361732 3.00856634 1.38103366 3.01086654 1 P 0 ;0,1=296,2=270.000000
L 1.38103366 3.01086654 1.37638366 3.01316673 1 P 0 ;0,1=296,2=270.000000
L 1.3645 3.03649961 1.36553317 3.03343287 1 P 0 ;0,1=296,2=270.000000
L 1.36553317 3.03343287 1.36811693 3.03113337 1 P 0 ;0,1=296,2=270.000000
L 1.36811693 3.03113337 1.37121624 3.0295997 1 P 0 ;0,1=296,2=270.000000
L 1.37121624 3.0295997 1.37535059 3.0284499 1 P 0 ;0,1=296,2=270.000000
L 1.37535059 3.0284499 1.38000049 3.02806663 1 P 0 ;0,1=296,2=270.000000
L 1.38000049 3.02806663 1.38465049 3.0284499 1 P 0 ;0,1=296,2=270.000000
L 1.38465049 3.0284499 1.38878386 3.0295997 1 P 0 ;0,1=296,2=270.000000
L 1.38878386 3.0295997 1.39188415 3.03113337 1 P 0 ;0,1=296,2=270.000000
L 1.39188415 3.03113337 1.39446693 3.03343287 1 P 0 ;0,1=296,2=270.000000
L 1.39446693 3.03343287 1.3955 3.03649961 1 P 0 ;0,1=296,2=270.000000
L 1.3955 3.03649961 1.39446693 3.03956634 1 P 0 ;0,1=296,2=270.000000
L 1.39446693 3.03956634 1.39188415 3.04186654 1 P 0 ;0,1=296,2=270.000000
L 1.39188415 3.04186654 1.38878386 3.0434002 1 P 0 ;0,1=296,2=270.000000
L 1.38878386 3.0434002 1.38465049 3.04455 1 P 0 ;0,1=296,2=270.000000
L 1.38465049 3.04455 1.38000049 3.04493327 1 P 0 ;0,1=296,2=270.000000
L 1.38000049 3.04493327 1.37535059 3.04455 1 P 0 ;0,1=296,2=270.000000
L 1.37535059 3.04455 1.37121624 3.0434002 1 P 0 ;0,1=296,2=270.000000
L 1.37121624 3.0434002 1.36811693 3.04186654 1 P 0 ;0,1=296,2=270.000000
L 1.36811693 3.04186654 1.36553317 3.03956634 1 P 0 ;0,1=296,2=270.000000
L 1.36553317 3.03956634 1.3645 3.03649961 1 P 0 ;0,1=296,2=270.000000
L 4.552 1.115 4.552 1.205 1 P 0 
L 4.508 1.205 4.508 1.115 1 P 0 
L 4.508 1.115 4.552 1.115 1 P 0 
L 4.552 1.205 4.508 1.205 1 P 0 
L 4.5905 0.99583317 4.5595 0.99583317 1 P 0 ;0,1=297,2=270.000000
L 4.5595 0.99583317 4.5595 1.00541654 1 P 0 ;0,1=297,2=270.000000
L 4.5595 1.00541654 4.56105069 1.00848327 1 P 0 ;0,1=297,2=270.000000
L 4.56105069 1.00848327 4.56311693 1.0104002 1 P 0 ;0,1=297,2=270.000000
L 4.56311693 1.0104002 4.5672503 1.01116673 1 P 0 ;0,1=297,2=270.000000
L 4.5672503 1.01116673 4.57138366 1.0104002 1 P 0 ;0,1=297,2=270.000000
L 4.57138366 1.0104002 4.57396644 1.0081 1 P 0 ;0,1=297,2=270.000000
L 4.57396644 1.0081 4.57551713 1.00541654 1 P 0 ;0,1=297,2=270.000000
L 4.57551713 1.00541654 4.57551713 0.99583317 1 P 0 ;0,1=297,2=270.000000
L 4.57551713 1.00541654 4.5905 1.01116673 1 P 0 ;0,1=297,2=270.000000
L 4.5905 1.0391 4.5595 1.0391 1 P 0 ;0,1=297,2=270.000000
L 4.5595 1.0391 4.58171673 1.02491624 1 P 0 ;0,1=297,2=270.000000
L 4.58171673 1.02491624 4.58171673 1.04408366 1 P 0 ;0,1=297,2=270.000000
L 4.58430039 1.05706663 4.58791722 1.05936614 1 P 0 ;0,1=297,2=270.000000
L 4.58791722 1.05936614 4.58998346 1.06243287 1 P 0 ;0,1=297,2=270.000000
L 4.58998346 1.06243287 4.5905 1.06588356 1 P 0 ;0,1=297,2=270.000000
L 4.5905 1.06588356 4.58998346 1.0689503 1 P 0 ;0,1=297,2=270.000000
L 4.58998346 1.0689503 4.58740069 1.07201703 1 P 0 ;0,1=297,2=270.000000
L 4.58740069 1.07201703 4.58430039 1.07393327 1 P 0 ;0,1=297,2=270.000000
L 4.58430039 1.07393327 4.5812001 1.07431654 1 P 0 ;0,1=297,2=270.000000
L 4.5812001 1.07431654 4.57758425 1.07355 1 P 0 ;0,1=297,2=270.000000
L 4.57758425 1.07355 4.57500049 1.07086654 1 P 0 ;0,1=297,2=270.000000
L 4.57500049 1.07086654 4.57396644 1.06818307 1 P 0 ;0,1=297,2=270.000000
L 4.57396644 1.06818307 4.57396644 1.06473307 1 P 0 ;0,1=297,2=270.000000
L 4.57396644 1.06818307 4.57241683 1.07048327 1 P 0 ;0,1=297,2=270.000000
L 4.57241683 1.07048327 4.56983406 1.0724002 1 P 0 ;0,1=297,2=270.000000
L 4.56983406 1.0724002 4.56673376 1.07316673 1 P 0 ;0,1=297,2=270.000000
L 4.56673376 1.07316673 4.56363346 1.0724002 1 P 0 ;0,1=297,2=270.000000
L 4.56363346 1.0724002 4.56105069 1.07048327 1 P 0 ;0,1=297,2=270.000000
L 4.56105069 1.07048327 4.5595 1.06703327 1 P 0 ;0,1=297,2=270.000000
L 4.5595 1.06703327 4.56001663 1.06358337 1 P 0 ;0,1=297,2=270.000000
L 4.56001663 1.06358337 4.56208376 1.06013337 1 P 0 ;0,1=297,2=270.000000
L 4.58688415 1.08998287 4.58946693 1.09266634 1 P 0 ;0,1=297,2=270.000000
L 4.58946693 1.09266634 4.5905 1.09573307 1 P 0 ;0,1=297,2=270.000000
L 4.5905 1.09573307 4.58946693 1.0987998 1 P 0 ;0,1=297,2=270.000000
L 4.58946693 1.0987998 4.58636762 1.10148327 1 P 0 ;0,1=297,2=270.000000
L 4.58636762 1.10148327 4.58171673 1.1034002 1 P 0 ;0,1=297,2=270.000000
L 4.58171673 1.1034002 4.57706673 1.10416673 1 P 0 ;0,1=297,2=270.000000
L 4.57706673 1.10416673 4.57138366 1.10416673 1 P 0 ;0,1=297,2=270.000000
L 4.57138366 1.10416673 4.56673376 1.1034002 1 P 0 ;0,1=297,2=270.000000
L 4.56673376 1.1034002 4.5626003 1.10148327 1 P 0 ;0,1=297,2=270.000000
L 4.5626003 1.10148327 4.56053317 1.09918307 1 P 0 ;0,1=297,2=270.000000
L 4.56053317 1.09918307 4.5595 1.09649961 1 P 0 ;0,1=297,2=270.000000
L 4.5595 1.09649961 4.56053317 1.09343287 1 P 0 ;0,1=297,2=270.000000
L 4.56053317 1.09343287 4.5626003 1.09113337 1 P 0 ;0,1=297,2=270.000000
L 4.5626003 1.09113337 4.5656997 1.0895997 1 P 0 ;0,1=297,2=270.000000
L 4.5656997 1.0895997 4.56983406 1.08883317 1 P 0 ;0,1=297,2=270.000000
L 4.56983406 1.08883317 4.5734499 1.0895997 1 P 0 ;0,1=297,2=270.000000
L 4.5734499 1.0895997 4.57706673 1.09151663 1 P 0 ;0,1=297,2=270.000000
L 4.57706673 1.09151663 4.57913396 1.09381683 1 P 0 ;0,1=297,2=270.000000
L 4.57913396 1.09381683 4.57965049 1.09649961 1 P 0 ;0,1=297,2=270.000000
L 4.57965049 1.09649961 4.57861732 1.09956634 1 P 0 ;0,1=297,2=270.000000
L 4.57861732 1.09956634 4.57603366 1.10186654 1 P 0 ;0,1=297,2=270.000000
L 4.57603366 1.10186654 4.57138366 1.10416673 1 P 0 ;0,1=297,2=270.000000
L 4.563 1.205 4.563 1.115 1 P 0 
L 4.563 1.115 4.607 1.115 1 P 0 
L 4.607 1.115 4.607 1.205 1 P 0 
L 4.607 1.205 4.563 1.205 1 P 0 
L 4.6305 0.99583317 4.5995 0.99583317 1 P 0 ;0,1=298,2=270.000000
L 4.5995 0.99583317 4.5995 1.00541654 1 P 0 ;0,1=298,2=270.000000
L 4.5995 1.00541654 4.60105069 1.00848327 1 P 0 ;0,1=298,2=270.000000
L 4.60105069 1.00848327 4.60311693 1.0104002 1 P 0 ;0,1=298,2=270.000000
L 4.60311693 1.0104002 4.6072503 1.01116673 1 P 0 ;0,1=298,2=270.000000
L 4.6072503 1.01116673 4.61138366 1.0104002 1 P 0 ;0,1=298,2=270.000000
L 4.61138366 1.0104002 4.61396644 1.0081 1 P 0 ;0,1=298,2=270.000000
L 4.61396644 1.0081 4.61551713 1.00541654 1 P 0 ;0,1=298,2=270.000000
L 4.61551713 1.00541654 4.61551713 0.99583317 1 P 0 ;0,1=298,2=270.000000
L 4.61551713 1.00541654 4.6305 1.01116673 1 P 0 ;0,1=298,2=270.000000
L 4.6305 1.0391 4.5995 1.0391 1 P 0 ;0,1=298,2=270.000000
L 4.5995 1.0391 4.62171673 1.02491624 1 P 0 ;0,1=298,2=270.000000
L 4.62171673 1.02491624 4.62171673 1.04408366 1 P 0 ;0,1=298,2=270.000000
L 4.62430039 1.05706663 4.62791722 1.05936614 1 P 0 ;0,1=298,2=270.000000
L 4.62791722 1.05936614 4.62998346 1.06243287 1 P 0 ;0,1=298,2=270.000000
L 4.62998346 1.06243287 4.6305 1.06588356 1 P 0 ;0,1=298,2=270.000000
L 4.6305 1.06588356 4.62998346 1.0689503 1 P 0 ;0,1=298,2=270.000000
L 4.62998346 1.0689503 4.62740069 1.07201703 1 P 0 ;0,1=298,2=270.000000
L 4.62740069 1.07201703 4.62430039 1.07393327 1 P 0 ;0,1=298,2=270.000000
L 4.62430039 1.07393327 4.6212001 1.07431654 1 P 0 ;0,1=298,2=270.000000
L 4.6212001 1.07431654 4.61758425 1.07355 1 P 0 ;0,1=298,2=270.000000
L 4.61758425 1.07355 4.61500049 1.07086654 1 P 0 ;0,1=298,2=270.000000
L 4.61500049 1.07086654 4.61396644 1.06818307 1 P 0 ;0,1=298,2=270.000000
L 4.61396644 1.06818307 4.61396644 1.06473307 1 P 0 ;0,1=298,2=270.000000
L 4.61396644 1.06818307 4.61241683 1.07048327 1 P 0 ;0,1=298,2=270.000000
L 4.61241683 1.07048327 4.60983406 1.0724002 1 P 0 ;0,1=298,2=270.000000
L 4.60983406 1.0724002 4.60673376 1.07316673 1 P 0 ;0,1=298,2=270.000000
L 4.60673376 1.07316673 4.60363346 1.0724002 1 P 0 ;0,1=298,2=270.000000
L 4.60363346 1.0724002 4.60105069 1.07048327 1 P 0 ;0,1=298,2=270.000000
L 4.60105069 1.07048327 4.5995 1.06703327 1 P 0 ;0,1=298,2=270.000000
L 4.5995 1.06703327 4.60001663 1.06358337 1 P 0 ;0,1=298,2=270.000000
L 4.60001663 1.06358337 4.60208376 1.06013337 1 P 0 ;0,1=298,2=270.000000
L 4.6305 1.09649961 4.62998346 1.09918307 1 P 0 ;0,1=298,2=270.000000
L 4.62998346 1.09918307 4.62843386 1.1022498 1 P 0 ;0,1=298,2=270.000000
L 4.62843386 1.1022498 4.62585108 1.10416673 1 P 0 ;0,1=298,2=270.000000
L 4.62585108 1.10416673 4.62223327 1.10493327 1 P 0 ;0,1=298,2=270.000000
L 4.62223327 1.10493327 4.61861732 1.10416673 1 P 0 ;0,1=298,2=270.000000
L 4.61861732 1.10416673 4.61551713 1.10186654 1 P 0 ;0,1=298,2=270.000000
L 4.61551713 1.10186654 4.61396644 1.09841654 1 P 0 ;0,1=298,2=270.000000
L 4.61396644 1.09841654 4.61396644 1.09458337 1 P 0 ;0,1=298,2=270.000000
L 4.61396644 1.09458337 4.61293337 1.09228317 1 P 0 ;0,1=298,2=270.000000
L 4.61293337 1.09228317 4.61035059 1.09036614 1 P 0 ;0,1=298,2=270.000000
L 4.61035059 1.09036614 4.60673376 1.0895997 1 P 0 ;0,1=298,2=270.000000
L 4.60673376 1.0895997 4.60311693 1.0907501 1 P 0 ;0,1=298,2=270.000000
L 4.60311693 1.0907501 4.60053317 1.09343287 1 P 0 ;0,1=298,2=270.000000
L 4.60053317 1.09343287 4.5995 1.09649961 1 P 0 ;0,1=298,2=270.000000
L 4.5995 1.09649961 4.60053317 1.09956634 1 P 0 ;0,1=298,2=270.000000
L 4.60053317 1.09956634 4.60311693 1.1022498 1 P 0 ;0,1=298,2=270.000000
L 4.60311693 1.1022498 4.60673376 1.1034002 1 P 0 ;0,1=298,2=270.000000
L 4.60673376 1.1034002 4.61035059 1.10263307 1 P 0 ;0,1=298,2=270.000000
L 4.61035059 1.10263307 4.61293337 1.10071673 1 P 0 ;0,1=298,2=270.000000
L 4.61293337 1.10071673 4.61396644 1.09841654 1 P 0 ;0,1=298,2=270.000000
L 4.61396644 1.09841654 4.61396644 1.09458337 1 P 0 ;0,1=298,2=270.000000
L 4.61396644 1.09458337 4.61551713 1.09113337 1 P 0 ;0,1=298,2=270.000000
L 4.61551713 1.09113337 4.61861732 1.08883317 1 P 0 ;0,1=298,2=270.000000
L 4.61861732 1.08883317 4.62223327 1.08806663 1 P 0 ;0,1=298,2=270.000000
L 4.62223327 1.08806663 4.62585108 1.08883317 1 P 0 ;0,1=298,2=270.000000
L 4.62585108 1.08883317 4.62843386 1.0907501 1 P 0 ;0,1=298,2=270.000000
L 4.62843386 1.0907501 4.62998346 1.09381683 1 P 0 ;0,1=298,2=270.000000
L 4.62998346 1.09381683 4.6305 1.09649961 1 P 0 ;0,1=298,2=270.000000
L 4.172 2.576 4.128 2.576 1 P 0 
L 4.128 2.576 4.128 2.486 1 P 0 
L 4.128 2.486 4.172 2.486 1 P 0 
L 4.172 2.486 4.172 2.576 1 P 0 
L 4.2705 2.47583317 4.2395 2.47583317 1 P 0 ;0,1=299,2=270.000000
L 4.2395 2.47583317 4.2395 2.48541654 1 P 0 ;0,1=299,2=270.000000
L 4.2395 2.48541654 4.24105069 2.48848327 1 P 0 ;0,1=299,2=270.000000
L 4.24105069 2.48848327 4.24311693 2.4904002 1 P 0 ;0,1=299,2=270.000000
L 4.24311693 2.4904002 4.2472503 2.49116673 1 P 0 ;0,1=299,2=270.000000
L 4.2472503 2.49116673 4.25138366 2.4904002 1 P 0 ;0,1=299,2=270.000000
L 4.25138366 2.4904002 4.25396644 2.4881 1 P 0 ;0,1=299,2=270.000000
L 4.25396644 2.4881 4.25551713 2.48541654 1 P 0 ;0,1=299,2=270.000000
L 4.25551713 2.48541654 4.25551713 2.47583317 1 P 0 ;0,1=299,2=270.000000
L 4.25551713 2.48541654 4.2705 2.49116673 1 P 0 ;0,1=299,2=270.000000
L 4.26430039 2.50606663 4.26791722 2.50836614 1 P 0 ;0,1=299,2=270.000000
L 4.26791722 2.50836614 4.26998346 2.51143287 1 P 0 ;0,1=299,2=270.000000
L 4.26998346 2.51143287 4.2705 2.51488356 1 P 0 ;0,1=299,2=270.000000
L 4.2705 2.51488356 4.26998346 2.5179503 1 P 0 ;0,1=299,2=270.000000
L 4.26998346 2.5179503 4.26740069 2.52101703 1 P 0 ;0,1=299,2=270.000000
L 4.26740069 2.52101703 4.26430039 2.52293327 1 P 0 ;0,1=299,2=270.000000
L 4.26430039 2.52293327 4.2612001 2.52331654 1 P 0 ;0,1=299,2=270.000000
L 4.2612001 2.52331654 4.25758425 2.52255 1 P 0 ;0,1=299,2=270.000000
L 4.25758425 2.52255 4.25500049 2.51986654 1 P 0 ;0,1=299,2=270.000000
L 4.25500049 2.51986654 4.25396644 2.51718307 1 P 0 ;0,1=299,2=270.000000
L 4.25396644 2.51718307 4.25396644 2.51373307 1 P 0 ;0,1=299,2=270.000000
L 4.25396644 2.51718307 4.25241683 2.51948327 1 P 0 ;0,1=299,2=270.000000
L 4.25241683 2.51948327 4.24983406 2.5214002 1 P 0 ;0,1=299,2=270.000000
L 4.24983406 2.5214002 4.24673376 2.52216673 1 P 0 ;0,1=299,2=270.000000
L 4.24673376 2.52216673 4.24363346 2.5214002 1 P 0 ;0,1=299,2=270.000000
L 4.24363346 2.5214002 4.24105069 2.51948327 1 P 0 ;0,1=299,2=270.000000
L 4.24105069 2.51948327 4.2395 2.51603327 1 P 0 ;0,1=299,2=270.000000
L 4.2395 2.51603327 4.24001663 2.51258337 1 P 0 ;0,1=299,2=270.000000
L 4.24001663 2.51258337 4.24208376 2.50913337 1 P 0 ;0,1=299,2=270.000000
L 4.24466654 2.53821644 4.24156722 2.54051663 1 P 0 ;0,1=299,2=270.000000
L 4.24156722 2.54051663 4.24001663 2.5432001 1 P 0 ;0,1=299,2=270.000000
L 4.24001663 2.5432001 4.2395 2.54626683 1 P 0 ;0,1=299,2=270.000000
L 4.2395 2.54626683 4.24053317 2.5501 1 P 0 ;0,1=299,2=270.000000
L 4.24053317 2.5501 4.24311693 2.55278346 1 P 0 ;0,1=299,2=270.000000
L 4.24311693 2.55278346 4.24621624 2.55355 1 P 0 ;0,1=299,2=270.000000
L 4.24621624 2.55355 4.24931742 2.55316673 1 P 0 ;0,1=299,2=270.000000
L 4.24931742 2.55316673 4.2519002 2.55163307 1 P 0 ;0,1=299,2=270.000000
L 4.2519002 2.55163307 4.25706673 2.54396663 1 P 0 ;0,1=299,2=270.000000
L 4.25706673 2.54396663 4.26068356 2.54051663 1 P 0 ;0,1=299,2=270.000000
L 4.26068356 2.54051663 4.26585108 2.53821644 1 P 0 ;0,1=299,2=270.000000
L 4.26585108 2.53821644 4.2705 2.5374499 1 P 0 ;0,1=299,2=270.000000
L 4.2705 2.5374499 4.2705 2.55355 1 P 0 ;0,1=299,2=270.000000
L 4.2705 2.57573307 4.26378386 2.57649961 1 P 0 ;0,1=299,2=270.000000
L 4.26378386 2.57649961 4.25810079 2.5776501 1 P 0 ;0,1=299,2=270.000000
L 4.25810079 2.5776501 4.25293337 2.57918307 1 P 0 ;0,1=299,2=270.000000
L 4.25293337 2.57918307 4.2472503 2.5811 1 P 0 ;0,1=299,2=270.000000
L 4.2472503 2.5811 4.2395 2.58416673 1 P 0 ;0,1=299,2=270.000000
L 4.2395 2.58416673 4.2395 2.56883317 1 P 0 ;0,1=299,2=270.000000
L 4.231 2.576 4.187 2.576 1 P 0 
L 4.187 2.576 4.187 2.486 1 P 0 
L 4.187 2.486 4.231 2.486 1 P 0 
L 4.231 2.486 4.231 2.576 1 P 0 
L 4.3105 2.47583317 4.2795 2.47583317 1 P 0 ;0,1=300,2=270.000000
L 4.2795 2.47583317 4.2795 2.48541654 1 P 0 ;0,1=300,2=270.000000
L 4.2795 2.48541654 4.28105069 2.48848327 1 P 0 ;0,1=300,2=270.000000
L 4.28105069 2.48848327 4.28311693 2.4904002 1 P 0 ;0,1=300,2=270.000000
L 4.28311693 2.4904002 4.2872503 2.49116673 1 P 0 ;0,1=300,2=270.000000
L 4.2872503 2.49116673 4.29138366 2.4904002 1 P 0 ;0,1=300,2=270.000000
L 4.29138366 2.4904002 4.29396644 2.4881 1 P 0 ;0,1=300,2=270.000000
L 4.29396644 2.4881 4.29551713 2.48541654 1 P 0 ;0,1=300,2=270.000000
L 4.29551713 2.48541654 4.29551713 2.47583317 1 P 0 ;0,1=300,2=270.000000
L 4.29551713 2.48541654 4.3105 2.49116673 1 P 0 ;0,1=300,2=270.000000
L 4.30430039 2.50606663 4.30791722 2.50836614 1 P 0 ;0,1=300,2=270.000000
L 4.30791722 2.50836614 4.30998346 2.51143287 1 P 0 ;0,1=300,2=270.000000
L 4.30998346 2.51143287 4.3105 2.51488356 1 P 0 ;0,1=300,2=270.000000
L 4.3105 2.51488356 4.30998346 2.5179503 1 P 0 ;0,1=300,2=270.000000
L 4.30998346 2.5179503 4.30740069 2.52101703 1 P 0 ;0,1=300,2=270.000000
L 4.30740069 2.52101703 4.30430039 2.52293327 1 P 0 ;0,1=300,2=270.000000
L 4.30430039 2.52293327 4.3012001 2.52331654 1 P 0 ;0,1=300,2=270.000000
L 4.3012001 2.52331654 4.29758425 2.52255 1 P 0 ;0,1=300,2=270.000000
L 4.29758425 2.52255 4.29500049 2.51986654 1 P 0 ;0,1=300,2=270.000000
L 4.29500049 2.51986654 4.29396644 2.51718307 1 P 0 ;0,1=300,2=270.000000
L 4.29396644 2.51718307 4.29396644 2.51373307 1 P 0 ;0,1=300,2=270.000000
L 4.29396644 2.51718307 4.29241683 2.51948327 1 P 0 ;0,1=300,2=270.000000
L 4.29241683 2.51948327 4.28983406 2.5214002 1 P 0 ;0,1=300,2=270.000000
L 4.28983406 2.5214002 4.28673376 2.52216673 1 P 0 ;0,1=300,2=270.000000
L 4.28673376 2.52216673 4.28363346 2.5214002 1 P 0 ;0,1=300,2=270.000000
L 4.28363346 2.5214002 4.28105069 2.51948327 1 P 0 ;0,1=300,2=270.000000
L 4.28105069 2.51948327 4.2795 2.51603327 1 P 0 ;0,1=300,2=270.000000
L 4.2795 2.51603327 4.28001663 2.51258337 1 P 0 ;0,1=300,2=270.000000
L 4.28001663 2.51258337 4.28208376 2.50913337 1 P 0 ;0,1=300,2=270.000000
L 4.28466654 2.53821644 4.28156722 2.54051663 1 P 0 ;0,1=300,2=270.000000
L 4.28156722 2.54051663 4.28001663 2.5432001 1 P 0 ;0,1=300,2=270.000000
L 4.28001663 2.5432001 4.2795 2.54626683 1 P 0 ;0,1=300,2=270.000000
L 4.2795 2.54626683 4.28053317 2.5501 1 P 0 ;0,1=300,2=270.000000
L 4.28053317 2.5501 4.28311693 2.55278346 1 P 0 ;0,1=300,2=270.000000
L 4.28311693 2.55278346 4.28621624 2.55355 1 P 0 ;0,1=300,2=270.000000
L 4.28621624 2.55355 4.28931742 2.55316673 1 P 0 ;0,1=300,2=270.000000
L 4.28931742 2.55316673 4.2919002 2.55163307 1 P 0 ;0,1=300,2=270.000000
L 4.2919002 2.55163307 4.29706673 2.54396663 1 P 0 ;0,1=300,2=270.000000
L 4.29706673 2.54396663 4.30068356 2.54051663 1 P 0 ;0,1=300,2=270.000000
L 4.30068356 2.54051663 4.30585108 2.53821644 1 P 0 ;0,1=300,2=270.000000
L 4.30585108 2.53821644 4.3105 2.5374499 1 P 0 ;0,1=300,2=270.000000
L 4.3105 2.5374499 4.3105 2.55355 1 P 0 ;0,1=300,2=270.000000
L 4.30585108 2.56806663 4.30843386 2.57036614 1 P 0 ;0,1=300,2=270.000000
L 4.30843386 2.57036614 4.30998346 2.57304961 1 P 0 ;0,1=300,2=270.000000
L 4.30998346 2.57304961 4.3105 2.57649961 1 P 0 ;0,1=300,2=270.000000
L 4.3105 2.57649961 4.30946693 2.5799503 1 P 0 ;0,1=300,2=270.000000
L 4.30946693 2.5799503 4.30740069 2.58263307 1 P 0 ;0,1=300,2=270.000000
L 4.30740069 2.58263307 4.30378386 2.58455 1 P 0 ;0,1=300,2=270.000000
L 4.30378386 2.58455 4.29965049 2.58493327 1 P 0 ;0,1=300,2=270.000000
L 4.29965049 2.58493327 4.29551713 2.58416673 1 P 0 ;0,1=300,2=270.000000
L 4.29551713 2.58416673 4.29293337 2.5822498 1 P 0 ;0,1=300,2=270.000000
L 4.29293337 2.5822498 4.29086713 2.57956634 1 P 0 ;0,1=300,2=270.000000
L 4.29086713 2.57956634 4.29035059 2.57688356 1 P 0 ;0,1=300,2=270.000000
L 4.29035059 2.57688356 4.29086713 2.5742001 1 P 0 ;0,1=300,2=270.000000
L 4.29086713 2.5742001 4.29293337 2.5707501 1 P 0 ;0,1=300,2=270.000000
L 4.29293337 2.5707501 4.2795 2.5718999 1 P 0 ;0,1=300,2=270.000000
L 4.2795 2.5718999 4.2795 2.5822498 1 P 0 ;0,1=300,2=270.000000
L 4.115 2.576 4.071 2.576 1 P 0 
L 4.071 2.576 4.071 2.486 1 P 0 
L 4.071 2.486 4.115 2.486 1 P 0 
L 4.115 2.486 4.115 2.576 1 P 0 
L 4.1405 2.37083317 4.1095 2.37083317 1 P 0 ;0,1=301,2=270.000000
L 4.1095 2.37083317 4.1095 2.38041654 1 P 0 ;0,1=301,2=270.000000
L 4.1095 2.38041654 4.11105069 2.38348327 1 P 0 ;0,1=301,2=270.000000
L 4.11105069 2.38348327 4.11311693 2.3854002 1 P 0 ;0,1=301,2=270.000000
L 4.11311693 2.3854002 4.1172503 2.38616673 1 P 0 ;0,1=301,2=270.000000
L 4.1172503 2.38616673 4.12138366 2.3854002 1 P 0 ;0,1=301,2=270.000000
L 4.12138366 2.3854002 4.12396644 2.3831 1 P 0 ;0,1=301,2=270.000000
L 4.12396644 2.3831 4.12551713 2.38041654 1 P 0 ;0,1=301,2=270.000000
L 4.12551713 2.38041654 4.12551713 2.37083317 1 P 0 ;0,1=301,2=270.000000
L 4.12551713 2.38041654 4.1405 2.38616673 1 P 0 ;0,1=301,2=270.000000
L 4.13430039 2.40106663 4.13791722 2.40336614 1 P 0 ;0,1=301,2=270.000000
L 4.13791722 2.40336614 4.13998346 2.40643287 1 P 0 ;0,1=301,2=270.000000
L 4.13998346 2.40643287 4.1405 2.40988356 1 P 0 ;0,1=301,2=270.000000
L 4.1405 2.40988356 4.13998346 2.4129503 1 P 0 ;0,1=301,2=270.000000
L 4.13998346 2.4129503 4.13740069 2.41601703 1 P 0 ;0,1=301,2=270.000000
L 4.13740069 2.41601703 4.13430039 2.41793327 1 P 0 ;0,1=301,2=270.000000
L 4.13430039 2.41793327 4.1312001 2.41831654 1 P 0 ;0,1=301,2=270.000000
L 4.1312001 2.41831654 4.12758425 2.41755 1 P 0 ;0,1=301,2=270.000000
L 4.12758425 2.41755 4.12500049 2.41486654 1 P 0 ;0,1=301,2=270.000000
L 4.12500049 2.41486654 4.12396644 2.41218307 1 P 0 ;0,1=301,2=270.000000
L 4.12396644 2.41218307 4.12396644 2.40873307 1 P 0 ;0,1=301,2=270.000000
L 4.12396644 2.41218307 4.12241683 2.41448327 1 P 0 ;0,1=301,2=270.000000
L 4.12241683 2.41448327 4.11983406 2.4164002 1 P 0 ;0,1=301,2=270.000000
L 4.11983406 2.4164002 4.11673376 2.41716673 1 P 0 ;0,1=301,2=270.000000
L 4.11673376 2.41716673 4.11363346 2.4164002 1 P 0 ;0,1=301,2=270.000000
L 4.11363346 2.4164002 4.11105069 2.41448327 1 P 0 ;0,1=301,2=270.000000
L 4.11105069 2.41448327 4.1095 2.41103327 1 P 0 ;0,1=301,2=270.000000
L 4.1095 2.41103327 4.11001663 2.40758337 1 P 0 ;0,1=301,2=270.000000
L 4.11001663 2.40758337 4.11208376 2.40413337 1 P 0 ;0,1=301,2=270.000000
L 4.1095 2.44049961 4.11053317 2.43743287 1 P 0 ;0,1=301,2=270.000000
L 4.11053317 2.43743287 4.11311693 2.43513337 1 P 0 ;0,1=301,2=270.000000
L 4.11311693 2.43513337 4.11621624 2.4335997 1 P 0 ;0,1=301,2=270.000000
L 4.11621624 2.4335997 4.12035059 2.4324499 1 P 0 ;0,1=301,2=270.000000
L 4.12035059 2.4324499 4.12500049 2.43206663 1 P 0 ;0,1=301,2=270.000000
L 4.12500049 2.43206663 4.12965049 2.4324499 1 P 0 ;0,1=301,2=270.000000
L 4.12965049 2.4324499 4.13378386 2.4335997 1 P 0 ;0,1=301,2=270.000000
L 4.13378386 2.4335997 4.13688415 2.43513337 1 P 0 ;0,1=301,2=270.000000
L 4.13688415 2.43513337 4.13946693 2.43743287 1 P 0 ;0,1=301,2=270.000000
L 4.13946693 2.43743287 4.1405 2.44049961 1 P 0 ;0,1=301,2=270.000000
L 4.1405 2.44049961 4.13946693 2.44356634 1 P 0 ;0,1=301,2=270.000000
L 4.13946693 2.44356634 4.13688415 2.44586654 1 P 0 ;0,1=301,2=270.000000
L 4.13688415 2.44586654 4.13378386 2.4474002 1 P 0 ;0,1=301,2=270.000000
L 4.13378386 2.4474002 4.12965049 2.44855 1 P 0 ;0,1=301,2=270.000000
L 4.12965049 2.44855 4.12500049 2.44893327 1 P 0 ;0,1=301,2=270.000000
L 4.12500049 2.44893327 4.12035059 2.44855 1 P 0 ;0,1=301,2=270.000000
L 4.12035059 2.44855 4.11621624 2.4474002 1 P 0 ;0,1=301,2=270.000000
L 4.11621624 2.4474002 4.11311693 2.44586654 1 P 0 ;0,1=301,2=270.000000
L 4.11311693 2.44586654 4.11053317 2.44356634 1 P 0 ;0,1=301,2=270.000000
L 4.11053317 2.44356634 4.1095 2.44049961 1 P 0 ;0,1=301,2=270.000000
L 4.1405 2.47149961 4.13998346 2.47418307 1 P 0 ;0,1=301,2=270.000000
L 4.13998346 2.47418307 4.13843386 2.4772498 1 P 0 ;0,1=301,2=270.000000
L 4.13843386 2.4772498 4.13585108 2.47916673 1 P 0 ;0,1=301,2=270.000000
L 4.13585108 2.47916673 4.13223327 2.47993327 1 P 0 ;0,1=301,2=270.000000
L 4.13223327 2.47993327 4.12861732 2.47916673 1 P 0 ;0,1=301,2=270.000000
L 4.12861732 2.47916673 4.12551713 2.47686654 1 P 0 ;0,1=301,2=270.000000
L 4.12551713 2.47686654 4.12396644 2.47341654 1 P 0 ;0,1=301,2=270.000000
L 4.12396644 2.47341654 4.12396644 2.46958337 1 P 0 ;0,1=301,2=270.000000
L 4.12396644 2.46958337 4.12293337 2.46728317 1 P 0 ;0,1=301,2=270.000000
L 4.12293337 2.46728317 4.12035059 2.46536614 1 P 0 ;0,1=301,2=270.000000
L 4.12035059 2.46536614 4.11673376 2.4645997 1 P 0 ;0,1=301,2=270.000000
L 4.11673376 2.4645997 4.11311693 2.4657501 1 P 0 ;0,1=301,2=270.000000
L 4.11311693 2.4657501 4.11053317 2.46843287 1 P 0 ;0,1=301,2=270.000000
L 4.11053317 2.46843287 4.1095 2.47149961 1 P 0 ;0,1=301,2=270.000000
L 4.1095 2.47149961 4.11053317 2.47456634 1 P 0 ;0,1=301,2=270.000000
L 4.11053317 2.47456634 4.11311693 2.4772498 1 P 0 ;0,1=301,2=270.000000
L 4.11311693 2.4772498 4.11673376 2.4784002 1 P 0 ;0,1=301,2=270.000000
L 4.11673376 2.4784002 4.12035059 2.47763307 1 P 0 ;0,1=301,2=270.000000
L 4.12035059 2.47763307 4.12293337 2.47571673 1 P 0 ;0,1=301,2=270.000000
L 4.12293337 2.47571673 4.12396644 2.47341654 1 P 0 ;0,1=301,2=270.000000
L 4.12396644 2.47341654 4.12396644 2.46958337 1 P 0 ;0,1=301,2=270.000000
L 4.12396644 2.46958337 4.12551713 2.46613337 1 P 0 ;0,1=301,2=270.000000
L 4.12551713 2.46613337 4.12861732 2.46383317 1 P 0 ;0,1=301,2=270.000000
L 4.12861732 2.46383317 4.13223327 2.46306663 1 P 0 ;0,1=301,2=270.000000
L 4.13223327 2.46306663 4.13585108 2.46383317 1 P 0 ;0,1=301,2=270.000000
L 4.13585108 2.46383317 4.13843386 2.4657501 1 P 0 ;0,1=301,2=270.000000
L 4.13843386 2.4657501 4.13998346 2.46881683 1 P 0 ;0,1=301,2=270.000000
L 4.13998346 2.46881683 4.1405 2.47149961 1 P 0 ;0,1=301,2=270.000000
L 3.823 2.576 3.779 2.576 1 P 0 
L 3.779 2.576 3.779 2.486 1 P 0 
L 3.779 2.486 3.823 2.486 1 P 0 
L 3.823 2.486 3.823 2.576 1 P 0 
L 3.8455 2.37083317 3.8145 2.37083317 1 P 0 ;0,1=302,2=270.000000
L 3.8145 2.37083317 3.8145 2.38041654 1 P 0 ;0,1=302,2=270.000000
L 3.8145 2.38041654 3.81605069 2.38348327 1 P 0 ;0,1=302,2=270.000000
L 3.81605069 2.38348327 3.81811693 2.3854002 1 P 0 ;0,1=302,2=270.000000
L 3.81811693 2.3854002 3.8222503 2.38616673 1 P 0 ;0,1=302,2=270.000000
L 3.8222503 2.38616673 3.82638366 2.3854002 1 P 0 ;0,1=302,2=270.000000
L 3.82638366 2.3854002 3.82896644 2.3831 1 P 0 ;0,1=302,2=270.000000
L 3.82896644 2.3831 3.83051713 2.38041654 1 P 0 ;0,1=302,2=270.000000
L 3.83051713 2.38041654 3.83051713 2.37083317 1 P 0 ;0,1=302,2=270.000000
L 3.83051713 2.38041654 3.8455 2.38616673 1 P 0 ;0,1=302,2=270.000000
L 3.81966654 2.40221644 3.81656722 2.40451663 1 P 0 ;0,1=302,2=270.000000
L 3.81656722 2.40451663 3.81501663 2.4072001 1 P 0 ;0,1=302,2=270.000000
L 3.81501663 2.4072001 3.8145 2.41026683 1 P 0 ;0,1=302,2=270.000000
L 3.8145 2.41026683 3.81553317 2.4141 1 P 0 ;0,1=302,2=270.000000
L 3.81553317 2.4141 3.81811693 2.41678346 1 P 0 ;0,1=302,2=270.000000
L 3.81811693 2.41678346 3.82121624 2.41755 1 P 0 ;0,1=302,2=270.000000
L 3.82121624 2.41755 3.82431742 2.41716673 1 P 0 ;0,1=302,2=270.000000
L 3.82431742 2.41716673 3.8269002 2.41563307 1 P 0 ;0,1=302,2=270.000000
L 3.8269002 2.41563307 3.83206673 2.40796663 1 P 0 ;0,1=302,2=270.000000
L 3.83206673 2.40796663 3.83568356 2.40451663 1 P 0 ;0,1=302,2=270.000000
L 3.83568356 2.40451663 3.84085108 2.40221644 1 P 0 ;0,1=302,2=270.000000
L 3.84085108 2.40221644 3.8455 2.4014499 1 P 0 ;0,1=302,2=270.000000
L 3.8455 2.4014499 3.8455 2.41755 1 P 0 ;0,1=302,2=270.000000
L 3.8455 2.44049961 3.84498346 2.44318307 1 P 0 ;0,1=302,2=270.000000
L 3.84498346 2.44318307 3.84343386 2.4462498 1 P 0 ;0,1=302,2=270.000000
L 3.84343386 2.4462498 3.84085108 2.44816673 1 P 0 ;0,1=302,2=270.000000
L 3.84085108 2.44816673 3.83723327 2.44893327 1 P 0 ;0,1=302,2=270.000000
L 3.83723327 2.44893327 3.83361732 2.44816673 1 P 0 ;0,1=302,2=270.000000
L 3.83361732 2.44816673 3.83051713 2.44586654 1 P 0 ;0,1=302,2=270.000000
L 3.83051713 2.44586654 3.82896644 2.44241654 1 P 0 ;0,1=302,2=270.000000
L 3.82896644 2.44241654 3.82896644 2.43858337 1 P 0 ;0,1=302,2=270.000000
L 3.82896644 2.43858337 3.82793337 2.43628317 1 P 0 ;0,1=302,2=270.000000
L 3.82793337 2.43628317 3.82535059 2.43436614 1 P 0 ;0,1=302,2=270.000000
L 3.82535059 2.43436614 3.82173376 2.4335997 1 P 0 ;0,1=302,2=270.000000
L 3.82173376 2.4335997 3.81811693 2.4347501 1 P 0 ;0,1=302,2=270.000000
L 3.81811693 2.4347501 3.81553317 2.43743287 1 P 0 ;0,1=302,2=270.000000
L 3.81553317 2.43743287 3.8145 2.44049961 1 P 0 ;0,1=302,2=270.000000
L 3.8145 2.44049961 3.81553317 2.44356634 1 P 0 ;0,1=302,2=270.000000
L 3.81553317 2.44356634 3.81811693 2.4462498 1 P 0 ;0,1=302,2=270.000000
L 3.81811693 2.4462498 3.82173376 2.4474002 1 P 0 ;0,1=302,2=270.000000
L 3.82173376 2.4474002 3.82535059 2.44663307 1 P 0 ;0,1=302,2=270.000000
L 3.82535059 2.44663307 3.82793337 2.44471673 1 P 0 ;0,1=302,2=270.000000
L 3.82793337 2.44471673 3.82896644 2.44241654 1 P 0 ;0,1=302,2=270.000000
L 3.82896644 2.44241654 3.82896644 2.43858337 1 P 0 ;0,1=302,2=270.000000
L 3.82896644 2.43858337 3.83051713 2.43513337 1 P 0 ;0,1=302,2=270.000000
L 3.83051713 2.43513337 3.83361732 2.43283317 1 P 0 ;0,1=302,2=270.000000
L 3.83361732 2.43283317 3.83723327 2.43206663 1 P 0 ;0,1=302,2=270.000000
L 3.83723327 2.43206663 3.84085108 2.43283317 1 P 0 ;0,1=302,2=270.000000
L 3.84085108 2.43283317 3.84343386 2.4347501 1 P 0 ;0,1=302,2=270.000000
L 3.84343386 2.4347501 3.84498346 2.43781683 1 P 0 ;0,1=302,2=270.000000
L 3.84498346 2.43781683 3.8455 2.44049961 1 P 0 ;0,1=302,2=270.000000
L 3.84085108 2.46306663 3.84343386 2.46536614 1 P 0 ;0,1=302,2=270.000000
L 3.84343386 2.46536614 3.84498346 2.46804961 1 P 0 ;0,1=302,2=270.000000
L 3.84498346 2.46804961 3.8455 2.47149961 1 P 0 ;0,1=302,2=270.000000
L 3.8455 2.47149961 3.84446693 2.4749503 1 P 0 ;0,1=302,2=270.000000
L 3.84446693 2.4749503 3.84240069 2.47763307 1 P 0 ;0,1=302,2=270.000000
L 3.84240069 2.47763307 3.83878386 2.47955 1 P 0 ;0,1=302,2=270.000000
L 3.83878386 2.47955 3.83465049 2.47993327 1 P 0 ;0,1=302,2=270.000000
L 3.83465049 2.47993327 3.83051713 2.47916673 1 P 0 ;0,1=302,2=270.000000
L 3.83051713 2.47916673 3.82793337 2.4772498 1 P 0 ;0,1=302,2=270.000000
L 3.82793337 2.4772498 3.82586713 2.47456634 1 P 0 ;0,1=302,2=270.000000
L 3.82586713 2.47456634 3.82535059 2.47188356 1 P 0 ;0,1=302,2=270.000000
L 3.82535059 2.47188356 3.82586713 2.4692001 1 P 0 ;0,1=302,2=270.000000
L 3.82586713 2.4692001 3.82793337 2.4657501 1 P 0 ;0,1=302,2=270.000000
L 3.82793337 2.4657501 3.8145 2.4668999 1 P 0 ;0,1=302,2=270.000000
L 3.8145 2.4668999 3.8145 2.4772498 1 P 0 ;0,1=302,2=270.000000
L 3.882 2.576 3.838 2.576 1 P 0 
L 3.838 2.576 3.838 2.486 1 P 0 
L 3.838 2.486 3.882 2.486 1 P 0 
L 3.882 2.486 3.882 2.576 1 P 0 
L 3.9055 2.37083317 3.8745 2.37083317 1 P 0 ;0,1=303,2=270.000000
L 3.8745 2.37083317 3.8745 2.38041654 1 P 0 ;0,1=303,2=270.000000
L 3.8745 2.38041654 3.87605069 2.38348327 1 P 0 ;0,1=303,2=270.000000
L 3.87605069 2.38348327 3.87811693 2.3854002 1 P 0 ;0,1=303,2=270.000000
L 3.87811693 2.3854002 3.8822503 2.38616673 1 P 0 ;0,1=303,2=270.000000
L 3.8822503 2.38616673 3.88638366 2.3854002 1 P 0 ;0,1=303,2=270.000000
L 3.88638366 2.3854002 3.88896644 2.3831 1 P 0 ;0,1=303,2=270.000000
L 3.88896644 2.3831 3.89051713 2.38041654 1 P 0 ;0,1=303,2=270.000000
L 3.89051713 2.38041654 3.89051713 2.37083317 1 P 0 ;0,1=303,2=270.000000
L 3.89051713 2.38041654 3.9055 2.38616673 1 P 0 ;0,1=303,2=270.000000
L 3.87966654 2.40221644 3.87656722 2.40451663 1 P 0 ;0,1=303,2=270.000000
L 3.87656722 2.40451663 3.87501663 2.4072001 1 P 0 ;0,1=303,2=270.000000
L 3.87501663 2.4072001 3.8745 2.41026683 1 P 0 ;0,1=303,2=270.000000
L 3.8745 2.41026683 3.87553317 2.4141 1 P 0 ;0,1=303,2=270.000000
L 3.87553317 2.4141 3.87811693 2.41678346 1 P 0 ;0,1=303,2=270.000000
L 3.87811693 2.41678346 3.88121624 2.41755 1 P 0 ;0,1=303,2=270.000000
L 3.88121624 2.41755 3.88431742 2.41716673 1 P 0 ;0,1=303,2=270.000000
L 3.88431742 2.41716673 3.8869002 2.41563307 1 P 0 ;0,1=303,2=270.000000
L 3.8869002 2.41563307 3.89206673 2.40796663 1 P 0 ;0,1=303,2=270.000000
L 3.89206673 2.40796663 3.89568356 2.40451663 1 P 0 ;0,1=303,2=270.000000
L 3.89568356 2.40451663 3.90085108 2.40221644 1 P 0 ;0,1=303,2=270.000000
L 3.90085108 2.40221644 3.9055 2.4014499 1 P 0 ;0,1=303,2=270.000000
L 3.9055 2.4014499 3.9055 2.41755 1 P 0 ;0,1=303,2=270.000000
L 3.9055 2.44049961 3.90498346 2.44318307 1 P 0 ;0,1=303,2=270.000000
L 3.90498346 2.44318307 3.90343386 2.4462498 1 P 0 ;0,1=303,2=270.000000
L 3.90343386 2.4462498 3.90085108 2.44816673 1 P 0 ;0,1=303,2=270.000000
L 3.90085108 2.44816673 3.89723327 2.44893327 1 P 0 ;0,1=303,2=270.000000
L 3.89723327 2.44893327 3.89361732 2.44816673 1 P 0 ;0,1=303,2=270.000000
L 3.89361732 2.44816673 3.89051713 2.44586654 1 P 0 ;0,1=303,2=270.000000
L 3.89051713 2.44586654 3.88896644 2.44241654 1 P 0 ;0,1=303,2=270.000000
L 3.88896644 2.44241654 3.88896644 2.43858337 1 P 0 ;0,1=303,2=270.000000
L 3.88896644 2.43858337 3.88793337 2.43628317 1 P 0 ;0,1=303,2=270.000000
L 3.88793337 2.43628317 3.88535059 2.43436614 1 P 0 ;0,1=303,2=270.000000
L 3.88535059 2.43436614 3.88173376 2.4335997 1 P 0 ;0,1=303,2=270.000000
L 3.88173376 2.4335997 3.87811693 2.4347501 1 P 0 ;0,1=303,2=270.000000
L 3.87811693 2.4347501 3.87553317 2.43743287 1 P 0 ;0,1=303,2=270.000000
L 3.87553317 2.43743287 3.8745 2.44049961 1 P 0 ;0,1=303,2=270.000000
L 3.8745 2.44049961 3.87553317 2.44356634 1 P 0 ;0,1=303,2=270.000000
L 3.87553317 2.44356634 3.87811693 2.4462498 1 P 0 ;0,1=303,2=270.000000
L 3.87811693 2.4462498 3.88173376 2.4474002 1 P 0 ;0,1=303,2=270.000000
L 3.88173376 2.4474002 3.88535059 2.44663307 1 P 0 ;0,1=303,2=270.000000
L 3.88535059 2.44663307 3.88793337 2.44471673 1 P 0 ;0,1=303,2=270.000000
L 3.88793337 2.44471673 3.88896644 2.44241654 1 P 0 ;0,1=303,2=270.000000
L 3.88896644 2.44241654 3.88896644 2.43858337 1 P 0 ;0,1=303,2=270.000000
L 3.88896644 2.43858337 3.89051713 2.43513337 1 P 0 ;0,1=303,2=270.000000
L 3.89051713 2.43513337 3.89361732 2.43283317 1 P 0 ;0,1=303,2=270.000000
L 3.89361732 2.43283317 3.89723327 2.43206663 1 P 0 ;0,1=303,2=270.000000
L 3.89723327 2.43206663 3.90085108 2.43283317 1 P 0 ;0,1=303,2=270.000000
L 3.90085108 2.43283317 3.90343386 2.4347501 1 P 0 ;0,1=303,2=270.000000
L 3.90343386 2.4347501 3.90498346 2.43781683 1 P 0 ;0,1=303,2=270.000000
L 3.90498346 2.43781683 3.9055 2.44049961 1 P 0 ;0,1=303,2=270.000000
L 3.89930039 2.46306663 3.90291722 2.46536614 1 P 0 ;0,1=303,2=270.000000
L 3.90291722 2.46536614 3.90498346 2.46843287 1 P 0 ;0,1=303,2=270.000000
L 3.90498346 2.46843287 3.9055 2.47188356 1 P 0 ;0,1=303,2=270.000000
L 3.9055 2.47188356 3.90498346 2.4749503 1 P 0 ;0,1=303,2=270.000000
L 3.90498346 2.4749503 3.90240069 2.47801703 1 P 0 ;0,1=303,2=270.000000
L 3.90240069 2.47801703 3.89930039 2.47993327 1 P 0 ;0,1=303,2=270.000000
L 3.89930039 2.47993327 3.8962001 2.48031654 1 P 0 ;0,1=303,2=270.000000
L 3.8962001 2.48031654 3.89258425 2.47955 1 P 0 ;0,1=303,2=270.000000
L 3.89258425 2.47955 3.89000049 2.47686654 1 P 0 ;0,1=303,2=270.000000
L 3.89000049 2.47686654 3.88896644 2.47418307 1 P 0 ;0,1=303,2=270.000000
L 3.88896644 2.47418307 3.88896644 2.47073307 1 P 0 ;0,1=303,2=270.000000
L 3.88896644 2.47418307 3.88741683 2.47648327 1 P 0 ;0,1=303,2=270.000000
L 3.88741683 2.47648327 3.88483406 2.4784002 1 P 0 ;0,1=303,2=270.000000
L 3.88483406 2.4784002 3.88173376 2.47916673 1 P 0 ;0,1=303,2=270.000000
L 3.88173376 2.47916673 3.87863346 2.4784002 1 P 0 ;0,1=303,2=270.000000
L 3.87863346 2.4784002 3.87605069 2.47648327 1 P 0 ;0,1=303,2=270.000000
L 3.87605069 2.47648327 3.8745 2.47303327 1 P 0 ;0,1=303,2=270.000000
L 3.8745 2.47303327 3.87501663 2.46958337 1 P 0 ;0,1=303,2=270.000000
L 3.87501663 2.46958337 3.87708376 2.46613337 1 P 0 ;0,1=303,2=270.000000
L 0.565 3.268 0.655 3.268 1 P 0 
L 0.655 3.268 0.655 3.312 1 P 0 
L 0.655 3.312 0.565 3.312 1 P 0 
L 0.565 3.312 0.565 3.268 1 P 0 
L 0.50083317 3.2295 0.50083317 3.2605 1 P 0 ;0,1=304,2=0.000000
L 0.50083317 3.2605 0.51041654 3.2605 1 P 0 ;0,1=304,2=0.000000
L 0.51041654 3.2605 0.51348327 3.25894931 1 P 0 ;0,1=304,2=0.000000
L 0.51348327 3.25894931 0.5154002 3.25688307 1 P 0 ;0,1=304,2=0.000000
L 0.5154002 3.25688307 0.51616673 3.2527497 1 P 0 ;0,1=304,2=0.000000
L 0.51616673 3.2527497 0.5154002 3.24861634 1 P 0 ;0,1=304,2=0.000000
L 0.5154002 3.24861634 0.5131 3.24603356 1 P 0 ;0,1=304,2=0.000000
L 0.5131 3.24603356 0.51041654 3.24448287 1 P 0 ;0,1=304,2=0.000000
L 0.51041654 3.24448287 0.50083317 3.24448287 1 P 0 ;0,1=304,2=0.000000
L 0.51041654 3.24448287 0.51616673 3.2295 1 P 0 ;0,1=304,2=0.000000
L 0.5441 3.2295 0.5441 3.2605 1 P 0 ;0,1=304,2=0.000000
L 0.5441 3.2605 0.52991624 3.23828327 1 P 0 ;0,1=304,2=0.000000
L 0.52991624 3.23828327 0.54908366 3.23828327 1 P 0 ;0,1=304,2=0.000000
L 0.5751 3.2295 0.5751 3.2605 1 P 0 ;0,1=304,2=0.000000
L 0.5751 3.2605 0.56091624 3.23828327 1 P 0 ;0,1=304,2=0.000000
L 0.56091624 3.23828327 0.58008366 3.23828327 1 P 0 ;0,1=304,2=0.000000
L 0.59306663 3.23414892 0.59536614 3.23156614 1 P 0 ;0,1=304,2=0.000000
L 0.59536614 3.23156614 0.59804961 3.23001654 1 P 0 ;0,1=304,2=0.000000
L 0.59804961 3.23001654 0.60149961 3.2295 1 P 0 ;0,1=304,2=0.000000
L 0.60149961 3.2295 0.6049503 3.23053307 1 P 0 ;0,1=304,2=0.000000
L 0.6049503 3.23053307 0.60763307 3.23259931 1 P 0 ;0,1=304,2=0.000000
L 0.60763307 3.23259931 0.60955 3.23621614 1 P 0 ;0,1=304,2=0.000000
L 0.60955 3.23621614 0.60993327 3.24034951 1 P 0 ;0,1=304,2=0.000000
L 0.60993327 3.24034951 0.60916673 3.24448287 1 P 0 ;0,1=304,2=0.000000
L 0.60916673 3.24448287 0.6072498 3.24706663 1 P 0 ;0,1=304,2=0.000000
L 0.6072498 3.24706663 0.60456634 3.24913287 1 P 0 ;0,1=304,2=0.000000
L 0.60456634 3.24913287 0.60188356 3.24964941 1 P 0 ;0,1=304,2=0.000000
L 0.60188356 3.24964941 0.5992001 3.24913287 1 P 0 ;0,1=304,2=0.000000
L 0.5992001 3.24913287 0.5957501 3.24706663 1 P 0 ;0,1=304,2=0.000000
L 0.5957501 3.24706663 0.5968999 3.2605 1 P 0 ;0,1=304,2=0.000000
L 0.5968999 3.2605 0.6072498 3.2605 1 P 0 ;0,1=304,2=0.000000
L 0.617 3.62 0.573 3.62 1 P 0 
L 0.617 3.53 0.617 3.62 1 P 0 
L 0.573 3.62 0.573 3.53 1 P 0 
L 0.573 3.53 0.617 3.53 1 P 0 
L 0.5655 3.57083317 0.5345 3.57083317 1 P 0 ;0,1=305,2=270.000000
L 0.5345 3.57083317 0.5345 3.58041654 1 P 0 ;0,1=305,2=270.000000
L 0.5345 3.58041654 0.53605069 3.58348327 1 P 0 ;0,1=305,2=270.000000
L 0.53605069 3.58348327 0.53811693 3.5854002 1 P 0 ;0,1=305,2=270.000000
L 0.53811693 3.5854002 0.5422503 3.58616673 1 P 0 ;0,1=305,2=270.000000
L 0.5422503 3.58616673 0.54638366 3.5854002 1 P 0 ;0,1=305,2=270.000000
L 0.54638366 3.5854002 0.54896644 3.5831 1 P 0 ;0,1=305,2=270.000000
L 0.54896644 3.5831 0.55051713 3.58041654 1 P 0 ;0,1=305,2=270.000000
L 0.55051713 3.58041654 0.55051713 3.57083317 1 P 0 ;0,1=305,2=270.000000
L 0.55051713 3.58041654 0.5655 3.58616673 1 P 0 ;0,1=305,2=270.000000
L 0.5655 3.6141 0.5345 3.6141 1 P 0 ;0,1=305,2=270.000000
L 0.5345 3.6141 0.55671673 3.59991624 1 P 0 ;0,1=305,2=270.000000
L 0.55671673 3.59991624 0.55671673 3.61908366 1 P 0 ;0,1=305,2=270.000000
L 0.5655 3.6451 0.5345 3.6451 1 P 0 ;0,1=305,2=270.000000
L 0.5345 3.6451 0.55671673 3.63091624 1 P 0 ;0,1=305,2=270.000000
L 0.55671673 3.63091624 0.55671673 3.65008366 1 P 0 ;0,1=305,2=270.000000
L 0.53966654 3.66421644 0.53656722 3.66651663 1 P 0 ;0,1=305,2=270.000000
L 0.53656722 3.66651663 0.53501663 3.6692001 1 P 0 ;0,1=305,2=270.000000
L 0.53501663 3.6692001 0.5345 3.67226683 1 P 0 ;0,1=305,2=270.000000
L 0.5345 3.67226683 0.53553317 3.6761 1 P 0 ;0,1=305,2=270.000000
L 0.53553317 3.6761 0.53811693 3.67878346 1 P 0 ;0,1=305,2=270.000000
L 0.53811693 3.67878346 0.54121624 3.67955 1 P 0 ;0,1=305,2=270.000000
L 0.54121624 3.67955 0.54431742 3.67916673 1 P 0 ;0,1=305,2=270.000000
L 0.54431742 3.67916673 0.5469002 3.67763307 1 P 0 ;0,1=305,2=270.000000
L 0.5469002 3.67763307 0.55206673 3.66996663 1 P 0 ;0,1=305,2=270.000000
L 0.55206673 3.66996663 0.55568356 3.66651663 1 P 0 ;0,1=305,2=270.000000
L 0.55568356 3.66651663 0.56085108 3.66421644 1 P 0 ;0,1=305,2=270.000000
L 0.56085108 3.66421644 0.5655 3.6634499 1 P 0 ;0,1=305,2=270.000000
L 0.5655 3.6634499 0.5655 3.67955 1 P 0 ;0,1=305,2=270.000000
L 1.295 3.772 1.205 3.772 1 P 0 
L 1.205 3.772 1.205 3.728 1 P 0 
L 1.205 3.728 1.295 3.728 1 P 0 
L 1.295 3.728 1.295 3.772 1 P 0 
L 1.30083317 3.6695 1.30083317 3.7005 1 P 0 ;0,1=306,2=0.000000
L 1.30083317 3.7005 1.31041654 3.7005 1 P 0 ;0,1=306,2=0.000000
L 1.31041654 3.7005 1.31348327 3.69894931 1 P 0 ;0,1=306,2=0.000000
L 1.31348327 3.69894931 1.3154002 3.69688307 1 P 0 ;0,1=306,2=0.000000
L 1.3154002 3.69688307 1.31616673 3.6927497 1 P 0 ;0,1=306,2=0.000000
L 1.31616673 3.6927497 1.3154002 3.68861634 1 P 0 ;0,1=306,2=0.000000
L 1.3154002 3.68861634 1.3131 3.68603356 1 P 0 ;0,1=306,2=0.000000
L 1.3131 3.68603356 1.31041654 3.68448287 1 P 0 ;0,1=306,2=0.000000
L 1.31041654 3.68448287 1.30083317 3.68448287 1 P 0 ;0,1=306,2=0.000000
L 1.31041654 3.68448287 1.31616673 3.6695 1 P 0 ;0,1=306,2=0.000000
L 1.3441 3.6695 1.3441 3.7005 1 P 0 ;0,1=306,2=0.000000
L 1.3441 3.7005 1.32991624 3.67828327 1 P 0 ;0,1=306,2=0.000000
L 1.32991624 3.67828327 1.34908366 3.67828327 1 P 0 ;0,1=306,2=0.000000
L 1.36206663 3.67414892 1.36436614 3.67156614 1 P 0 ;0,1=306,2=0.000000
L 1.36436614 3.67156614 1.36704961 3.67001654 1 P 0 ;0,1=306,2=0.000000
L 1.36704961 3.67001654 1.37049961 3.6695 1 P 0 ;0,1=306,2=0.000000
L 1.37049961 3.6695 1.3739503 3.67053307 1 P 0 ;0,1=306,2=0.000000
L 1.3739503 3.67053307 1.37663307 3.67259931 1 P 0 ;0,1=306,2=0.000000
L 1.37663307 3.67259931 1.37855 3.67621614 1 P 0 ;0,1=306,2=0.000000
L 1.37855 3.67621614 1.37893327 3.68034951 1 P 0 ;0,1=306,2=0.000000
L 1.37893327 3.68034951 1.37816673 3.68448287 1 P 0 ;0,1=306,2=0.000000
L 1.37816673 3.68448287 1.3762498 3.68706663 1 P 0 ;0,1=306,2=0.000000
L 1.3762498 3.68706663 1.37356634 3.68913287 1 P 0 ;0,1=306,2=0.000000
L 1.37356634 3.68913287 1.37088356 3.68964941 1 P 0 ;0,1=306,2=0.000000
L 1.37088356 3.68964941 1.3682001 3.68913287 1 P 0 ;0,1=306,2=0.000000
L 1.3682001 3.68913287 1.3647501 3.68706663 1 P 0 ;0,1=306,2=0.000000
L 1.3647501 3.68706663 1.3658999 3.7005 1 P 0 ;0,1=306,2=0.000000
L 1.3658999 3.7005 1.3762498 3.7005 1 P 0 ;0,1=306,2=0.000000
L 1.39306663 3.67414892 1.39536614 3.67156614 1 P 0 ;0,1=306,2=0.000000
L 1.39536614 3.67156614 1.39804961 3.67001654 1 P 0 ;0,1=306,2=0.000000
L 1.39804961 3.67001654 1.40149961 3.6695 1 P 0 ;0,1=306,2=0.000000
L 1.40149961 3.6695 1.4049503 3.67053307 1 P 0 ;0,1=306,2=0.000000
L 1.4049503 3.67053307 1.40763307 3.67259931 1 P 0 ;0,1=306,2=0.000000
L 1.40763307 3.67259931 1.40955 3.67621614 1 P 0 ;0,1=306,2=0.000000
L 1.40955 3.67621614 1.40993327 3.68034951 1 P 0 ;0,1=306,2=0.000000
L 1.40993327 3.68034951 1.40916673 3.68448287 1 P 0 ;0,1=306,2=0.000000
L 1.40916673 3.68448287 1.4072498 3.68706663 1 P 0 ;0,1=306,2=0.000000
L 1.4072498 3.68706663 1.40456634 3.68913287 1 P 0 ;0,1=306,2=0.000000
L 1.40456634 3.68913287 1.40188356 3.68964941 1 P 0 ;0,1=306,2=0.000000
L 1.40188356 3.68964941 1.3992001 3.68913287 1 P 0 ;0,1=306,2=0.000000
L 1.3992001 3.68913287 1.3957501 3.68706663 1 P 0 ;0,1=306,2=0.000000
L 1.3957501 3.68706663 1.3968999 3.7005 1 P 0 ;0,1=306,2=0.000000
L 1.3968999 3.7005 1.4072498 3.7005 1 P 0 ;0,1=306,2=0.000000
L 3.882 2.658 3.882 2.702 1 P 0 
L 3.882 2.702 3.792 2.702 1 P 0 
L 3.792 2.658 3.882 2.658 1 P 0 
L 3.792 2.702 3.792 2.658 1 P 0 
L 2.67783317 3.41466004 2.67783317 3.44566004 1 P 0 ;0,1=307,2=0.000000
L 2.67783317 3.44566004 2.68741654 3.44566004 1 P 0 ;0,1=307,2=0.000000
L 2.68741654 3.44566004 2.69048327 3.44410935 1 P 0 ;0,1=307,2=0.000000
L 2.69048327 3.44410935 2.6924002 3.44204311 1 P 0 ;0,1=307,2=0.000000
L 2.6924002 3.44204311 2.69316673 3.43790974 1 P 0 ;0,1=307,2=0.000000
L 2.69316673 3.43790974 2.6924002 3.43377638 1 P 0 ;0,1=307,2=0.000000
L 2.6924002 3.43377638 2.6901 3.4311936 1 P 0 ;0,1=307,2=0.000000
L 2.6901 3.4311936 2.68741654 3.42964291 1 P 0 ;0,1=307,2=0.000000
L 2.68741654 3.42964291 2.67783317 3.42964291 1 P 0 ;0,1=307,2=0.000000
L 2.68741654 3.42964291 2.69316673 3.41466004 1 P 0 ;0,1=307,2=0.000000
L 2.71649961 3.41466004 2.71649961 3.44566004 1 P 0 ;0,1=307,2=0.000000
L 2.71649961 3.44566004 2.7118999 3.43946033 1 P 0 ;0,1=307,2=0.000000
L 2.7118999 3.41466004 2.72109931 3.41466004 1 P 0 ;0,1=307,2=0.000000
L 2.74749961 3.41466004 2.75018307 3.41517657 1 P 0 ;0,1=307,2=0.000000
L 2.75018307 3.41517657 2.7532498 3.41672618 1 P 0 ;0,1=307,2=0.000000
L 2.7532498 3.41672618 2.75516673 3.41930896 1 P 0 ;0,1=307,2=0.000000
L 2.75516673 3.41930896 2.75593327 3.42292677 1 P 0 ;0,1=307,2=0.000000
L 2.75593327 3.42292677 2.75516673 3.42654272 1 P 0 ;0,1=307,2=0.000000
L 2.75516673 3.42654272 2.75286654 3.42964291 1 P 0 ;0,1=307,2=0.000000
L 2.75286654 3.42964291 2.74941654 3.4311936 1 P 0 ;0,1=307,2=0.000000
L 2.74941654 3.4311936 2.74558337 3.4311936 1 P 0 ;0,1=307,2=0.000000
L 2.74558337 3.4311936 2.74328317 3.43222667 1 P 0 ;0,1=307,2=0.000000
L 2.74328317 3.43222667 2.74136614 3.43480945 1 P 0 ;0,1=307,2=0.000000
L 2.74136614 3.43480945 2.7405997 3.43842628 1 P 0 ;0,1=307,2=0.000000
L 2.7405997 3.43842628 2.7417501 3.44204311 1 P 0 ;0,1=307,2=0.000000
L 2.7417501 3.44204311 2.74443287 3.44462687 1 P 0 ;0,1=307,2=0.000000
L 2.74443287 3.44462687 2.74749961 3.44566004 1 P 0 ;0,1=307,2=0.000000
L 2.74749961 3.44566004 2.75056634 3.44462687 1 P 0 ;0,1=307,2=0.000000
L 2.75056634 3.44462687 2.7532498 3.44204311 1 P 0 ;0,1=307,2=0.000000
L 2.7532498 3.44204311 2.7544002 3.43842628 1 P 0 ;0,1=307,2=0.000000
L 2.7544002 3.43842628 2.75363307 3.43480945 1 P 0 ;0,1=307,2=0.000000
L 2.75363307 3.43480945 2.75171673 3.43222667 1 P 0 ;0,1=307,2=0.000000
L 2.75171673 3.43222667 2.74941654 3.4311936 1 P 0 ;0,1=307,2=0.000000
L 2.74941654 3.4311936 2.74558337 3.4311936 1 P 0 ;0,1=307,2=0.000000
L 2.74558337 3.4311936 2.74213337 3.42964291 1 P 0 ;0,1=307,2=0.000000
L 2.74213337 3.42964291 2.73983317 3.42654272 1 P 0 ;0,1=307,2=0.000000
L 2.73983317 3.42654272 2.73906663 3.42292677 1 P 0 ;0,1=307,2=0.000000
L 2.73906663 3.42292677 2.73983317 3.41930896 1 P 0 ;0,1=307,2=0.000000
L 2.73983317 3.41930896 2.7417501 3.41672618 1 P 0 ;0,1=307,2=0.000000
L 2.7417501 3.41672618 2.74481683 3.41517657 1 P 0 ;0,1=307,2=0.000000
L 2.74481683 3.41517657 2.74749961 3.41466004 1 P 0 ;0,1=307,2=0.000000
L 2.77121644 3.42757579 2.7738999 3.4311936 1 P 0 ;0,1=307,2=0.000000
L 2.7738999 3.4311936 2.7762001 3.43325984 1 P 0 ;0,1=307,2=0.000000
L 2.7762001 3.43325984 2.77926683 3.43429291 1 P 0 ;0,1=307,2=0.000000
L 2.77926683 3.43429291 2.7819503 3.43325984 1 P 0 ;0,1=307,2=0.000000
L 2.7819503 3.43325984 2.78386654 3.4311936 1 P 0 ;0,1=307,2=0.000000
L 2.78386654 3.4311936 2.7854002 3.42809331 1 P 0 ;0,1=307,2=0.000000
L 2.7854002 3.42809331 2.78578346 3.42447648 1 P 0 ;0,1=307,2=0.000000
L 2.78578346 3.42447648 2.7854002 3.42137618 1 P 0 ;0,1=307,2=0.000000
L 2.7854002 3.42137618 2.78386654 3.41827589 1 P 0 ;0,1=307,2=0.000000
L 2.78386654 3.41827589 2.78156634 3.41569311 1 P 0 ;0,1=307,2=0.000000
L 2.78156634 3.41569311 2.77888356 3.41466004 1 P 0 ;0,1=307,2=0.000000
L 2.77888356 3.41466004 2.77581683 3.41569311 1 P 0 ;0,1=307,2=0.000000
L 2.77581683 3.41569311 2.77313337 3.41879242 1 P 0 ;0,1=307,2=0.000000
L 2.77313337 3.41879242 2.7715997 3.42344331 1 P 0 ;0,1=307,2=0.000000
L 2.7715997 3.42344331 2.77121644 3.42860984 1 P 0 ;0,1=307,2=0.000000
L 2.77121644 3.42860984 2.77198287 3.43532598 1 P 0 ;0,1=307,2=0.000000
L 2.77198287 3.43532598 2.77313337 3.4389438 1 P 0 ;0,1=307,2=0.000000
L 2.77313337 3.4389438 2.77504961 3.44255974 1 P 0 ;0,1=307,2=0.000000
L 2.77504961 3.44255974 2.77773307 3.44514341 1 P 0 ;0,1=307,2=0.000000
L 2.77773307 3.44514341 2.78041654 3.44566004 1 P 0 ;0,1=307,2=0.000000
L 2.78041654 3.44566004 2.7831 3.44462687 1 P 0 ;0,1=307,2=0.000000
L 2.7831 3.44462687 2.78501703 3.44204311 1 P 0 ;0,1=307,2=0.000000
L 1.177 3.755 1.133 3.755 1 P 0 
L 1.133 3.755 1.133 3.665 1 P 0 
L 1.133 3.665 1.177 3.665 1 P 0 
L 1.177 3.665 1.177 3.755 1 P 0 
L 1.1355 3.85083317 1.1045 3.85083317 1 P 0 ;0,1=308,2=270.000000
L 1.1045 3.85083317 1.1045 3.86041654 1 P 0 ;0,1=308,2=270.000000
L 1.1045 3.86041654 1.10605069 3.86348327 1 P 0 ;0,1=308,2=270.000000
L 1.10605069 3.86348327 1.10811693 3.8654002 1 P 0 ;0,1=308,2=270.000000
L 1.10811693 3.8654002 1.1122503 3.86616673 1 P 0 ;0,1=308,2=270.000000
L 1.1122503 3.86616673 1.11638366 3.8654002 1 P 0 ;0,1=308,2=270.000000
L 1.11638366 3.8654002 1.11896644 3.8631 1 P 0 ;0,1=308,2=270.000000
L 1.11896644 3.8631 1.12051713 3.86041654 1 P 0 ;0,1=308,2=270.000000
L 1.12051713 3.86041654 1.12051713 3.85083317 1 P 0 ;0,1=308,2=270.000000
L 1.12051713 3.86041654 1.1355 3.86616673 1 P 0 ;0,1=308,2=270.000000
L 1.1355 3.88949961 1.1045 3.88949961 1 P 0 ;0,1=308,2=270.000000
L 1.1045 3.88949961 1.1106997 3.8848999 1 P 0 ;0,1=308,2=270.000000
L 1.1355 3.8848999 1.1355 3.89409931 1 P 0 ;0,1=308,2=270.000000
L 1.10966654 3.91321644 1.10656722 3.91551663 1 P 0 ;0,1=308,2=270.000000
L 1.10656722 3.91551663 1.10501663 3.9182001 1 P 0 ;0,1=308,2=270.000000
L 1.10501663 3.9182001 1.1045 3.92126683 1 P 0 ;0,1=308,2=270.000000
L 1.1045 3.92126683 1.10553317 3.9251 1 P 0 ;0,1=308,2=270.000000
L 1.10553317 3.9251 1.10811693 3.92778346 1 P 0 ;0,1=308,2=270.000000
L 1.10811693 3.92778346 1.11121624 3.92855 1 P 0 ;0,1=308,2=270.000000
L 1.11121624 3.92855 1.11431742 3.92816673 1 P 0 ;0,1=308,2=270.000000
L 1.11431742 3.92816673 1.1169002 3.92663307 1 P 0 ;0,1=308,2=270.000000
L 1.1169002 3.92663307 1.12206673 3.91896663 1 P 0 ;0,1=308,2=270.000000
L 1.12206673 3.91896663 1.12568356 3.91551663 1 P 0 ;0,1=308,2=270.000000
L 1.12568356 3.91551663 1.13085108 3.91321644 1 P 0 ;0,1=308,2=270.000000
L 1.13085108 3.91321644 1.1355 3.9124499 1 P 0 ;0,1=308,2=270.000000
L 1.1355 3.9124499 1.1355 3.92855 1 P 0 ;0,1=308,2=270.000000
L 1.1355 3.95149961 1.13498346 3.95418307 1 P 0 ;0,1=308,2=270.000000
L 1.13498346 3.95418307 1.13343386 3.9572498 1 P 0 ;0,1=308,2=270.000000
L 1.13343386 3.9572498 1.13085108 3.95916673 1 P 0 ;0,1=308,2=270.000000
L 1.13085108 3.95916673 1.12723327 3.95993327 1 P 0 ;0,1=308,2=270.000000
L 1.12723327 3.95993327 1.12361732 3.95916673 1 P 0 ;0,1=308,2=270.000000
L 1.12361732 3.95916673 1.12051713 3.95686654 1 P 0 ;0,1=308,2=270.000000
L 1.12051713 3.95686654 1.11896644 3.95341654 1 P 0 ;0,1=308,2=270.000000
L 1.11896644 3.95341654 1.11896644 3.94958337 1 P 0 ;0,1=308,2=270.000000
L 1.11896644 3.94958337 1.11793337 3.94728317 1 P 0 ;0,1=308,2=270.000000
L 1.11793337 3.94728317 1.11535059 3.94536614 1 P 0 ;0,1=308,2=270.000000
L 1.11535059 3.94536614 1.11173376 3.9445997 1 P 0 ;0,1=308,2=270.000000
L 1.11173376 3.9445997 1.10811693 3.9457501 1 P 0 ;0,1=308,2=270.000000
L 1.10811693 3.9457501 1.10553317 3.94843287 1 P 0 ;0,1=308,2=270.000000
L 1.10553317 3.94843287 1.1045 3.95149961 1 P 0 ;0,1=308,2=270.000000
L 1.1045 3.95149961 1.10553317 3.95456634 1 P 0 ;0,1=308,2=270.000000
L 1.10553317 3.95456634 1.10811693 3.9572498 1 P 0 ;0,1=308,2=270.000000
L 1.10811693 3.9572498 1.11173376 3.9584002 1 P 0 ;0,1=308,2=270.000000
L 1.11173376 3.9584002 1.11535059 3.95763307 1 P 0 ;0,1=308,2=270.000000
L 1.11535059 3.95763307 1.11793337 3.95571673 1 P 0 ;0,1=308,2=270.000000
L 1.11793337 3.95571673 1.11896644 3.95341654 1 P 0 ;0,1=308,2=270.000000
L 1.11896644 3.95341654 1.11896644 3.94958337 1 P 0 ;0,1=308,2=270.000000
L 1.11896644 3.94958337 1.12051713 3.94613337 1 P 0 ;0,1=308,2=270.000000
L 1.12051713 3.94613337 1.12361732 3.94383317 1 P 0 ;0,1=308,2=270.000000
L 1.12361732 3.94383317 1.12723327 3.94306663 1 P 0 ;0,1=308,2=270.000000
L 1.12723327 3.94306663 1.13085108 3.94383317 1 P 0 ;0,1=308,2=270.000000
L 1.13085108 3.94383317 1.13343386 3.9457501 1 P 0 ;0,1=308,2=270.000000
L 1.13343386 3.9457501 1.13498346 3.94881683 1 P 0 ;0,1=308,2=270.000000
L 1.13498346 3.94881683 1.1355 3.95149961 1 P 0 ;0,1=308,2=270.000000
L 1.127 3.755 1.083 3.755 1 P 0 
L 1.083 3.755 1.083 3.665 1 P 0 
L 1.083 3.665 1.127 3.665 1 P 0 
L 1.127 3.665 1.127 3.755 1 P 0 
L 1.0955 3.85083317 1.0645 3.85083317 1 P 0 ;0,1=309,2=270.000000
L 1.0645 3.85083317 1.0645 3.86041654 1 P 0 ;0,1=309,2=270.000000
L 1.0645 3.86041654 1.06605069 3.86348327 1 P 0 ;0,1=309,2=270.000000
L 1.06605069 3.86348327 1.06811693 3.8654002 1 P 0 ;0,1=309,2=270.000000
L 1.06811693 3.8654002 1.0722503 3.86616673 1 P 0 ;0,1=309,2=270.000000
L 1.0722503 3.86616673 1.07638366 3.8654002 1 P 0 ;0,1=309,2=270.000000
L 1.07638366 3.8654002 1.07896644 3.8631 1 P 0 ;0,1=309,2=270.000000
L 1.07896644 3.8631 1.08051713 3.86041654 1 P 0 ;0,1=309,2=270.000000
L 1.08051713 3.86041654 1.08051713 3.85083317 1 P 0 ;0,1=309,2=270.000000
L 1.08051713 3.86041654 1.0955 3.86616673 1 P 0 ;0,1=309,2=270.000000
L 1.0955 3.88949961 1.0645 3.88949961 1 P 0 ;0,1=309,2=270.000000
L 1.0645 3.88949961 1.0706997 3.8848999 1 P 0 ;0,1=309,2=270.000000
L 1.0955 3.8848999 1.0955 3.89409931 1 P 0 ;0,1=309,2=270.000000
L 1.06966654 3.91321644 1.06656722 3.91551663 1 P 0 ;0,1=309,2=270.000000
L 1.06656722 3.91551663 1.06501663 3.9182001 1 P 0 ;0,1=309,2=270.000000
L 1.06501663 3.9182001 1.0645 3.92126683 1 P 0 ;0,1=309,2=270.000000
L 1.0645 3.92126683 1.06553317 3.9251 1 P 0 ;0,1=309,2=270.000000
L 1.06553317 3.9251 1.06811693 3.92778346 1 P 0 ;0,1=309,2=270.000000
L 1.06811693 3.92778346 1.07121624 3.92855 1 P 0 ;0,1=309,2=270.000000
L 1.07121624 3.92855 1.07431742 3.92816673 1 P 0 ;0,1=309,2=270.000000
L 1.07431742 3.92816673 1.0769002 3.92663307 1 P 0 ;0,1=309,2=270.000000
L 1.0769002 3.92663307 1.08206673 3.91896663 1 P 0 ;0,1=309,2=270.000000
L 1.08206673 3.91896663 1.08568356 3.91551663 1 P 0 ;0,1=309,2=270.000000
L 1.08568356 3.91551663 1.09085108 3.91321644 1 P 0 ;0,1=309,2=270.000000
L 1.09085108 3.91321644 1.0955 3.9124499 1 P 0 ;0,1=309,2=270.000000
L 1.0955 3.9124499 1.0955 3.92855 1 P 0 ;0,1=309,2=270.000000
L 1.09188415 3.94498287 1.09446693 3.94766634 1 P 0 ;0,1=309,2=270.000000
L 1.09446693 3.94766634 1.0955 3.95073307 1 P 0 ;0,1=309,2=270.000000
L 1.0955 3.95073307 1.09446693 3.9537998 1 P 0 ;0,1=309,2=270.000000
L 1.09446693 3.9537998 1.09136762 3.95648327 1 P 0 ;0,1=309,2=270.000000
L 1.09136762 3.95648327 1.08671673 3.9584002 1 P 0 ;0,1=309,2=270.000000
L 1.08671673 3.9584002 1.08206673 3.95916673 1 P 0 ;0,1=309,2=270.000000
L 1.08206673 3.95916673 1.07638366 3.95916673 1 P 0 ;0,1=309,2=270.000000
L 1.07638366 3.95916673 1.07173376 3.9584002 1 P 0 ;0,1=309,2=270.000000
L 1.07173376 3.9584002 1.0676003 3.95648327 1 P 0 ;0,1=309,2=270.000000
L 1.0676003 3.95648327 1.06553317 3.95418307 1 P 0 ;0,1=309,2=270.000000
L 1.06553317 3.95418307 1.0645 3.95149961 1 P 0 ;0,1=309,2=270.000000
L 1.0645 3.95149961 1.06553317 3.94843287 1 P 0 ;0,1=309,2=270.000000
L 1.06553317 3.94843287 1.0676003 3.94613337 1 P 0 ;0,1=309,2=270.000000
L 1.0676003 3.94613337 1.0706997 3.9445997 1 P 0 ;0,1=309,2=270.000000
L 1.0706997 3.9445997 1.07483406 3.94383317 1 P 0 ;0,1=309,2=270.000000
L 1.07483406 3.94383317 1.0784499 3.9445997 1 P 0 ;0,1=309,2=270.000000
L 1.0784499 3.9445997 1.08206673 3.94651663 1 P 0 ;0,1=309,2=270.000000
L 1.08206673 3.94651663 1.08413396 3.94881683 1 P 0 ;0,1=309,2=270.000000
L 1.08413396 3.94881683 1.08465049 3.95149961 1 P 0 ;0,1=309,2=270.000000
L 1.08465049 3.95149961 1.08361732 3.95456634 1 P 0 ;0,1=309,2=270.000000
L 1.08361732 3.95456634 1.08103366 3.95686654 1 P 0 ;0,1=309,2=270.000000
L 1.08103366 3.95686654 1.07638366 3.95916673 1 P 0 ;0,1=309,2=270.000000
L 0.685 2.768 0.685 2.812 1 P 0 
L 0.685 2.812 0.595 2.812 1 P 0 
L 0.595 2.812 0.595 2.768 1 P 0 
L 0.595 2.768 0.685 2.768 1 P 0 
L 0.60083317 2.8445 0.60083317 2.8755 1 P 0 ;0,1=310,2=0.000000
L 0.60083317 2.8755 0.61041654 2.8755 1 P 0 ;0,1=310,2=0.000000
L 0.61041654 2.8755 0.61348327 2.87394931 1 P 0 ;0,1=310,2=0.000000
L 0.61348327 2.87394931 0.6154002 2.87188307 1 P 0 ;0,1=310,2=0.000000
L 0.6154002 2.87188307 0.61616673 2.8677497 1 P 0 ;0,1=310,2=0.000000
L 0.61616673 2.8677497 0.6154002 2.86361634 1 P 0 ;0,1=310,2=0.000000
L 0.6154002 2.86361634 0.6131 2.86103356 1 P 0 ;0,1=310,2=0.000000
L 0.6131 2.86103356 0.61041654 2.85948287 1 P 0 ;0,1=310,2=0.000000
L 0.61041654 2.85948287 0.60083317 2.85948287 1 P 0 ;0,1=310,2=0.000000
L 0.61041654 2.85948287 0.61616673 2.8445 1 P 0 ;0,1=310,2=0.000000
L 0.63106663 2.85069961 0.63336614 2.84708278 1 P 0 ;0,1=310,2=0.000000
L 0.63336614 2.84708278 0.63643287 2.84501654 1 P 0 ;0,1=310,2=0.000000
L 0.63643287 2.84501654 0.63988356 2.8445 1 P 0 ;0,1=310,2=0.000000
L 0.63988356 2.8445 0.6429503 2.84501654 1 P 0 ;0,1=310,2=0.000000
L 0.6429503 2.84501654 0.64601703 2.84759931 1 P 0 ;0,1=310,2=0.000000
L 0.64601703 2.84759931 0.64793327 2.85069961 1 P 0 ;0,1=310,2=0.000000
L 0.64793327 2.85069961 0.64831654 2.8537999 1 P 0 ;0,1=310,2=0.000000
L 0.64831654 2.8537999 0.64755 2.85741575 1 P 0 ;0,1=310,2=0.000000
L 0.64755 2.85741575 0.64486654 2.85999951 1 P 0 ;0,1=310,2=0.000000
L 0.64486654 2.85999951 0.64218307 2.86103356 1 P 0 ;0,1=310,2=0.000000
L 0.64218307 2.86103356 0.63873307 2.86103356 1 P 0 ;0,1=310,2=0.000000
L 0.64218307 2.86103356 0.64448327 2.86258317 1 P 0 ;0,1=310,2=0.000000
L 0.64448327 2.86258317 0.6464002 2.86516594 1 P 0 ;0,1=310,2=0.000000
L 0.6464002 2.86516594 0.64716673 2.86826624 1 P 0 ;0,1=310,2=0.000000
L 0.64716673 2.86826624 0.6464002 2.87136654 1 P 0 ;0,1=310,2=0.000000
L 0.6464002 2.87136654 0.64448327 2.87394931 1 P 0 ;0,1=310,2=0.000000
L 0.64448327 2.87394931 0.64103327 2.8755 1 P 0 ;0,1=310,2=0.000000
L 0.64103327 2.8755 0.63758337 2.87498337 1 P 0 ;0,1=310,2=0.000000
L 0.63758337 2.87498337 0.63413337 2.87291624 1 P 0 ;0,1=310,2=0.000000
L 0.6751 2.8445 0.6751 2.8755 1 P 0 ;0,1=310,2=0.000000
L 0.6751 2.8755 0.66091624 2.85328327 1 P 0 ;0,1=310,2=0.000000
L 0.66091624 2.85328327 0.68008366 2.85328327 1 P 0 ;0,1=310,2=0.000000
L 0.69421644 2.85741575 0.6968999 2.86103356 1 P 0 ;0,1=310,2=0.000000
L 0.6968999 2.86103356 0.6992001 2.8630998 1 P 0 ;0,1=310,2=0.000000
L 0.6992001 2.8630998 0.70226683 2.86413287 1 P 0 ;0,1=310,2=0.000000
L 0.70226683 2.86413287 0.7049503 2.8630998 1 P 0 ;0,1=310,2=0.000000
L 0.7049503 2.8630998 0.70686654 2.86103356 1 P 0 ;0,1=310,2=0.000000
L 0.70686654 2.86103356 0.7084002 2.85793327 1 P 0 ;0,1=310,2=0.000000
L 0.7084002 2.85793327 0.70878346 2.85431644 1 P 0 ;0,1=310,2=0.000000
L 0.70878346 2.85431644 0.7084002 2.85121614 1 P 0 ;0,1=310,2=0.000000
L 0.7084002 2.85121614 0.70686654 2.84811585 1 P 0 ;0,1=310,2=0.000000
L 0.70686654 2.84811585 0.70456634 2.84553307 1 P 0 ;0,1=310,2=0.000000
L 0.70456634 2.84553307 0.70188356 2.8445 1 P 0 ;0,1=310,2=0.000000
L 0.70188356 2.8445 0.69881683 2.84553307 1 P 0 ;0,1=310,2=0.000000
L 0.69881683 2.84553307 0.69613337 2.84863238 1 P 0 ;0,1=310,2=0.000000
L 0.69613337 2.84863238 0.6945997 2.85328327 1 P 0 ;0,1=310,2=0.000000
L 0.6945997 2.85328327 0.69421644 2.8584498 1 P 0 ;0,1=310,2=0.000000
L 0.69421644 2.8584498 0.69498287 2.86516594 1 P 0 ;0,1=310,2=0.000000
L 0.69498287 2.86516594 0.69613337 2.86878376 1 P 0 ;0,1=310,2=0.000000
L 0.69613337 2.86878376 0.69804961 2.8723997 1 P 0 ;0,1=310,2=0.000000
L 0.69804961 2.8723997 0.70073307 2.87498337 1 P 0 ;0,1=310,2=0.000000
L 0.70073307 2.87498337 0.70341654 2.8755 1 P 0 ;0,1=310,2=0.000000
L 0.70341654 2.8755 0.7061 2.87446683 1 P 0 ;0,1=310,2=0.000000
L 0.7061 2.87446683 0.70801703 2.87188307 1 P 0 ;0,1=310,2=0.000000
L 0.70848002 2.592 0.70848002 2.636 1 P 0 
L 0.70848002 2.636 0.61848002 2.636 1 P 0 
L 0.61848002 2.636 0.61848002 2.592 1 P 0 
L 0.61848002 2.592 0.70848002 2.592 1 P 0 
L 0.66166654 2.5425 0.66166654 2.5675 1 P 0 ;0,1=311,2=0.000000
L 0.66166654 2.5675 0.66833327 2.5675 1 P 0 ;0,1=311,2=0.000000
L 0.66833327 2.5675 0.67046663 2.56624941 1 P 0 ;0,1=311,2=0.000000
L 0.67046663 2.56624941 0.6718001 2.56458317 1 P 0 ;0,1=311,2=0.000000
L 0.6718001 2.56458317 0.67233337 2.5612498 1 P 0 ;0,1=311,2=0.000000
L 0.67233337 2.5612498 0.6718001 2.55791634 1 P 0 ;0,1=311,2=0.000000
L 0.6718001 2.55791634 0.6702 2.55583346 1 P 0 ;0,1=311,2=0.000000
L 0.6702 2.55583346 0.66833327 2.55458297 1 P 0 ;0,1=311,2=0.000000
L 0.66833327 2.55458297 0.66166654 2.55458297 1 P 0 ;0,1=311,2=0.000000
L 0.66833327 2.55458297 0.67233337 2.5425 1 P 0 ;0,1=311,2=0.000000
L 0.68313327 2.54749961 0.68473297 2.54458287 1 P 0 ;0,1=311,2=0.000000
L 0.68473297 2.54458287 0.68686634 2.54291654 1 P 0 ;0,1=311,2=0.000000
L 0.68686634 2.54291654 0.68926683 2.5425 1 P 0 ;0,1=311,2=0.000000
L 0.68926683 2.5425 0.6914002 2.54291654 1 P 0 ;0,1=311,2=0.000000
L 0.6914002 2.54291654 0.69353356 2.54499941 1 P 0 ;0,1=311,2=0.000000
L 0.69353356 2.54499941 0.69486663 2.54749961 1 P 0 ;0,1=311,2=0.000000
L 0.69486663 2.54749961 0.69513317 2.5499999 1 P 0 ;0,1=311,2=0.000000
L 0.69513317 2.5499999 0.6946 2.55291594 1 P 0 ;0,1=311,2=0.000000
L 0.6946 2.55291594 0.69273327 2.55499961 1 P 0 ;0,1=311,2=0.000000
L 0.69273327 2.55499961 0.69086644 2.55583346 1 P 0 ;0,1=311,2=0.000000
L 0.69086644 2.55583346 0.68846654 2.55583346 1 P 0 ;0,1=311,2=0.000000
L 0.69086644 2.55583346 0.69246663 2.55708327 1 P 0 ;0,1=311,2=0.000000
L 0.69246663 2.55708327 0.6938001 2.55916614 1 P 0 ;0,1=311,2=0.000000
L 0.6938001 2.55916614 0.69433337 2.56166634 1 P 0 ;0,1=311,2=0.000000
L 0.69433337 2.56166634 0.6938001 2.56416654 1 P 0 ;0,1=311,2=0.000000
L 0.6938001 2.56416654 0.69246663 2.56624941 1 P 0 ;0,1=311,2=0.000000
L 0.69246663 2.56624941 0.69006663 2.5675 1 P 0 ;0,1=311,2=0.000000
L 0.69006663 2.5675 0.68766663 2.56708337 1 P 0 ;0,1=311,2=0.000000
L 0.68766663 2.56708337 0.68526663 2.56541634 1 P 0 ;0,1=311,2=0.000000
L 0.7142 2.5425 0.7142 2.5675 1 P 0 ;0,1=311,2=0.000000
L 0.7142 2.5675 0.70433297 2.54958327 1 P 0 ;0,1=311,2=0.000000
L 0.70433297 2.54958327 0.71766693 2.54958327 1 P 0 ;0,1=311,2=0.000000
L 0.73246654 2.5425 0.7329997 2.54791624 1 P 0 ;0,1=311,2=0.000000
L 0.7329997 2.54791624 0.7338 2.55249931 1 P 0 ;0,1=311,2=0.000000
L 0.7338 2.55249931 0.73486644 2.55666663 1 P 0 ;0,1=311,2=0.000000
L 0.73486644 2.55666663 0.7362 2.5612498 1 P 0 ;0,1=311,2=0.000000
L 0.7362 2.5612498 0.73833337 2.5675 1 P 0 ;0,1=311,2=0.000000
L 0.73833337 2.5675 0.72766654 2.5675 1 P 0 ;0,1=311,2=0.000000
L 0.79148002 2.591 0.74748002 2.591 1 P 0 
L 0.74748002 2.591 0.74748002 2.501 1 P 0 
L 0.74748002 2.501 0.79148002 2.501 1 P 0 
L 0.79148002 2.501 0.79148002 2.591 1 P 0 
L 0.9705 2.44083317 0.9395 2.44083317 1 P 0 ;0,1=312,2=270.000000
L 0.9395 2.44083317 0.9395 2.45041654 1 P 0 ;0,1=312,2=270.000000
L 0.9395 2.45041654 0.94105069 2.45348327 1 P 0 ;0,1=312,2=270.000000
L 0.94105069 2.45348327 0.94311693 2.4554002 1 P 0 ;0,1=312,2=270.000000
L 0.94311693 2.4554002 0.9472503 2.45616673 1 P 0 ;0,1=312,2=270.000000
L 0.9472503 2.45616673 0.95138366 2.4554002 1 P 0 ;0,1=312,2=270.000000
L 0.95138366 2.4554002 0.95396644 2.4531 1 P 0 ;0,1=312,2=270.000000
L 0.95396644 2.4531 0.95551713 2.45041654 1 P 0 ;0,1=312,2=270.000000
L 0.95551713 2.45041654 0.95551713 2.44083317 1 P 0 ;0,1=312,2=270.000000
L 0.95551713 2.45041654 0.9705 2.45616673 1 P 0 ;0,1=312,2=270.000000
L 0.96430039 2.47106663 0.96791722 2.47336614 1 P 0 ;0,1=312,2=270.000000
L 0.96791722 2.47336614 0.96998346 2.47643287 1 P 0 ;0,1=312,2=270.000000
L 0.96998346 2.47643287 0.9705 2.47988356 1 P 0 ;0,1=312,2=270.000000
L 0.9705 2.47988356 0.96998346 2.4829503 1 P 0 ;0,1=312,2=270.000000
L 0.96998346 2.4829503 0.96740069 2.48601703 1 P 0 ;0,1=312,2=270.000000
L 0.96740069 2.48601703 0.96430039 2.48793327 1 P 0 ;0,1=312,2=270.000000
L 0.96430039 2.48793327 0.9612001 2.48831654 1 P 0 ;0,1=312,2=270.000000
L 0.9612001 2.48831654 0.95758425 2.48755 1 P 0 ;0,1=312,2=270.000000
L 0.95758425 2.48755 0.95500049 2.48486654 1 P 0 ;0,1=312,2=270.000000
L 0.95500049 2.48486654 0.95396644 2.48218307 1 P 0 ;0,1=312,2=270.000000
L 0.95396644 2.48218307 0.95396644 2.47873307 1 P 0 ;0,1=312,2=270.000000
L 0.95396644 2.48218307 0.95241683 2.48448327 1 P 0 ;0,1=312,2=270.000000
L 0.95241683 2.48448327 0.94983406 2.4864002 1 P 0 ;0,1=312,2=270.000000
L 0.94983406 2.4864002 0.94673376 2.48716673 1 P 0 ;0,1=312,2=270.000000
L 0.94673376 2.48716673 0.94363346 2.4864002 1 P 0 ;0,1=312,2=270.000000
L 0.94363346 2.4864002 0.94105069 2.48448327 1 P 0 ;0,1=312,2=270.000000
L 0.94105069 2.48448327 0.9395 2.48103327 1 P 0 ;0,1=312,2=270.000000
L 0.9395 2.48103327 0.94001663 2.47758337 1 P 0 ;0,1=312,2=270.000000
L 0.94001663 2.47758337 0.94208376 2.47413337 1 P 0 ;0,1=312,2=270.000000
L 0.96585108 2.50206663 0.96843386 2.50436614 1 P 0 ;0,1=312,2=270.000000
L 0.96843386 2.50436614 0.96998346 2.50704961 1 P 0 ;0,1=312,2=270.000000
L 0.96998346 2.50704961 0.9705 2.51049961 1 P 0 ;0,1=312,2=270.000000
L 0.9705 2.51049961 0.96946693 2.5139503 1 P 0 ;0,1=312,2=270.000000
L 0.96946693 2.5139503 0.96740069 2.51663307 1 P 0 ;0,1=312,2=270.000000
L 0.96740069 2.51663307 0.96378386 2.51855 1 P 0 ;0,1=312,2=270.000000
L 0.96378386 2.51855 0.95965049 2.51893327 1 P 0 ;0,1=312,2=270.000000
L 0.95965049 2.51893327 0.95551713 2.51816673 1 P 0 ;0,1=312,2=270.000000
L 0.95551713 2.51816673 0.95293337 2.5162498 1 P 0 ;0,1=312,2=270.000000
L 0.95293337 2.5162498 0.95086713 2.51356634 1 P 0 ;0,1=312,2=270.000000
L 0.95086713 2.51356634 0.95035059 2.51088356 1 P 0 ;0,1=312,2=270.000000
L 0.95035059 2.51088356 0.95086713 2.5082001 1 P 0 ;0,1=312,2=270.000000
L 0.95086713 2.5082001 0.95293337 2.5047501 1 P 0 ;0,1=312,2=270.000000
L 0.95293337 2.5047501 0.9395 2.5058999 1 P 0 ;0,1=312,2=270.000000
L 0.9395 2.5058999 0.9395 2.5162498 1 P 0 ;0,1=312,2=270.000000
L 0.9395 2.54149961 0.94053317 2.53843287 1 P 0 ;0,1=312,2=270.000000
L 0.94053317 2.53843287 0.94311693 2.53613337 1 P 0 ;0,1=312,2=270.000000
L 0.94311693 2.53613337 0.94621624 2.5345997 1 P 0 ;0,1=312,2=270.000000
L 0.94621624 2.5345997 0.95035059 2.5334499 1 P 0 ;0,1=312,2=270.000000
L 0.95035059 2.5334499 0.95500049 2.53306663 1 P 0 ;0,1=312,2=270.000000
L 0.95500049 2.53306663 0.95965049 2.5334499 1 P 0 ;0,1=312,2=270.000000
L 0.95965049 2.5334499 0.96378386 2.5345997 1 P 0 ;0,1=312,2=270.000000
L 0.96378386 2.5345997 0.96688415 2.53613337 1 P 0 ;0,1=312,2=270.000000
L 0.96688415 2.53613337 0.96946693 2.53843287 1 P 0 ;0,1=312,2=270.000000
L 0.96946693 2.53843287 0.9705 2.54149961 1 P 0 ;0,1=312,2=270.000000
L 0.9705 2.54149961 0.96946693 2.54456634 1 P 0 ;0,1=312,2=270.000000
L 0.96946693 2.54456634 0.96688415 2.54686654 1 P 0 ;0,1=312,2=270.000000
L 0.96688415 2.54686654 0.96378386 2.5484002 1 P 0 ;0,1=312,2=270.000000
L 0.96378386 2.5484002 0.95965049 2.54955 1 P 0 ;0,1=312,2=270.000000
L 0.95965049 2.54955 0.95500049 2.54993327 1 P 0 ;0,1=312,2=270.000000
L 0.95500049 2.54993327 0.95035059 2.54955 1 P 0 ;0,1=312,2=270.000000
L 0.95035059 2.54955 0.94621624 2.5484002 1 P 0 ;0,1=312,2=270.000000
L 0.94621624 2.5484002 0.94311693 2.54686654 1 P 0 ;0,1=312,2=270.000000
L 0.94311693 2.54686654 0.94053317 2.54456634 1 P 0 ;0,1=312,2=270.000000
L 0.94053317 2.54456634 0.9395 2.54149961 1 P 0 ;0,1=312,2=270.000000
L 0.857 2.5 0.857 2.59 1 P 0 
L 0.857 2.59 0.813 2.59 1 P 0 
L 0.813 2.59 0.813 2.5 1 P 0 
L 0.813 2.5 0.857 2.5 1 P 0 
L 1.0105 2.44083317 0.9795 2.44083317 1 P 0 ;0,1=313,2=270.000000
L 0.9795 2.44083317 0.9795 2.45041654 1 P 0 ;0,1=313,2=270.000000
L 0.9795 2.45041654 0.98105069 2.45348327 1 P 0 ;0,1=313,2=270.000000
L 0.98105069 2.45348327 0.98311693 2.4554002 1 P 0 ;0,1=313,2=270.000000
L 0.98311693 2.4554002 0.9872503 2.45616673 1 P 0 ;0,1=313,2=270.000000
L 0.9872503 2.45616673 0.99138366 2.4554002 1 P 0 ;0,1=313,2=270.000000
L 0.99138366 2.4554002 0.99396644 2.4531 1 P 0 ;0,1=313,2=270.000000
L 0.99396644 2.4531 0.99551713 2.45041654 1 P 0 ;0,1=313,2=270.000000
L 0.99551713 2.45041654 0.99551713 2.44083317 1 P 0 ;0,1=313,2=270.000000
L 0.99551713 2.45041654 1.0105 2.45616673 1 P 0 ;0,1=313,2=270.000000
L 1.00430039 2.47106663 1.00791722 2.47336614 1 P 0 ;0,1=313,2=270.000000
L 1.00791722 2.47336614 1.00998346 2.47643287 1 P 0 ;0,1=313,2=270.000000
L 1.00998346 2.47643287 1.0105 2.47988356 1 P 0 ;0,1=313,2=270.000000
L 1.0105 2.47988356 1.00998346 2.4829503 1 P 0 ;0,1=313,2=270.000000
L 1.00998346 2.4829503 1.00740069 2.48601703 1 P 0 ;0,1=313,2=270.000000
L 1.00740069 2.48601703 1.00430039 2.48793327 1 P 0 ;0,1=313,2=270.000000
L 1.00430039 2.48793327 1.0012001 2.48831654 1 P 0 ;0,1=313,2=270.000000
L 1.0012001 2.48831654 0.99758425 2.48755 1 P 0 ;0,1=313,2=270.000000
L 0.99758425 2.48755 0.99500049 2.48486654 1 P 0 ;0,1=313,2=270.000000
L 0.99500049 2.48486654 0.99396644 2.48218307 1 P 0 ;0,1=313,2=270.000000
L 0.99396644 2.48218307 0.99396644 2.47873307 1 P 0 ;0,1=313,2=270.000000
L 0.99396644 2.48218307 0.99241683 2.48448327 1 P 0 ;0,1=313,2=270.000000
L 0.99241683 2.48448327 0.98983406 2.4864002 1 P 0 ;0,1=313,2=270.000000
L 0.98983406 2.4864002 0.98673376 2.48716673 1 P 0 ;0,1=313,2=270.000000
L 0.98673376 2.48716673 0.98363346 2.4864002 1 P 0 ;0,1=313,2=270.000000
L 0.98363346 2.4864002 0.98105069 2.48448327 1 P 0 ;0,1=313,2=270.000000
L 0.98105069 2.48448327 0.9795 2.48103327 1 P 0 ;0,1=313,2=270.000000
L 0.9795 2.48103327 0.98001663 2.47758337 1 P 0 ;0,1=313,2=270.000000
L 0.98001663 2.47758337 0.98208376 2.47413337 1 P 0 ;0,1=313,2=270.000000
L 1.00585108 2.50206663 1.00843386 2.50436614 1 P 0 ;0,1=313,2=270.000000
L 1.00843386 2.50436614 1.00998346 2.50704961 1 P 0 ;0,1=313,2=270.000000
L 1.00998346 2.50704961 1.0105 2.51049961 1 P 0 ;0,1=313,2=270.000000
L 1.0105 2.51049961 1.00946693 2.5139503 1 P 0 ;0,1=313,2=270.000000
L 1.00946693 2.5139503 1.00740069 2.51663307 1 P 0 ;0,1=313,2=270.000000
L 1.00740069 2.51663307 1.00378386 2.51855 1 P 0 ;0,1=313,2=270.000000
L 1.00378386 2.51855 0.99965049 2.51893327 1 P 0 ;0,1=313,2=270.000000
L 0.99965049 2.51893327 0.99551713 2.51816673 1 P 0 ;0,1=313,2=270.000000
L 0.99551713 2.51816673 0.99293337 2.5162498 1 P 0 ;0,1=313,2=270.000000
L 0.99293337 2.5162498 0.99086713 2.51356634 1 P 0 ;0,1=313,2=270.000000
L 0.99086713 2.51356634 0.99035059 2.51088356 1 P 0 ;0,1=313,2=270.000000
L 0.99035059 2.51088356 0.99086713 2.5082001 1 P 0 ;0,1=313,2=270.000000
L 0.99086713 2.5082001 0.99293337 2.5047501 1 P 0 ;0,1=313,2=270.000000
L 0.99293337 2.5047501 0.9795 2.5058999 1 P 0 ;0,1=313,2=270.000000
L 0.9795 2.5058999 0.9795 2.5162498 1 P 0 ;0,1=313,2=270.000000
L 1.0105 2.54149961 0.9795 2.54149961 1 P 0 ;0,1=313,2=270.000000
L 0.9795 2.54149961 0.9856997 2.5368999 1 P 0 ;0,1=313,2=270.000000
L 1.0105 2.5368999 1.0105 2.54609931 1 P 0 ;0,1=313,2=270.000000
L 4.95 2.048 4.95 2.092 1 P 0 
L 4.95 2.092 4.86 2.092 1 P 0 
L 4.86 2.092 4.86 2.048 1 P 0 
L 4.86 2.048 4.95 2.048 1 P 0 
L 4.97583317 2.0495 4.97583317 2.0805 1 P 0 ;0,1=314,2=0.000000
L 4.97583317 2.0805 4.98541654 2.0805 1 P 0 ;0,1=314,2=0.000000
L 4.98541654 2.0805 4.98848327 2.07894931 1 P 0 ;0,1=314,2=0.000000
L 4.98848327 2.07894931 4.9904002 2.07688307 1 P 0 ;0,1=314,2=0.000000
L 4.9904002 2.07688307 4.99116673 2.0727497 1 P 0 ;0,1=314,2=0.000000
L 4.99116673 2.0727497 4.9904002 2.06861634 1 P 0 ;0,1=314,2=0.000000
L 4.9904002 2.06861634 4.9881 2.06603356 1 P 0 ;0,1=314,2=0.000000
L 4.9881 2.06603356 4.98541654 2.06448287 1 P 0 ;0,1=314,2=0.000000
L 4.98541654 2.06448287 4.97583317 2.06448287 1 P 0 ;0,1=314,2=0.000000
L 4.98541654 2.06448287 4.99116673 2.0495 1 P 0 ;0,1=314,2=0.000000
L 5.00606663 2.05569961 5.00836614 2.05208278 1 P 0 ;0,1=314,2=0.000000
L 5.00836614 2.05208278 5.01143287 2.05001654 1 P 0 ;0,1=314,2=0.000000
L 5.01143287 2.05001654 5.01488356 2.0495 1 P 0 ;0,1=314,2=0.000000
L 5.01488356 2.0495 5.0179503 2.05001654 1 P 0 ;0,1=314,2=0.000000
L 5.0179503 2.05001654 5.02101703 2.05259931 1 P 0 ;0,1=314,2=0.000000
L 5.02101703 2.05259931 5.02293327 2.05569961 1 P 0 ;0,1=314,2=0.000000
L 5.02293327 2.05569961 5.02331654 2.0587999 1 P 0 ;0,1=314,2=0.000000
L 5.02331654 2.0587999 5.02255 2.06241575 1 P 0 ;0,1=314,2=0.000000
L 5.02255 2.06241575 5.01986654 2.06499951 1 P 0 ;0,1=314,2=0.000000
L 5.01986654 2.06499951 5.01718307 2.06603356 1 P 0 ;0,1=314,2=0.000000
L 5.01718307 2.06603356 5.01373307 2.06603356 1 P 0 ;0,1=314,2=0.000000
L 5.01718307 2.06603356 5.01948327 2.06758317 1 P 0 ;0,1=314,2=0.000000
L 5.01948327 2.06758317 5.0214002 2.07016594 1 P 0 ;0,1=314,2=0.000000
L 5.0214002 2.07016594 5.02216673 2.07326624 1 P 0 ;0,1=314,2=0.000000
L 5.02216673 2.07326624 5.0214002 2.07636654 1 P 0 ;0,1=314,2=0.000000
L 5.0214002 2.07636654 5.01948327 2.07894931 1 P 0 ;0,1=314,2=0.000000
L 5.01948327 2.07894931 5.01603327 2.0805 1 P 0 ;0,1=314,2=0.000000
L 5.01603327 2.0805 5.01258337 2.07998337 1 P 0 ;0,1=314,2=0.000000
L 5.01258337 2.07998337 5.00913337 2.07791624 1 P 0 ;0,1=314,2=0.000000
L 5.03706663 2.05414892 5.03936614 2.05156614 1 P 0 ;0,1=314,2=0.000000
L 5.03936614 2.05156614 5.04204961 2.05001654 1 P 0 ;0,1=314,2=0.000000
L 5.04204961 2.05001654 5.04549961 2.0495 1 P 0 ;0,1=314,2=0.000000
L 5.04549961 2.0495 5.0489503 2.05053307 1 P 0 ;0,1=314,2=0.000000
L 5.0489503 2.05053307 5.05163307 2.05259931 1 P 0 ;0,1=314,2=0.000000
L 5.05163307 2.05259931 5.05355 2.05621614 1 P 0 ;0,1=314,2=0.000000
L 5.05355 2.05621614 5.05393327 2.06034951 1 P 0 ;0,1=314,2=0.000000
L 5.05393327 2.06034951 5.05316673 2.06448287 1 P 0 ;0,1=314,2=0.000000
L 5.05316673 2.06448287 5.0512498 2.06706663 1 P 0 ;0,1=314,2=0.000000
L 5.0512498 2.06706663 5.04856634 2.06913287 1 P 0 ;0,1=314,2=0.000000
L 5.04856634 2.06913287 5.04588356 2.06964941 1 P 0 ;0,1=314,2=0.000000
L 5.04588356 2.06964941 5.0432001 2.06913287 1 P 0 ;0,1=314,2=0.000000
L 5.0432001 2.06913287 5.0397501 2.06706663 1 P 0 ;0,1=314,2=0.000000
L 5.0397501 2.06706663 5.0408999 2.0805 1 P 0 ;0,1=314,2=0.000000
L 5.0408999 2.0805 5.0512498 2.0805 1 P 0 ;0,1=314,2=0.000000
L 5.06921644 2.06241575 5.0718999 2.06603356 1 P 0 ;0,1=314,2=0.000000
L 5.0718999 2.06603356 5.0742001 2.0680998 1 P 0 ;0,1=314,2=0.000000
L 5.0742001 2.0680998 5.07726683 2.06913287 1 P 0 ;0,1=314,2=0.000000
L 5.07726683 2.06913287 5.0799503 2.0680998 1 P 0 ;0,1=314,2=0.000000
L 5.0799503 2.0680998 5.08186654 2.06603356 1 P 0 ;0,1=314,2=0.000000
L 5.08186654 2.06603356 5.0834002 2.06293327 1 P 0 ;0,1=314,2=0.000000
L 5.0834002 2.06293327 5.08378346 2.05931644 1 P 0 ;0,1=314,2=0.000000
L 5.08378346 2.05931644 5.0834002 2.05621614 1 P 0 ;0,1=314,2=0.000000
L 5.0834002 2.05621614 5.08186654 2.05311585 1 P 0 ;0,1=314,2=0.000000
L 5.08186654 2.05311585 5.07956634 2.05053307 1 P 0 ;0,1=314,2=0.000000
L 5.07956634 2.05053307 5.07688356 2.0495 1 P 0 ;0,1=314,2=0.000000
L 5.07688356 2.0495 5.07381683 2.05053307 1 P 0 ;0,1=314,2=0.000000
L 5.07381683 2.05053307 5.07113337 2.05363238 1 P 0 ;0,1=314,2=0.000000
L 5.07113337 2.05363238 5.0695997 2.05828327 1 P 0 ;0,1=314,2=0.000000
L 5.0695997 2.05828327 5.06921644 2.0634498 1 P 0 ;0,1=314,2=0.000000
L 5.06921644 2.0634498 5.06998287 2.07016594 1 P 0 ;0,1=314,2=0.000000
L 5.06998287 2.07016594 5.07113337 2.07378376 1 P 0 ;0,1=314,2=0.000000
L 5.07113337 2.07378376 5.07304961 2.0773997 1 P 0 ;0,1=314,2=0.000000
L 5.07304961 2.0773997 5.07573307 2.07998337 1 P 0 ;0,1=314,2=0.000000
L 5.07573307 2.07998337 5.07841654 2.0805 1 P 0 ;0,1=314,2=0.000000
L 5.07841654 2.0805 5.0811 2.07946683 1 P 0 ;0,1=314,2=0.000000
L 5.0811 2.07946683 5.08301703 2.07688307 1 P 0 ;0,1=314,2=0.000000
L 1.103 3.005 1.103 2.915 1 P 0 
L 1.103 2.915 1.147 2.915 1 P 0 
L 1.147 2.915 1.147 3.005 1 P 0 
L 1.147 3.005 1.103 3.005 1 P 0 
L 1.2355 2.92083317 1.2045 2.92083317 1 P 0 ;0,1=315,2=270.000000
L 1.2045 2.92083317 1.2045 2.93041654 1 P 0 ;0,1=315,2=270.000000
L 1.2045 2.93041654 1.20605069 2.93348327 1 P 0 ;0,1=315,2=270.000000
L 1.20605069 2.93348327 1.20811693 2.9354002 1 P 0 ;0,1=315,2=270.000000
L 1.20811693 2.9354002 1.2122503 2.93616673 1 P 0 ;0,1=315,2=270.000000
L 1.2122503 2.93616673 1.21638366 2.9354002 1 P 0 ;0,1=315,2=270.000000
L 1.21638366 2.9354002 1.21896644 2.9331 1 P 0 ;0,1=315,2=270.000000
L 1.21896644 2.9331 1.22051713 2.93041654 1 P 0 ;0,1=315,2=270.000000
L 1.22051713 2.93041654 1.22051713 2.92083317 1 P 0 ;0,1=315,2=270.000000
L 1.22051713 2.93041654 1.2355 2.93616673 1 P 0 ;0,1=315,2=270.000000
L 1.22930039 2.95106663 1.23291722 2.95336614 1 P 0 ;0,1=315,2=270.000000
L 1.23291722 2.95336614 1.23498346 2.95643287 1 P 0 ;0,1=315,2=270.000000
L 1.23498346 2.95643287 1.2355 2.95988356 1 P 0 ;0,1=315,2=270.000000
L 1.2355 2.95988356 1.23498346 2.9629503 1 P 0 ;0,1=315,2=270.000000
L 1.23498346 2.9629503 1.23240069 2.96601703 1 P 0 ;0,1=315,2=270.000000
L 1.23240069 2.96601703 1.22930039 2.96793327 1 P 0 ;0,1=315,2=270.000000
L 1.22930039 2.96793327 1.2262001 2.96831654 1 P 0 ;0,1=315,2=270.000000
L 1.2262001 2.96831654 1.22258425 2.96755 1 P 0 ;0,1=315,2=270.000000
L 1.22258425 2.96755 1.22000049 2.96486654 1 P 0 ;0,1=315,2=270.000000
L 1.22000049 2.96486654 1.21896644 2.96218307 1 P 0 ;0,1=315,2=270.000000
L 1.21896644 2.96218307 1.21896644 2.95873307 1 P 0 ;0,1=315,2=270.000000
L 1.21896644 2.96218307 1.21741683 2.96448327 1 P 0 ;0,1=315,2=270.000000
L 1.21741683 2.96448327 1.21483406 2.9664002 1 P 0 ;0,1=315,2=270.000000
L 1.21483406 2.9664002 1.21173376 2.96716673 1 P 0 ;0,1=315,2=270.000000
L 1.21173376 2.96716673 1.20863346 2.9664002 1 P 0 ;0,1=315,2=270.000000
L 1.20863346 2.9664002 1.20605069 2.96448327 1 P 0 ;0,1=315,2=270.000000
L 1.20605069 2.96448327 1.2045 2.96103327 1 P 0 ;0,1=315,2=270.000000
L 1.2045 2.96103327 1.20501663 2.95758337 1 P 0 ;0,1=315,2=270.000000
L 1.20501663 2.95758337 1.20708376 2.95413337 1 P 0 ;0,1=315,2=270.000000
L 1.23085108 2.98206663 1.23343386 2.98436614 1 P 0 ;0,1=315,2=270.000000
L 1.23343386 2.98436614 1.23498346 2.98704961 1 P 0 ;0,1=315,2=270.000000
L 1.23498346 2.98704961 1.2355 2.99049961 1 P 0 ;0,1=315,2=270.000000
L 1.2355 2.99049961 1.23446693 2.9939503 1 P 0 ;0,1=315,2=270.000000
L 1.23446693 2.9939503 1.23240069 2.99663307 1 P 0 ;0,1=315,2=270.000000
L 1.23240069 2.99663307 1.22878386 2.99855 1 P 0 ;0,1=315,2=270.000000
L 1.22878386 2.99855 1.22465049 2.99893327 1 P 0 ;0,1=315,2=270.000000
L 1.22465049 2.99893327 1.22051713 2.99816673 1 P 0 ;0,1=315,2=270.000000
L 1.22051713 2.99816673 1.21793337 2.9962498 1 P 0 ;0,1=315,2=270.000000
L 1.21793337 2.9962498 1.21586713 2.99356634 1 P 0 ;0,1=315,2=270.000000
L 1.21586713 2.99356634 1.21535059 2.99088356 1 P 0 ;0,1=315,2=270.000000
L 1.21535059 2.99088356 1.21586713 2.9882001 1 P 0 ;0,1=315,2=270.000000
L 1.21586713 2.9882001 1.21793337 2.9847501 1 P 0 ;0,1=315,2=270.000000
L 1.21793337 2.9847501 1.2045 2.9858999 1 P 0 ;0,1=315,2=270.000000
L 1.2045 2.9858999 1.2045 2.9962498 1 P 0 ;0,1=315,2=270.000000
L 1.20966654 3.01421644 1.20656722 3.01651663 1 P 0 ;0,1=315,2=270.000000
L 1.20656722 3.01651663 1.20501663 3.0192001 1 P 0 ;0,1=315,2=270.000000
L 1.20501663 3.0192001 1.2045 3.02226683 1 P 0 ;0,1=315,2=270.000000
L 1.2045 3.02226683 1.20553317 3.0261 1 P 0 ;0,1=315,2=270.000000
L 1.20553317 3.0261 1.20811693 3.02878346 1 P 0 ;0,1=315,2=270.000000
L 1.20811693 3.02878346 1.21121624 3.02955 1 P 0 ;0,1=315,2=270.000000
L 1.21121624 3.02955 1.21431742 3.02916673 1 P 0 ;0,1=315,2=270.000000
L 1.21431742 3.02916673 1.2169002 3.02763307 1 P 0 ;0,1=315,2=270.000000
L 1.2169002 3.02763307 1.22206673 3.01996663 1 P 0 ;0,1=315,2=270.000000
L 1.22206673 3.01996663 1.22568356 3.01651663 1 P 0 ;0,1=315,2=270.000000
L 1.22568356 3.01651663 1.23085108 3.01421644 1 P 0 ;0,1=315,2=270.000000
L 1.23085108 3.01421644 1.2355 3.0134499 1 P 0 ;0,1=315,2=270.000000
L 1.2355 3.0134499 1.2355 3.02955 1 P 0 ;0,1=315,2=270.000000
L 1.053 3.005 1.053 2.915 1 P 0 
L 1.053 2.915 1.097 2.915 1 P 0 
L 1.097 2.915 1.097 3.005 1 P 0 
L 1.097 3.005 1.053 3.005 1 P 0 
L 1.1005 2.78083317 1.0695 2.78083317 1 P 0 ;0,1=316,2=270.000000
L 1.0695 2.78083317 1.0695 2.79041654 1 P 0 ;0,1=316,2=270.000000
L 1.0695 2.79041654 1.07105069 2.79348327 1 P 0 ;0,1=316,2=270.000000
L 1.07105069 2.79348327 1.07311693 2.7954002 1 P 0 ;0,1=316,2=270.000000
L 1.07311693 2.7954002 1.0772503 2.79616673 1 P 0 ;0,1=316,2=270.000000
L 1.0772503 2.79616673 1.08138366 2.7954002 1 P 0 ;0,1=316,2=270.000000
L 1.08138366 2.7954002 1.08396644 2.7931 1 P 0 ;0,1=316,2=270.000000
L 1.08396644 2.7931 1.08551713 2.79041654 1 P 0 ;0,1=316,2=270.000000
L 1.08551713 2.79041654 1.08551713 2.78083317 1 P 0 ;0,1=316,2=270.000000
L 1.08551713 2.79041654 1.1005 2.79616673 1 P 0 ;0,1=316,2=270.000000
L 1.09430039 2.81106663 1.09791722 2.81336614 1 P 0 ;0,1=316,2=270.000000
L 1.09791722 2.81336614 1.09998346 2.81643287 1 P 0 ;0,1=316,2=270.000000
L 1.09998346 2.81643287 1.1005 2.81988356 1 P 0 ;0,1=316,2=270.000000
L 1.1005 2.81988356 1.09998346 2.8229503 1 P 0 ;0,1=316,2=270.000000
L 1.09998346 2.8229503 1.09740069 2.82601703 1 P 0 ;0,1=316,2=270.000000
L 1.09740069 2.82601703 1.09430039 2.82793327 1 P 0 ;0,1=316,2=270.000000
L 1.09430039 2.82793327 1.0912001 2.82831654 1 P 0 ;0,1=316,2=270.000000
L 1.0912001 2.82831654 1.08758425 2.82755 1 P 0 ;0,1=316,2=270.000000
L 1.08758425 2.82755 1.08500049 2.82486654 1 P 0 ;0,1=316,2=270.000000
L 1.08500049 2.82486654 1.08396644 2.82218307 1 P 0 ;0,1=316,2=270.000000
L 1.08396644 2.82218307 1.08396644 2.81873307 1 P 0 ;0,1=316,2=270.000000
L 1.08396644 2.82218307 1.08241683 2.82448327 1 P 0 ;0,1=316,2=270.000000
L 1.08241683 2.82448327 1.07983406 2.8264002 1 P 0 ;0,1=316,2=270.000000
L 1.07983406 2.8264002 1.07673376 2.82716673 1 P 0 ;0,1=316,2=270.000000
L 1.07673376 2.82716673 1.07363346 2.8264002 1 P 0 ;0,1=316,2=270.000000
L 1.07363346 2.8264002 1.07105069 2.82448327 1 P 0 ;0,1=316,2=270.000000
L 1.07105069 2.82448327 1.0695 2.82103327 1 P 0 ;0,1=316,2=270.000000
L 1.0695 2.82103327 1.07001663 2.81758337 1 P 0 ;0,1=316,2=270.000000
L 1.07001663 2.81758337 1.07208376 2.81413337 1 P 0 ;0,1=316,2=270.000000
L 1.09585108 2.84206663 1.09843386 2.84436614 1 P 0 ;0,1=316,2=270.000000
L 1.09843386 2.84436614 1.09998346 2.84704961 1 P 0 ;0,1=316,2=270.000000
L 1.09998346 2.84704961 1.1005 2.85049961 1 P 0 ;0,1=316,2=270.000000
L 1.1005 2.85049961 1.09946693 2.8539503 1 P 0 ;0,1=316,2=270.000000
L 1.09946693 2.8539503 1.09740069 2.85663307 1 P 0 ;0,1=316,2=270.000000
L 1.09740069 2.85663307 1.09378386 2.85855 1 P 0 ;0,1=316,2=270.000000
L 1.09378386 2.85855 1.08965049 2.85893327 1 P 0 ;0,1=316,2=270.000000
L 1.08965049 2.85893327 1.08551713 2.85816673 1 P 0 ;0,1=316,2=270.000000
L 1.08551713 2.85816673 1.08293337 2.8562498 1 P 0 ;0,1=316,2=270.000000
L 1.08293337 2.8562498 1.08086713 2.85356634 1 P 0 ;0,1=316,2=270.000000
L 1.08086713 2.85356634 1.08035059 2.85088356 1 P 0 ;0,1=316,2=270.000000
L 1.08035059 2.85088356 1.08086713 2.8482001 1 P 0 ;0,1=316,2=270.000000
L 1.08086713 2.8482001 1.08293337 2.8447501 1 P 0 ;0,1=316,2=270.000000
L 1.08293337 2.8447501 1.0695 2.8458999 1 P 0 ;0,1=316,2=270.000000
L 1.0695 2.8458999 1.0695 2.8562498 1 P 0 ;0,1=316,2=270.000000
L 1.09430039 2.87306663 1.09791722 2.87536614 1 P 0 ;0,1=316,2=270.000000
L 1.09791722 2.87536614 1.09998346 2.87843287 1 P 0 ;0,1=316,2=270.000000
L 1.09998346 2.87843287 1.1005 2.88188356 1 P 0 ;0,1=316,2=270.000000
L 1.1005 2.88188356 1.09998346 2.8849503 1 P 0 ;0,1=316,2=270.000000
L 1.09998346 2.8849503 1.09740069 2.88801703 1 P 0 ;0,1=316,2=270.000000
L 1.09740069 2.88801703 1.09430039 2.88993327 1 P 0 ;0,1=316,2=270.000000
L 1.09430039 2.88993327 1.0912001 2.89031654 1 P 0 ;0,1=316,2=270.000000
L 1.0912001 2.89031654 1.08758425 2.88955 1 P 0 ;0,1=316,2=270.000000
L 1.08758425 2.88955 1.08500049 2.88686654 1 P 0 ;0,1=316,2=270.000000
L 1.08500049 2.88686654 1.08396644 2.88418307 1 P 0 ;0,1=316,2=270.000000
L 1.08396644 2.88418307 1.08396644 2.88073307 1 P 0 ;0,1=316,2=270.000000
L 1.08396644 2.88418307 1.08241683 2.88648327 1 P 0 ;0,1=316,2=270.000000
L 1.08241683 2.88648327 1.07983406 2.8884002 1 P 0 ;0,1=316,2=270.000000
L 1.07983406 2.8884002 1.07673376 2.88916673 1 P 0 ;0,1=316,2=270.000000
L 1.07673376 2.88916673 1.07363346 2.8884002 1 P 0 ;0,1=316,2=270.000000
L 1.07363346 2.8884002 1.07105069 2.88648327 1 P 0 ;0,1=316,2=270.000000
L 1.07105069 2.88648327 1.0695 2.88303327 1 P 0 ;0,1=316,2=270.000000
L 1.0695 2.88303327 1.07001663 2.87958337 1 P 0 ;0,1=316,2=270.000000
L 1.07001663 2.87958337 1.07208376 2.87613337 1 P 0 ;0,1=316,2=270.000000
L 4.59 2.823 4.59 2.867 1 P 0 
L 4.59 2.867 4.5 2.867 1 P 0 
L 4.5 2.823 4.59 2.823 1 P 0 
L 4.5 2.867 4.5 2.823 1 P 0 
L 4.62583317 2.8245 4.62583317 2.8555 1 P 0 ;0,1=317,2=0.000000
L 4.62583317 2.8555 4.63541654 2.8555 1 P 0 ;0,1=317,2=0.000000
L 4.63541654 2.8555 4.63848327 2.85394931 1 P 0 ;0,1=317,2=0.000000
L 4.63848327 2.85394931 4.6404002 2.85188307 1 P 0 ;0,1=317,2=0.000000
L 4.6404002 2.85188307 4.64116673 2.8477497 1 P 0 ;0,1=317,2=0.000000
L 4.64116673 2.8477497 4.6404002 2.84361634 1 P 0 ;0,1=317,2=0.000000
L 4.6404002 2.84361634 4.6381 2.84103356 1 P 0 ;0,1=317,2=0.000000
L 4.6381 2.84103356 4.63541654 2.83948287 1 P 0 ;0,1=317,2=0.000000
L 4.63541654 2.83948287 4.62583317 2.83948287 1 P 0 ;0,1=317,2=0.000000
L 4.63541654 2.83948287 4.64116673 2.8245 1 P 0 ;0,1=317,2=0.000000
L 4.65721644 2.85033346 4.65951663 2.85343278 1 P 0 ;0,1=317,2=0.000000
L 4.65951663 2.85343278 4.6622001 2.85498337 1 P 0 ;0,1=317,2=0.000000
L 4.6622001 2.85498337 4.66526683 2.8555 1 P 0 ;0,1=317,2=0.000000
L 4.66526683 2.8555 4.6691 2.85446683 1 P 0 ;0,1=317,2=0.000000
L 4.6691 2.85446683 4.67178346 2.85188307 1 P 0 ;0,1=317,2=0.000000
L 4.67178346 2.85188307 4.67255 2.84878376 1 P 0 ;0,1=317,2=0.000000
L 4.67255 2.84878376 4.67216673 2.84568258 1 P 0 ;0,1=317,2=0.000000
L 4.67216673 2.84568258 4.67063307 2.8430998 1 P 0 ;0,1=317,2=0.000000
L 4.67063307 2.8430998 4.66296663 2.83793327 1 P 0 ;0,1=317,2=0.000000
L 4.66296663 2.83793327 4.65951663 2.83431644 1 P 0 ;0,1=317,2=0.000000
L 4.65951663 2.83431644 4.65721644 2.82914892 1 P 0 ;0,1=317,2=0.000000
L 4.65721644 2.82914892 4.6564499 2.8245 1 P 0 ;0,1=317,2=0.000000
L 4.6564499 2.8245 4.67255 2.8245 1 P 0 ;0,1=317,2=0.000000
L 4.68706663 2.83069961 4.68936614 2.82708278 1 P 0 ;0,1=317,2=0.000000
L 4.68936614 2.82708278 4.69243287 2.82501654 1 P 0 ;0,1=317,2=0.000000
L 4.69243287 2.82501654 4.69588356 2.8245 1 P 0 ;0,1=317,2=0.000000
L 4.69588356 2.8245 4.6989503 2.82501654 1 P 0 ;0,1=317,2=0.000000
L 4.6989503 2.82501654 4.70201703 2.82759931 1 P 0 ;0,1=317,2=0.000000
L 4.70201703 2.82759931 4.70393327 2.83069961 1 P 0 ;0,1=317,2=0.000000
L 4.70393327 2.83069961 4.70431654 2.8337999 1 P 0 ;0,1=317,2=0.000000
L 4.70431654 2.8337999 4.70355 2.83741575 1 P 0 ;0,1=317,2=0.000000
L 4.70355 2.83741575 4.70086654 2.83999951 1 P 0 ;0,1=317,2=0.000000
L 4.70086654 2.83999951 4.69818307 2.84103356 1 P 0 ;0,1=317,2=0.000000
L 4.69818307 2.84103356 4.69473307 2.84103356 1 P 0 ;0,1=317,2=0.000000
L 4.69818307 2.84103356 4.70048327 2.84258317 1 P 0 ;0,1=317,2=0.000000
L 4.70048327 2.84258317 4.7024002 2.84516594 1 P 0 ;0,1=317,2=0.000000
L 4.7024002 2.84516594 4.70316673 2.84826624 1 P 0 ;0,1=317,2=0.000000
L 4.70316673 2.84826624 4.7024002 2.85136654 1 P 0 ;0,1=317,2=0.000000
L 4.7024002 2.85136654 4.70048327 2.85394931 1 P 0 ;0,1=317,2=0.000000
L 4.70048327 2.85394931 4.69703327 2.8555 1 P 0 ;0,1=317,2=0.000000
L 4.69703327 2.8555 4.69358337 2.85498337 1 P 0 ;0,1=317,2=0.000000
L 4.69358337 2.85498337 4.69013337 2.85291624 1 P 0 ;0,1=317,2=0.000000
L 4.72573307 2.8245 4.72649961 2.83121614 1 P 0 ;0,1=317,2=0.000000
L 4.72649961 2.83121614 4.7276501 2.83689921 1 P 0 ;0,1=317,2=0.000000
L 4.7276501 2.83689921 4.72918307 2.84206663 1 P 0 ;0,1=317,2=0.000000
L 4.72918307 2.84206663 4.7311 2.8477497 1 P 0 ;0,1=317,2=0.000000
L 4.7311 2.8477497 4.73416673 2.8555 1 P 0 ;0,1=317,2=0.000000
L 4.73416673 2.8555 4.71883317 2.8555 1 P 0 ;0,1=317,2=0.000000
L 4.3925 1.101 4.4825 1.101 1 P 0 
L 4.4825 1.101 4.4825 1.145 1 P 0 
L 4.4825 1.145 4.3925 1.145 1 P 0 
L 4.3925 1.145 4.3925 1.101 1 P 0 
L 4.5305 0.98583317 4.4995 0.98583317 1 P 0 ;0,1=318,2=270.000000
L 4.4995 0.98583317 4.4995 0.99541654 1 P 0 ;0,1=318,2=270.000000
L 4.4995 0.99541654 4.50105069 0.99848327 1 P 0 ;0,1=318,2=270.000000
L 4.50105069 0.99848327 4.50311693 1.0004002 1 P 0 ;0,1=318,2=270.000000
L 4.50311693 1.0004002 4.5072503 1.00116673 1 P 0 ;0,1=318,2=270.000000
L 4.5072503 1.00116673 4.51138366 1.0004002 1 P 0 ;0,1=318,2=270.000000
L 4.51138366 1.0004002 4.51396644 0.9981 1 P 0 ;0,1=318,2=270.000000
L 4.51396644 0.9981 4.51551713 0.99541654 1 P 0 ;0,1=318,2=270.000000
L 4.51551713 0.99541654 4.51551713 0.98583317 1 P 0 ;0,1=318,2=270.000000
L 4.51551713 0.99541654 4.5305 1.00116673 1 P 0 ;0,1=318,2=270.000000
L 4.52430039 1.01606663 4.52791722 1.01836614 1 P 0 ;0,1=318,2=270.000000
L 4.52791722 1.01836614 4.52998346 1.02143287 1 P 0 ;0,1=318,2=270.000000
L 4.52998346 1.02143287 4.5305 1.02488356 1 P 0 ;0,1=318,2=270.000000
L 4.5305 1.02488356 4.52998346 1.0279503 1 P 0 ;0,1=318,2=270.000000
L 4.52998346 1.0279503 4.52740069 1.03101703 1 P 0 ;0,1=318,2=270.000000
L 4.52740069 1.03101703 4.52430039 1.03293327 1 P 0 ;0,1=318,2=270.000000
L 4.52430039 1.03293327 4.5212001 1.03331654 1 P 0 ;0,1=318,2=270.000000
L 4.5212001 1.03331654 4.51758425 1.03255 1 P 0 ;0,1=318,2=270.000000
L 4.51758425 1.03255 4.51500049 1.02986654 1 P 0 ;0,1=318,2=270.000000
L 4.51500049 1.02986654 4.51396644 1.02718307 1 P 0 ;0,1=318,2=270.000000
L 4.51396644 1.02718307 4.51396644 1.02373307 1 P 0 ;0,1=318,2=270.000000
L 4.51396644 1.02718307 4.51241683 1.02948327 1 P 0 ;0,1=318,2=270.000000
L 4.51241683 1.02948327 4.50983406 1.0314002 1 P 0 ;0,1=318,2=270.000000
L 4.50983406 1.0314002 4.50673376 1.03216673 1 P 0 ;0,1=318,2=270.000000
L 4.50673376 1.03216673 4.50363346 1.0314002 1 P 0 ;0,1=318,2=270.000000
L 4.50363346 1.0314002 4.50105069 1.02948327 1 P 0 ;0,1=318,2=270.000000
L 4.50105069 1.02948327 4.4995 1.02603327 1 P 0 ;0,1=318,2=270.000000
L 4.4995 1.02603327 4.50001663 1.02258337 1 P 0 ;0,1=318,2=270.000000
L 4.50001663 1.02258337 4.50208376 1.01913337 1 P 0 ;0,1=318,2=270.000000
L 4.52585108 1.04706663 4.52843386 1.04936614 1 P 0 ;0,1=318,2=270.000000
L 4.52843386 1.04936614 4.52998346 1.05204961 1 P 0 ;0,1=318,2=270.000000
L 4.52998346 1.05204961 4.5305 1.05549961 1 P 0 ;0,1=318,2=270.000000
L 4.5305 1.05549961 4.52946693 1.0589503 1 P 0 ;0,1=318,2=270.000000
L 4.52946693 1.0589503 4.52740069 1.06163307 1 P 0 ;0,1=318,2=270.000000
L 4.52740069 1.06163307 4.52378386 1.06355 1 P 0 ;0,1=318,2=270.000000
L 4.52378386 1.06355 4.51965049 1.06393327 1 P 0 ;0,1=318,2=270.000000
L 4.51965049 1.06393327 4.51551713 1.06316673 1 P 0 ;0,1=318,2=270.000000
L 4.51551713 1.06316673 4.51293337 1.0612498 1 P 0 ;0,1=318,2=270.000000
L 4.51293337 1.0612498 4.51086713 1.05856634 1 P 0 ;0,1=318,2=270.000000
L 4.51086713 1.05856634 4.51035059 1.05588356 1 P 0 ;0,1=318,2=270.000000
L 4.51035059 1.05588356 4.51086713 1.0532001 1 P 0 ;0,1=318,2=270.000000
L 4.51086713 1.0532001 4.51293337 1.0497501 1 P 0 ;0,1=318,2=270.000000
L 4.51293337 1.0497501 4.4995 1.0508999 1 P 0 ;0,1=318,2=270.000000
L 4.4995 1.0508999 4.4995 1.0612498 1 P 0 ;0,1=318,2=270.000000
L 4.52688415 1.07998287 4.52946693 1.08266634 1 P 0 ;0,1=318,2=270.000000
L 4.52946693 1.08266634 4.5305 1.08573307 1 P 0 ;0,1=318,2=270.000000
L 4.5305 1.08573307 4.52946693 1.0887998 1 P 0 ;0,1=318,2=270.000000
L 4.52946693 1.0887998 4.52636762 1.09148327 1 P 0 ;0,1=318,2=270.000000
L 4.52636762 1.09148327 4.52171673 1.0934002 1 P 0 ;0,1=318,2=270.000000
L 4.52171673 1.0934002 4.51706673 1.09416673 1 P 0 ;0,1=318,2=270.000000
L 4.51706673 1.09416673 4.51138366 1.09416673 1 P 0 ;0,1=318,2=270.000000
L 4.51138366 1.09416673 4.50673376 1.0934002 1 P 0 ;0,1=318,2=270.000000
L 4.50673376 1.0934002 4.5026003 1.09148327 1 P 0 ;0,1=318,2=270.000000
L 4.5026003 1.09148327 4.50053317 1.08918307 1 P 0 ;0,1=318,2=270.000000
L 4.50053317 1.08918307 4.4995 1.08649961 1 P 0 ;0,1=318,2=270.000000
L 4.4995 1.08649961 4.50053317 1.08343287 1 P 0 ;0,1=318,2=270.000000
L 4.50053317 1.08343287 4.5026003 1.08113337 1 P 0 ;0,1=318,2=270.000000
L 4.5026003 1.08113337 4.5056997 1.0795997 1 P 0 ;0,1=318,2=270.000000
L 4.5056997 1.0795997 4.50983406 1.07883317 1 P 0 ;0,1=318,2=270.000000
L 4.50983406 1.07883317 4.5134499 1.0795997 1 P 0 ;0,1=318,2=270.000000
L 4.5134499 1.0795997 4.51706673 1.08151663 1 P 0 ;0,1=318,2=270.000000
L 4.51706673 1.08151663 4.51913396 1.08381683 1 P 0 ;0,1=318,2=270.000000
L 4.51913396 1.08381683 4.51965049 1.08649961 1 P 0 ;0,1=318,2=270.000000
L 4.51965049 1.08649961 4.51861732 1.08956634 1 P 0 ;0,1=318,2=270.000000
L 4.51861732 1.08956634 4.51603366 1.09186654 1 P 0 ;0,1=318,2=270.000000
L 4.51603366 1.09186654 4.51138366 1.09416673 1 P 0 ;0,1=318,2=270.000000
L 4.3905 1.101 4.3905 1.145 1 P 0 
L 4.3905 1.145 4.3005 1.145 1 P 0 
L 4.3005 1.145 4.3005 1.101 1 P 0 
L 4.3005 1.101 4.3905 1.101 1 P 0 
L 4.2805 1.03583317 4.2495 1.03583317 1 P 0 ;0,1=319,2=270.000000
L 4.2495 1.03583317 4.2495 1.04541654 1 P 0 ;0,1=319,2=270.000000
L 4.2495 1.04541654 4.25105069 1.04848327 1 P 0 ;0,1=319,2=270.000000
L 4.25105069 1.04848327 4.25311693 1.0504002 1 P 0 ;0,1=319,2=270.000000
L 4.25311693 1.0504002 4.2572503 1.05116673 1 P 0 ;0,1=319,2=270.000000
L 4.2572503 1.05116673 4.26138366 1.0504002 1 P 0 ;0,1=319,2=270.000000
L 4.26138366 1.0504002 4.26396644 1.0481 1 P 0 ;0,1=319,2=270.000000
L 4.26396644 1.0481 4.26551713 1.04541654 1 P 0 ;0,1=319,2=270.000000
L 4.26551713 1.04541654 4.26551713 1.03583317 1 P 0 ;0,1=319,2=270.000000
L 4.26551713 1.04541654 4.2805 1.05116673 1 P 0 ;0,1=319,2=270.000000
L 4.27430039 1.06606663 4.27791722 1.06836614 1 P 0 ;0,1=319,2=270.000000
L 4.27791722 1.06836614 4.27998346 1.07143287 1 P 0 ;0,1=319,2=270.000000
L 4.27998346 1.07143287 4.2805 1.07488356 1 P 0 ;0,1=319,2=270.000000
L 4.2805 1.07488356 4.27998346 1.0779503 1 P 0 ;0,1=319,2=270.000000
L 4.27998346 1.0779503 4.27740069 1.08101703 1 P 0 ;0,1=319,2=270.000000
L 4.27740069 1.08101703 4.27430039 1.08293327 1 P 0 ;0,1=319,2=270.000000
L 4.27430039 1.08293327 4.2712001 1.08331654 1 P 0 ;0,1=319,2=270.000000
L 4.2712001 1.08331654 4.26758425 1.08255 1 P 0 ;0,1=319,2=270.000000
L 4.26758425 1.08255 4.26500049 1.07986654 1 P 0 ;0,1=319,2=270.000000
L 4.26500049 1.07986654 4.26396644 1.07718307 1 P 0 ;0,1=319,2=270.000000
L 4.26396644 1.07718307 4.26396644 1.07373307 1 P 0 ;0,1=319,2=270.000000
L 4.26396644 1.07718307 4.26241683 1.07948327 1 P 0 ;0,1=319,2=270.000000
L 4.26241683 1.07948327 4.25983406 1.0814002 1 P 0 ;0,1=319,2=270.000000
L 4.25983406 1.0814002 4.25673376 1.08216673 1 P 0 ;0,1=319,2=270.000000
L 4.25673376 1.08216673 4.25363346 1.0814002 1 P 0 ;0,1=319,2=270.000000
L 4.25363346 1.0814002 4.25105069 1.07948327 1 P 0 ;0,1=319,2=270.000000
L 4.25105069 1.07948327 4.2495 1.07603327 1 P 0 ;0,1=319,2=270.000000
L 4.2495 1.07603327 4.25001663 1.07258337 1 P 0 ;0,1=319,2=270.000000
L 4.25001663 1.07258337 4.25208376 1.06913337 1 P 0 ;0,1=319,2=270.000000
L 4.26758425 1.09821644 4.26396644 1.1008999 1 P 0 ;0,1=319,2=270.000000
L 4.26396644 1.1008999 4.2619002 1.1032001 1 P 0 ;0,1=319,2=270.000000
L 4.2619002 1.1032001 4.26086713 1.10626683 1 P 0 ;0,1=319,2=270.000000
L 4.26086713 1.10626683 4.2619002 1.1089503 1 P 0 ;0,1=319,2=270.000000
L 4.2619002 1.1089503 4.26396644 1.11086654 1 P 0 ;0,1=319,2=270.000000
L 4.26396644 1.11086654 4.26706673 1.1124002 1 P 0 ;0,1=319,2=270.000000
L 4.26706673 1.1124002 4.27068356 1.11278346 1 P 0 ;0,1=319,2=270.000000
L 4.27068356 1.11278346 4.27378386 1.1124002 1 P 0 ;0,1=319,2=270.000000
L 4.27378386 1.1124002 4.27688415 1.11086654 1 P 0 ;0,1=319,2=270.000000
L 4.27688415 1.11086654 4.27946693 1.10856634 1 P 0 ;0,1=319,2=270.000000
L 4.27946693 1.10856634 4.2805 1.10588356 1 P 0 ;0,1=319,2=270.000000
L 4.2805 1.10588356 4.27946693 1.10281683 1 P 0 ;0,1=319,2=270.000000
L 4.27946693 1.10281683 4.27636762 1.10013337 1 P 0 ;0,1=319,2=270.000000
L 4.27636762 1.10013337 4.27171673 1.0985997 1 P 0 ;0,1=319,2=270.000000
L 4.27171673 1.0985997 4.2665502 1.09821644 1 P 0 ;0,1=319,2=270.000000
L 4.2665502 1.09821644 4.25983406 1.09898287 1 P 0 ;0,1=319,2=270.000000
L 4.25983406 1.09898287 4.25621624 1.10013337 1 P 0 ;0,1=319,2=270.000000
L 4.25621624 1.10013337 4.2526003 1.10204961 1 P 0 ;0,1=319,2=270.000000
L 4.2526003 1.10204961 4.25001663 1.10473307 1 P 0 ;0,1=319,2=270.000000
L 4.25001663 1.10473307 4.2495 1.10741654 1 P 0 ;0,1=319,2=270.000000
L 4.2495 1.10741654 4.25053317 1.1101 1 P 0 ;0,1=319,2=270.000000
L 4.25053317 1.1101 4.25311693 1.11201703 1 P 0 ;0,1=319,2=270.000000
L 4.2495 1.13649961 4.25053317 1.13343287 1 P 0 ;0,1=319,2=270.000000
L 4.25053317 1.13343287 4.25311693 1.13113337 1 P 0 ;0,1=319,2=270.000000
L 4.25311693 1.13113337 4.25621624 1.1295997 1 P 0 ;0,1=319,2=270.000000
L 4.25621624 1.1295997 4.26035059 1.1284499 1 P 0 ;0,1=319,2=270.000000
L 4.26035059 1.1284499 4.26500049 1.12806663 1 P 0 ;0,1=319,2=270.000000
L 4.26500049 1.12806663 4.26965049 1.1284499 1 P 0 ;0,1=319,2=270.000000
L 4.26965049 1.1284499 4.27378386 1.1295997 1 P 0 ;0,1=319,2=270.000000
L 4.27378386 1.1295997 4.27688415 1.13113337 1 P 0 ;0,1=319,2=270.000000
L 4.27688415 1.13113337 4.27946693 1.13343287 1 P 0 ;0,1=319,2=270.000000
L 4.27946693 1.13343287 4.2805 1.13649961 1 P 0 ;0,1=319,2=270.000000
L 4.2805 1.13649961 4.27946693 1.13956634 1 P 0 ;0,1=319,2=270.000000
L 4.27946693 1.13956634 4.27688415 1.14186654 1 P 0 ;0,1=319,2=270.000000
L 4.27688415 1.14186654 4.27378386 1.1434002 1 P 0 ;0,1=319,2=270.000000
L 4.27378386 1.1434002 4.26965049 1.14455 1 P 0 ;0,1=319,2=270.000000
L 4.26965049 1.14455 4.26500049 1.14493327 1 P 0 ;0,1=319,2=270.000000
L 4.26500049 1.14493327 4.26035059 1.14455 1 P 0 ;0,1=319,2=270.000000
L 4.26035059 1.14455 4.25621624 1.1434002 1 P 0 ;0,1=319,2=270.000000
L 4.25621624 1.1434002 4.25311693 1.14186654 1 P 0 ;0,1=319,2=270.000000
L 4.25311693 1.14186654 4.25053317 1.13956634 1 P 0 ;0,1=319,2=270.000000
L 4.25053317 1.13956634 4.2495 1.13649961 1 P 0 ;0,1=319,2=270.000000
L 0.508 2.65 0.508 2.56 1 P 0 
L 0.508 2.56 0.552 2.56 1 P 0 
L 0.552 2.56 0.552 2.65 1 P 0 
L 0.552 2.65 0.508 2.65 1 P 0 
L 0.5205 2.74583317 0.4895 2.74583317 1 P 0 ;0,1=320,2=270.000000
L 0.4895 2.74583317 0.4895 2.75541654 1 P 0 ;0,1=320,2=270.000000
L 0.4895 2.75541654 0.49105069 2.75848327 1 P 0 ;0,1=320,2=270.000000
L 0.49105069 2.75848327 0.49311693 2.7604002 1 P 0 ;0,1=320,2=270.000000
L 0.49311693 2.7604002 0.4972503 2.76116673 1 P 0 ;0,1=320,2=270.000000
L 0.4972503 2.76116673 0.50138366 2.7604002 1 P 0 ;0,1=320,2=270.000000
L 0.50138366 2.7604002 0.50396644 2.7581 1 P 0 ;0,1=320,2=270.000000
L 0.50396644 2.7581 0.50551713 2.75541654 1 P 0 ;0,1=320,2=270.000000
L 0.50551713 2.75541654 0.50551713 2.74583317 1 P 0 ;0,1=320,2=270.000000
L 0.50551713 2.75541654 0.5205 2.76116673 1 P 0 ;0,1=320,2=270.000000
L 0.5205 2.78449961 0.4895 2.78449961 1 P 0 ;0,1=320,2=270.000000
L 0.4895 2.78449961 0.4956997 2.7798999 1 P 0 ;0,1=320,2=270.000000
L 0.5205 2.7798999 0.5205 2.78909931 1 P 0 ;0,1=320,2=270.000000
L 0.49466654 2.80821644 0.49156722 2.81051663 1 P 0 ;0,1=320,2=270.000000
L 0.49156722 2.81051663 0.49001663 2.8132001 1 P 0 ;0,1=320,2=270.000000
L 0.49001663 2.8132001 0.4895 2.81626683 1 P 0 ;0,1=320,2=270.000000
L 0.4895 2.81626683 0.49053317 2.8201 1 P 0 ;0,1=320,2=270.000000
L 0.49053317 2.8201 0.49311693 2.82278346 1 P 0 ;0,1=320,2=270.000000
L 0.49311693 2.82278346 0.49621624 2.82355 1 P 0 ;0,1=320,2=270.000000
L 0.49621624 2.82355 0.49931742 2.82316673 1 P 0 ;0,1=320,2=270.000000
L 0.49931742 2.82316673 0.5019002 2.82163307 1 P 0 ;0,1=320,2=270.000000
L 0.5019002 2.82163307 0.50706673 2.81396663 1 P 0 ;0,1=320,2=270.000000
L 0.50706673 2.81396663 0.51068356 2.81051663 1 P 0 ;0,1=320,2=270.000000
L 0.51068356 2.81051663 0.51585108 2.80821644 1 P 0 ;0,1=320,2=270.000000
L 0.51585108 2.80821644 0.5205 2.8074499 1 P 0 ;0,1=320,2=270.000000
L 0.5205 2.8074499 0.5205 2.82355 1 P 0 ;0,1=320,2=270.000000
L 0.4895 2.84649961 0.49053317 2.84343287 1 P 0 ;0,1=320,2=270.000000
L 0.49053317 2.84343287 0.49311693 2.84113337 1 P 0 ;0,1=320,2=270.000000
L 0.49311693 2.84113337 0.49621624 2.8395997 1 P 0 ;0,1=320,2=270.000000
L 0.49621624 2.8395997 0.50035059 2.8384499 1 P 0 ;0,1=320,2=270.000000
L 0.50035059 2.8384499 0.50500049 2.83806663 1 P 0 ;0,1=320,2=270.000000
L 0.50500049 2.83806663 0.50965049 2.8384499 1 P 0 ;0,1=320,2=270.000000
L 0.50965049 2.8384499 0.51378386 2.8395997 1 P 0 ;0,1=320,2=270.000000
L 0.51378386 2.8395997 0.51688415 2.84113337 1 P 0 ;0,1=320,2=270.000000
L 0.51688415 2.84113337 0.51946693 2.84343287 1 P 0 ;0,1=320,2=270.000000
L 0.51946693 2.84343287 0.5205 2.84649961 1 P 0 ;0,1=320,2=270.000000
L 0.5205 2.84649961 0.51946693 2.84956634 1 P 0 ;0,1=320,2=270.000000
L 0.51946693 2.84956634 0.51688415 2.85186654 1 P 0 ;0,1=320,2=270.000000
L 0.51688415 2.85186654 0.51378386 2.8534002 1 P 0 ;0,1=320,2=270.000000
L 0.51378386 2.8534002 0.50965049 2.85455 1 P 0 ;0,1=320,2=270.000000
L 0.50965049 2.85455 0.50500049 2.85493327 1 P 0 ;0,1=320,2=270.000000
L 0.50500049 2.85493327 0.50035059 2.85455 1 P 0 ;0,1=320,2=270.000000
L 0.50035059 2.85455 0.49621624 2.8534002 1 P 0 ;0,1=320,2=270.000000
L 0.49621624 2.8534002 0.49311693 2.85186654 1 P 0 ;0,1=320,2=270.000000
L 0.49311693 2.85186654 0.49053317 2.84956634 1 P 0 ;0,1=320,2=270.000000
L 0.49053317 2.84956634 0.4895 2.84649961 1 P 0 ;0,1=320,2=270.000000
L 0.508 2.115 0.508 2.025 1 P 0 
L 0.508 2.025 0.552 2.025 1 P 0 
L 0.552 2.025 0.552 2.115 1 P 0 
L 0.552 2.115 0.508 2.115 1 P 0 
L 0.4105 1.99583317 0.3795 1.99583317 1 P 0 ;0,1=321,2=270.000000
L 0.3795 1.99583317 0.3795 2.00541654 1 P 0 ;0,1=321,2=270.000000
L 0.3795 2.00541654 0.38105069 2.00848327 1 P 0 ;0,1=321,2=270.000000
L 0.38105069 2.00848327 0.38311693 2.0104002 1 P 0 ;0,1=321,2=270.000000
L 0.38311693 2.0104002 0.3872503 2.01116673 1 P 0 ;0,1=321,2=270.000000
L 0.3872503 2.01116673 0.39138366 2.0104002 1 P 0 ;0,1=321,2=270.000000
L 0.39138366 2.0104002 0.39396644 2.0081 1 P 0 ;0,1=321,2=270.000000
L 0.39396644 2.0081 0.39551713 2.00541654 1 P 0 ;0,1=321,2=270.000000
L 0.39551713 2.00541654 0.39551713 1.99583317 1 P 0 ;0,1=321,2=270.000000
L 0.39551713 2.00541654 0.4105 2.01116673 1 P 0 ;0,1=321,2=270.000000
L 0.4105 2.03449961 0.3795 2.03449961 1 P 0 ;0,1=321,2=270.000000
L 0.3795 2.03449961 0.3856997 2.0298999 1 P 0 ;0,1=321,2=270.000000
L 0.4105 2.0298999 0.4105 2.03909931 1 P 0 ;0,1=321,2=270.000000
L 0.38466654 2.05821644 0.38156722 2.06051663 1 P 0 ;0,1=321,2=270.000000
L 0.38156722 2.06051663 0.38001663 2.0632001 1 P 0 ;0,1=321,2=270.000000
L 0.38001663 2.0632001 0.3795 2.06626683 1 P 0 ;0,1=321,2=270.000000
L 0.3795 2.06626683 0.38053317 2.0701 1 P 0 ;0,1=321,2=270.000000
L 0.38053317 2.0701 0.38311693 2.07278346 1 P 0 ;0,1=321,2=270.000000
L 0.38311693 2.07278346 0.38621624 2.07355 1 P 0 ;0,1=321,2=270.000000
L 0.38621624 2.07355 0.38931742 2.07316673 1 P 0 ;0,1=321,2=270.000000
L 0.38931742 2.07316673 0.3919002 2.07163307 1 P 0 ;0,1=321,2=270.000000
L 0.3919002 2.07163307 0.39706673 2.06396663 1 P 0 ;0,1=321,2=270.000000
L 0.39706673 2.06396663 0.40068356 2.06051663 1 P 0 ;0,1=321,2=270.000000
L 0.40068356 2.06051663 0.40585108 2.05821644 1 P 0 ;0,1=321,2=270.000000
L 0.40585108 2.05821644 0.4105 2.0574499 1 P 0 ;0,1=321,2=270.000000
L 0.4105 2.0574499 0.4105 2.07355 1 P 0 ;0,1=321,2=270.000000
L 0.4105 2.09649961 0.3795 2.09649961 1 P 0 ;0,1=321,2=270.000000
L 0.3795 2.09649961 0.3856997 2.0918999 1 P 0 ;0,1=321,2=270.000000
L 0.4105 2.0918999 0.4105 2.10109931 1 P 0 ;0,1=321,2=270.000000
L 0.477 1.1499 0.433 1.1499 1 P 0 
L 0.433 1.1499 0.433 1.0599 1 P 0 
L 0.433 1.0599 0.477 1.0599 1 P 0 
L 0.477 1.0599 0.477 1.1499 1 P 0 
L 0.3855 1.03083317 0.3545 1.03083317 1 P 0 ;0,1=322,2=270.000000
L 0.3545 1.03083317 0.3545 1.04041654 1 P 0 ;0,1=322,2=270.000000
L 0.3545 1.04041654 0.35605069 1.04348327 1 P 0 ;0,1=322,2=270.000000
L 0.35605069 1.04348327 0.35811693 1.0454002 1 P 0 ;0,1=322,2=270.000000
L 0.35811693 1.0454002 0.3622503 1.04616673 1 P 0 ;0,1=322,2=270.000000
L 0.3622503 1.04616673 0.36638366 1.0454002 1 P 0 ;0,1=322,2=270.000000
L 0.36638366 1.0454002 0.36896644 1.0431 1 P 0 ;0,1=322,2=270.000000
L 0.36896644 1.0431 0.37051713 1.04041654 1 P 0 ;0,1=322,2=270.000000
L 0.37051713 1.04041654 0.37051713 1.03083317 1 P 0 ;0,1=322,2=270.000000
L 0.37051713 1.04041654 0.3855 1.04616673 1 P 0 ;0,1=322,2=270.000000
L 0.3855 1.06949961 0.3545 1.06949961 1 P 0 ;0,1=322,2=270.000000
L 0.3545 1.06949961 0.3606997 1.0648999 1 P 0 ;0,1=322,2=270.000000
L 0.3855 1.0648999 0.3855 1.07409931 1 P 0 ;0,1=322,2=270.000000
L 0.35966654 1.09321644 0.35656722 1.09551663 1 P 0 ;0,1=322,2=270.000000
L 0.35656722 1.09551663 0.35501663 1.0982001 1 P 0 ;0,1=322,2=270.000000
L 0.35501663 1.0982001 0.3545 1.10126683 1 P 0 ;0,1=322,2=270.000000
L 0.3545 1.10126683 0.35553317 1.1051 1 P 0 ;0,1=322,2=270.000000
L 0.35553317 1.1051 0.35811693 1.10778346 1 P 0 ;0,1=322,2=270.000000
L 0.35811693 1.10778346 0.36121624 1.10855 1 P 0 ;0,1=322,2=270.000000
L 0.36121624 1.10855 0.36431742 1.10816673 1 P 0 ;0,1=322,2=270.000000
L 0.36431742 1.10816673 0.3669002 1.10663307 1 P 0 ;0,1=322,2=270.000000
L 0.3669002 1.10663307 0.37206673 1.09896663 1 P 0 ;0,1=322,2=270.000000
L 0.37206673 1.09896663 0.37568356 1.09551663 1 P 0 ;0,1=322,2=270.000000
L 0.37568356 1.09551663 0.38085108 1.09321644 1 P 0 ;0,1=322,2=270.000000
L 0.38085108 1.09321644 0.3855 1.0924499 1 P 0 ;0,1=322,2=270.000000
L 0.3855 1.0924499 0.3855 1.10855 1 P 0 ;0,1=322,2=270.000000
L 0.35966654 1.12421644 0.35656722 1.12651663 1 P 0 ;0,1=322,2=270.000000
L 0.35656722 1.12651663 0.35501663 1.1292001 1 P 0 ;0,1=322,2=270.000000
L 0.35501663 1.1292001 0.3545 1.13226683 1 P 0 ;0,1=322,2=270.000000
L 0.3545 1.13226683 0.35553317 1.1361 1 P 0 ;0,1=322,2=270.000000
L 0.35553317 1.1361 0.35811693 1.13878346 1 P 0 ;0,1=322,2=270.000000
L 0.35811693 1.13878346 0.36121624 1.13955 1 P 0 ;0,1=322,2=270.000000
L 0.36121624 1.13955 0.36431742 1.13916673 1 P 0 ;0,1=322,2=270.000000
L 0.36431742 1.13916673 0.3669002 1.13763307 1 P 0 ;0,1=322,2=270.000000
L 0.3669002 1.13763307 0.37206673 1.12996663 1 P 0 ;0,1=322,2=270.000000
L 0.37206673 1.12996663 0.37568356 1.12651663 1 P 0 ;0,1=322,2=270.000000
L 0.37568356 1.12651663 0.38085108 1.12421644 1 P 0 ;0,1=322,2=270.000000
L 0.38085108 1.12421644 0.3855 1.1234499 1 P 0 ;0,1=322,2=270.000000
L 0.3855 1.1234499 0.3855 1.13955 1 P 0 ;0,1=322,2=270.000000
L 0.477 1.805 0.433 1.805 1 P 0 
L 0.477 1.715 0.477 1.805 1 P 0 
L 0.433 1.805 0.433 1.715 1 P 0 
L 0.433 1.715 0.477 1.715 1 P 0 
L 0.4205 1.72583317 0.3895 1.72583317 1 P 0 ;0,1=323,2=270.000000
L 0.3895 1.72583317 0.3895 1.73541654 1 P 0 ;0,1=323,2=270.000000
L 0.3895 1.73541654 0.39105069 1.73848327 1 P 0 ;0,1=323,2=270.000000
L 0.39105069 1.73848327 0.39311693 1.7404002 1 P 0 ;0,1=323,2=270.000000
L 0.39311693 1.7404002 0.3972503 1.74116673 1 P 0 ;0,1=323,2=270.000000
L 0.3972503 1.74116673 0.40138366 1.7404002 1 P 0 ;0,1=323,2=270.000000
L 0.40138366 1.7404002 0.40396644 1.7381 1 P 0 ;0,1=323,2=270.000000
L 0.40396644 1.7381 0.40551713 1.73541654 1 P 0 ;0,1=323,2=270.000000
L 0.40551713 1.73541654 0.40551713 1.72583317 1 P 0 ;0,1=323,2=270.000000
L 0.40551713 1.73541654 0.4205 1.74116673 1 P 0 ;0,1=323,2=270.000000
L 0.4205 1.76449961 0.3895 1.76449961 1 P 0 ;0,1=323,2=270.000000
L 0.3895 1.76449961 0.3956997 1.7598999 1 P 0 ;0,1=323,2=270.000000
L 0.4205 1.7598999 0.4205 1.76909931 1 P 0 ;0,1=323,2=270.000000
L 0.39466654 1.78821644 0.39156722 1.79051663 1 P 0 ;0,1=323,2=270.000000
L 0.39156722 1.79051663 0.39001663 1.7932001 1 P 0 ;0,1=323,2=270.000000
L 0.39001663 1.7932001 0.3895 1.79626683 1 P 0 ;0,1=323,2=270.000000
L 0.3895 1.79626683 0.39053317 1.8001 1 P 0 ;0,1=323,2=270.000000
L 0.39053317 1.8001 0.39311693 1.80278346 1 P 0 ;0,1=323,2=270.000000
L 0.39311693 1.80278346 0.39621624 1.80355 1 P 0 ;0,1=323,2=270.000000
L 0.39621624 1.80355 0.39931742 1.80316673 1 P 0 ;0,1=323,2=270.000000
L 0.39931742 1.80316673 0.4019002 1.80163307 1 P 0 ;0,1=323,2=270.000000
L 0.4019002 1.80163307 0.40706673 1.79396663 1 P 0 ;0,1=323,2=270.000000
L 0.40706673 1.79396663 0.41068356 1.79051663 1 P 0 ;0,1=323,2=270.000000
L 0.41068356 1.79051663 0.41585108 1.78821644 1 P 0 ;0,1=323,2=270.000000
L 0.41585108 1.78821644 0.4205 1.7874499 1 P 0 ;0,1=323,2=270.000000
L 0.4205 1.7874499 0.4205 1.80355 1 P 0 ;0,1=323,2=270.000000
L 0.40758425 1.81921644 0.40396644 1.8218999 1 P 0 ;0,1=323,2=270.000000
L 0.40396644 1.8218999 0.4019002 1.8242001 1 P 0 ;0,1=323,2=270.000000
L 0.4019002 1.8242001 0.40086713 1.82726683 1 P 0 ;0,1=323,2=270.000000
L 0.40086713 1.82726683 0.4019002 1.8299503 1 P 0 ;0,1=323,2=270.000000
L 0.4019002 1.8299503 0.40396644 1.83186654 1 P 0 ;0,1=323,2=270.000000
L 0.40396644 1.83186654 0.40706673 1.8334002 1 P 0 ;0,1=323,2=270.000000
L 0.40706673 1.8334002 0.41068356 1.83378346 1 P 0 ;0,1=323,2=270.000000
L 0.41068356 1.83378346 0.41378386 1.8334002 1 P 0 ;0,1=323,2=270.000000
L 0.41378386 1.8334002 0.41688415 1.83186654 1 P 0 ;0,1=323,2=270.000000
L 0.41688415 1.83186654 0.41946693 1.82956634 1 P 0 ;0,1=323,2=270.000000
L 0.41946693 1.82956634 0.4205 1.82688356 1 P 0 ;0,1=323,2=270.000000
L 0.4205 1.82688356 0.41946693 1.82381683 1 P 0 ;0,1=323,2=270.000000
L 0.41946693 1.82381683 0.41636762 1.82113337 1 P 0 ;0,1=323,2=270.000000
L 0.41636762 1.82113337 0.41171673 1.8195997 1 P 0 ;0,1=323,2=270.000000
L 0.41171673 1.8195997 0.4065502 1.81921644 1 P 0 ;0,1=323,2=270.000000
L 0.4065502 1.81921644 0.39983406 1.81998287 1 P 0 ;0,1=323,2=270.000000
L 0.39983406 1.81998287 0.39621624 1.82113337 1 P 0 ;0,1=323,2=270.000000
L 0.39621624 1.82113337 0.3926003 1.82304961 1 P 0 ;0,1=323,2=270.000000
L 0.3926003 1.82304961 0.39001663 1.82573307 1 P 0 ;0,1=323,2=270.000000
L 0.39001663 1.82573307 0.3895 1.82841654 1 P 0 ;0,1=323,2=270.000000
L 0.3895 1.82841654 0.39053317 1.8311 1 P 0 ;0,1=323,2=270.000000
L 0.39053317 1.8311 0.39311693 1.83301703 1 P 0 ;0,1=323,2=270.000000
L 0.44251998 2.299 0.44251998 2.209 1 P 0 
L 0.44251998 2.209 0.48651998 2.209 1 P 0 
L 0.48651998 2.209 0.48651998 2.299 1 P 0 
L 0.48651998 2.299 0.44251998 2.299 1 P 0 
L 0.3955 2.18583317 0.3645 2.18583317 1 P 0 ;0,1=324,2=270.000000
L 0.3645 2.18583317 0.3645 2.19541654 1 P 0 ;0,1=324,2=270.000000
L 0.3645 2.19541654 0.36605069 2.19848327 1 P 0 ;0,1=324,2=270.000000
L 0.36605069 2.19848327 0.36811693 2.2004002 1 P 0 ;0,1=324,2=270.000000
L 0.36811693 2.2004002 0.3722503 2.20116673 1 P 0 ;0,1=324,2=270.000000
L 0.3722503 2.20116673 0.37638366 2.2004002 1 P 0 ;0,1=324,2=270.000000
L 0.37638366 2.2004002 0.37896644 2.1981 1 P 0 ;0,1=324,2=270.000000
L 0.37896644 2.1981 0.38051713 2.19541654 1 P 0 ;0,1=324,2=270.000000
L 0.38051713 2.19541654 0.38051713 2.18583317 1 P 0 ;0,1=324,2=270.000000
L 0.38051713 2.19541654 0.3955 2.20116673 1 P 0 ;0,1=324,2=270.000000
L 0.3955 2.22449961 0.3645 2.22449961 1 P 0 ;0,1=324,2=270.000000
L 0.3645 2.22449961 0.3706997 2.2198999 1 P 0 ;0,1=324,2=270.000000
L 0.3955 2.2198999 0.3955 2.22909931 1 P 0 ;0,1=324,2=270.000000
L 0.36966654 2.24821644 0.36656722 2.25051663 1 P 0 ;0,1=324,2=270.000000
L 0.36656722 2.25051663 0.36501663 2.2532001 1 P 0 ;0,1=324,2=270.000000
L 0.36501663 2.2532001 0.3645 2.25626683 1 P 0 ;0,1=324,2=270.000000
L 0.3645 2.25626683 0.36553317 2.2601 1 P 0 ;0,1=324,2=270.000000
L 0.36553317 2.2601 0.36811693 2.26278346 1 P 0 ;0,1=324,2=270.000000
L 0.36811693 2.26278346 0.37121624 2.26355 1 P 0 ;0,1=324,2=270.000000
L 0.37121624 2.26355 0.37431742 2.26316673 1 P 0 ;0,1=324,2=270.000000
L 0.37431742 2.26316673 0.3769002 2.26163307 1 P 0 ;0,1=324,2=270.000000
L 0.3769002 2.26163307 0.38206673 2.25396663 1 P 0 ;0,1=324,2=270.000000
L 0.38206673 2.25396663 0.38568356 2.25051663 1 P 0 ;0,1=324,2=270.000000
L 0.38568356 2.25051663 0.39085108 2.24821644 1 P 0 ;0,1=324,2=270.000000
L 0.39085108 2.24821644 0.3955 2.2474499 1 P 0 ;0,1=324,2=270.000000
L 0.3955 2.2474499 0.3955 2.26355 1 P 0 ;0,1=324,2=270.000000
L 0.3955 2.28573307 0.38878386 2.28649961 1 P 0 ;0,1=324,2=270.000000
L 0.38878386 2.28649961 0.38310079 2.2876501 1 P 0 ;0,1=324,2=270.000000
L 0.38310079 2.2876501 0.37793337 2.28918307 1 P 0 ;0,1=324,2=270.000000
L 0.37793337 2.28918307 0.3722503 2.2911 1 P 0 ;0,1=324,2=270.000000
L 0.3722503 2.2911 0.3645 2.29416673 1 P 0 ;0,1=324,2=270.000000
L 0.3645 2.29416673 0.3645 2.27883317 1 P 0 ;0,1=324,2=270.000000
L 0.552 1.51 0.508 1.51 1 P 0 
L 0.508 1.51 0.508 1.42 1 P 0 
L 0.508 1.42 0.552 1.42 1 P 0 
L 0.552 1.42 0.552 1.51 1 P 0 
L 0.4055 1.36083317 0.3745 1.36083317 1 P 0 ;0,1=325,2=270.000000
L 0.3745 1.36083317 0.3745 1.37041654 1 P 0 ;0,1=325,2=270.000000
L 0.3745 1.37041654 0.37605069 1.37348327 1 P 0 ;0,1=325,2=270.000000
L 0.37605069 1.37348327 0.37811693 1.3754002 1 P 0 ;0,1=325,2=270.000000
L 0.37811693 1.3754002 0.3822503 1.37616673 1 P 0 ;0,1=325,2=270.000000
L 0.3822503 1.37616673 0.38638366 1.3754002 1 P 0 ;0,1=325,2=270.000000
L 0.38638366 1.3754002 0.38896644 1.3731 1 P 0 ;0,1=325,2=270.000000
L 0.38896644 1.3731 0.39051713 1.37041654 1 P 0 ;0,1=325,2=270.000000
L 0.39051713 1.37041654 0.39051713 1.36083317 1 P 0 ;0,1=325,2=270.000000
L 0.39051713 1.37041654 0.4055 1.37616673 1 P 0 ;0,1=325,2=270.000000
L 0.4055 1.39949961 0.3745 1.39949961 1 P 0 ;0,1=325,2=270.000000
L 0.3745 1.39949961 0.3806997 1.3948999 1 P 0 ;0,1=325,2=270.000000
L 0.4055 1.3948999 0.4055 1.40409931 1 P 0 ;0,1=325,2=270.000000
L 0.40085108 1.42206663 0.40343386 1.42436614 1 P 0 ;0,1=325,2=270.000000
L 0.40343386 1.42436614 0.40498346 1.42704961 1 P 0 ;0,1=325,2=270.000000
L 0.40498346 1.42704961 0.4055 1.43049961 1 P 0 ;0,1=325,2=270.000000
L 0.4055 1.43049961 0.40446693 1.4339503 1 P 0 ;0,1=325,2=270.000000
L 0.40446693 1.4339503 0.40240069 1.43663307 1 P 0 ;0,1=325,2=270.000000
L 0.40240069 1.43663307 0.39878386 1.43855 1 P 0 ;0,1=325,2=270.000000
L 0.39878386 1.43855 0.39465049 1.43893327 1 P 0 ;0,1=325,2=270.000000
L 0.39465049 1.43893327 0.39051713 1.43816673 1 P 0 ;0,1=325,2=270.000000
L 0.39051713 1.43816673 0.38793337 1.4362498 1 P 0 ;0,1=325,2=270.000000
L 0.38793337 1.4362498 0.38586713 1.43356634 1 P 0 ;0,1=325,2=270.000000
L 0.38586713 1.43356634 0.38535059 1.43088356 1 P 0 ;0,1=325,2=270.000000
L 0.38535059 1.43088356 0.38586713 1.4282001 1 P 0 ;0,1=325,2=270.000000
L 0.38586713 1.4282001 0.38793337 1.4247501 1 P 0 ;0,1=325,2=270.000000
L 0.38793337 1.4247501 0.3745 1.4258999 1 P 0 ;0,1=325,2=270.000000
L 0.3745 1.4258999 0.3745 1.4362498 1 P 0 ;0,1=325,2=270.000000
L 0.39258425 1.45421644 0.38896644 1.4568999 1 P 0 ;0,1=325,2=270.000000
L 0.38896644 1.4568999 0.3869002 1.4592001 1 P 0 ;0,1=325,2=270.000000
L 0.3869002 1.4592001 0.38586713 1.46226683 1 P 0 ;0,1=325,2=270.000000
L 0.38586713 1.46226683 0.3869002 1.4649503 1 P 0 ;0,1=325,2=270.000000
L 0.3869002 1.4649503 0.38896644 1.46686654 1 P 0 ;0,1=325,2=270.000000
L 0.38896644 1.46686654 0.39206673 1.4684002 1 P 0 ;0,1=325,2=270.000000
L 0.39206673 1.4684002 0.39568356 1.46878346 1 P 0 ;0,1=325,2=270.000000
L 0.39568356 1.46878346 0.39878386 1.4684002 1 P 0 ;0,1=325,2=270.000000
L 0.39878386 1.4684002 0.40188415 1.46686654 1 P 0 ;0,1=325,2=270.000000
L 0.40188415 1.46686654 0.40446693 1.46456634 1 P 0 ;0,1=325,2=270.000000
L 0.40446693 1.46456634 0.4055 1.46188356 1 P 0 ;0,1=325,2=270.000000
L 0.4055 1.46188356 0.40446693 1.45881683 1 P 0 ;0,1=325,2=270.000000
L 0.40446693 1.45881683 0.40136762 1.45613337 1 P 0 ;0,1=325,2=270.000000
L 0.40136762 1.45613337 0.39671673 1.4545997 1 P 0 ;0,1=325,2=270.000000
L 0.39671673 1.4545997 0.3915502 1.45421644 1 P 0 ;0,1=325,2=270.000000
L 0.3915502 1.45421644 0.38483406 1.45498287 1 P 0 ;0,1=325,2=270.000000
L 0.38483406 1.45498287 0.38121624 1.45613337 1 P 0 ;0,1=325,2=270.000000
L 0.38121624 1.45613337 0.3776003 1.45804961 1 P 0 ;0,1=325,2=270.000000
L 0.3776003 1.45804961 0.37501663 1.46073307 1 P 0 ;0,1=325,2=270.000000
L 0.37501663 1.46073307 0.3745 1.46341654 1 P 0 ;0,1=325,2=270.000000
L 0.3745 1.46341654 0.37553317 1.4661 1 P 0 ;0,1=325,2=270.000000
L 0.37553317 1.4661 0.37811693 1.46801703 1 P 0 ;0,1=325,2=270.000000
L 0.557 0.95 0.513 0.95 1 P 0 
L 0.513 0.95 0.513 0.86 1 P 0 
L 0.513 0.86 0.557 0.86 1 P 0 
L 0.557 0.86 0.557 0.95 1 P 0 
L 0.4105 0.82583317 0.3795 0.82583317 1 P 0 ;0,1=326,2=270.000000
L 0.3795 0.82583317 0.3795 0.83541654 1 P 0 ;0,1=326,2=270.000000
L 0.3795 0.83541654 0.38105069 0.83848327 1 P 0 ;0,1=326,2=270.000000
L 0.38105069 0.83848327 0.38311693 0.8404002 1 P 0 ;0,1=326,2=270.000000
L 0.38311693 0.8404002 0.3872503 0.84116673 1 P 0 ;0,1=326,2=270.000000
L 0.3872503 0.84116673 0.39138366 0.8404002 1 P 0 ;0,1=326,2=270.000000
L 0.39138366 0.8404002 0.39396644 0.8381 1 P 0 ;0,1=326,2=270.000000
L 0.39396644 0.8381 0.39551713 0.83541654 1 P 0 ;0,1=326,2=270.000000
L 0.39551713 0.83541654 0.39551713 0.82583317 1 P 0 ;0,1=326,2=270.000000
L 0.39551713 0.83541654 0.4105 0.84116673 1 P 0 ;0,1=326,2=270.000000
L 0.4105 0.86449961 0.3795 0.86449961 1 P 0 ;0,1=326,2=270.000000
L 0.3795 0.86449961 0.3856997 0.8598999 1 P 0 ;0,1=326,2=270.000000
L 0.4105 0.8598999 0.4105 0.86909931 1 P 0 ;0,1=326,2=270.000000
L 0.40585108 0.88706663 0.40843386 0.88936614 1 P 0 ;0,1=326,2=270.000000
L 0.40843386 0.88936614 0.40998346 0.89204961 1 P 0 ;0,1=326,2=270.000000
L 0.40998346 0.89204961 0.4105 0.89549961 1 P 0 ;0,1=326,2=270.000000
L 0.4105 0.89549961 0.40946693 0.8989503 1 P 0 ;0,1=326,2=270.000000
L 0.40946693 0.8989503 0.40740069 0.90163307 1 P 0 ;0,1=326,2=270.000000
L 0.40740069 0.90163307 0.40378386 0.90355 1 P 0 ;0,1=326,2=270.000000
L 0.40378386 0.90355 0.39965049 0.90393327 1 P 0 ;0,1=326,2=270.000000
L 0.39965049 0.90393327 0.39551713 0.90316673 1 P 0 ;0,1=326,2=270.000000
L 0.39551713 0.90316673 0.39293337 0.9012498 1 P 0 ;0,1=326,2=270.000000
L 0.39293337 0.9012498 0.39086713 0.89856634 1 P 0 ;0,1=326,2=270.000000
L 0.39086713 0.89856634 0.39035059 0.89588356 1 P 0 ;0,1=326,2=270.000000
L 0.39035059 0.89588356 0.39086713 0.8932001 1 P 0 ;0,1=326,2=270.000000
L 0.39086713 0.8932001 0.39293337 0.8897501 1 P 0 ;0,1=326,2=270.000000
L 0.39293337 0.8897501 0.3795 0.8908999 1 P 0 ;0,1=326,2=270.000000
L 0.3795 0.8908999 0.3795 0.9012498 1 P 0 ;0,1=326,2=270.000000
L 0.4105 0.92573307 0.40378386 0.92649961 1 P 0 ;0,1=326,2=270.000000
L 0.40378386 0.92649961 0.39810079 0.9276501 1 P 0 ;0,1=326,2=270.000000
L 0.39810079 0.9276501 0.39293337 0.92918307 1 P 0 ;0,1=326,2=270.000000
L 0.39293337 0.92918307 0.3872503 0.9311 1 P 0 ;0,1=326,2=270.000000
L 0.3872503 0.9311 0.3795 0.93416673 1 P 0 ;0,1=326,2=270.000000
L 0.3795 0.93416673 0.3795 0.91883317 1 P 0 ;0,1=326,2=270.000000
L 0.502 1.42 0.502 1.51 1 P 0 
L 0.502 1.51 0.458 1.51 1 P 0 
L 0.458 1.51 0.458 1.42 1 P 0 
L 0.458 1.42 0.502 1.42 1 P 0 
L 0.3655 1.36083317 0.3345 1.36083317 1 P 0 ;0,1=327,2=270.000000
L 0.3345 1.36083317 0.3345 1.37041654 1 P 0 ;0,1=327,2=270.000000
L 0.3345 1.37041654 0.33605069 1.37348327 1 P 0 ;0,1=327,2=270.000000
L 0.33605069 1.37348327 0.33811693 1.3754002 1 P 0 ;0,1=327,2=270.000000
L 0.33811693 1.3754002 0.3422503 1.37616673 1 P 0 ;0,1=327,2=270.000000
L 0.3422503 1.37616673 0.34638366 1.3754002 1 P 0 ;0,1=327,2=270.000000
L 0.34638366 1.3754002 0.34896644 1.3731 1 P 0 ;0,1=327,2=270.000000
L 0.34896644 1.3731 0.35051713 1.37041654 1 P 0 ;0,1=327,2=270.000000
L 0.35051713 1.37041654 0.35051713 1.36083317 1 P 0 ;0,1=327,2=270.000000
L 0.35051713 1.37041654 0.3655 1.37616673 1 P 0 ;0,1=327,2=270.000000
L 0.35930039 1.39106663 0.36291722 1.39336614 1 P 0 ;0,1=327,2=270.000000
L 0.36291722 1.39336614 0.36498346 1.39643287 1 P 0 ;0,1=327,2=270.000000
L 0.36498346 1.39643287 0.3655 1.39988356 1 P 0 ;0,1=327,2=270.000000
L 0.3655 1.39988356 0.36498346 1.4029503 1 P 0 ;0,1=327,2=270.000000
L 0.36498346 1.4029503 0.36240069 1.40601703 1 P 0 ;0,1=327,2=270.000000
L 0.36240069 1.40601703 0.35930039 1.40793327 1 P 0 ;0,1=327,2=270.000000
L 0.35930039 1.40793327 0.3562001 1.40831654 1 P 0 ;0,1=327,2=270.000000
L 0.3562001 1.40831654 0.35258425 1.40755 1 P 0 ;0,1=327,2=270.000000
L 0.35258425 1.40755 0.35000049 1.40486654 1 P 0 ;0,1=327,2=270.000000
L 0.35000049 1.40486654 0.34896644 1.40218307 1 P 0 ;0,1=327,2=270.000000
L 0.34896644 1.40218307 0.34896644 1.39873307 1 P 0 ;0,1=327,2=270.000000
L 0.34896644 1.40218307 0.34741683 1.40448327 1 P 0 ;0,1=327,2=270.000000
L 0.34741683 1.40448327 0.34483406 1.4064002 1 P 0 ;0,1=327,2=270.000000
L 0.34483406 1.4064002 0.34173376 1.40716673 1 P 0 ;0,1=327,2=270.000000
L 0.34173376 1.40716673 0.33863346 1.4064002 1 P 0 ;0,1=327,2=270.000000
L 0.33863346 1.4064002 0.33605069 1.40448327 1 P 0 ;0,1=327,2=270.000000
L 0.33605069 1.40448327 0.3345 1.40103327 1 P 0 ;0,1=327,2=270.000000
L 0.3345 1.40103327 0.33501663 1.39758337 1 P 0 ;0,1=327,2=270.000000
L 0.33501663 1.39758337 0.33708376 1.39413337 1 P 0 ;0,1=327,2=270.000000
L 0.35258425 1.42321644 0.34896644 1.4258999 1 P 0 ;0,1=327,2=270.000000
L 0.34896644 1.4258999 0.3469002 1.4282001 1 P 0 ;0,1=327,2=270.000000
L 0.3469002 1.4282001 0.34586713 1.43126683 1 P 0 ;0,1=327,2=270.000000
L 0.34586713 1.43126683 0.3469002 1.4339503 1 P 0 ;0,1=327,2=270.000000
L 0.3469002 1.4339503 0.34896644 1.43586654 1 P 0 ;0,1=327,2=270.000000
L 0.34896644 1.43586654 0.35206673 1.4374002 1 P 0 ;0,1=327,2=270.000000
L 0.35206673 1.4374002 0.35568356 1.43778346 1 P 0 ;0,1=327,2=270.000000
L 0.35568356 1.43778346 0.35878386 1.4374002 1 P 0 ;0,1=327,2=270.000000
L 0.35878386 1.4374002 0.36188415 1.43586654 1 P 0 ;0,1=327,2=270.000000
L 0.36188415 1.43586654 0.36446693 1.43356634 1 P 0 ;0,1=327,2=270.000000
L 0.36446693 1.43356634 0.3655 1.43088356 1 P 0 ;0,1=327,2=270.000000
L 0.3655 1.43088356 0.36446693 1.42781683 1 P 0 ;0,1=327,2=270.000000
L 0.36446693 1.42781683 0.36136762 1.42513337 1 P 0 ;0,1=327,2=270.000000
L 0.36136762 1.42513337 0.35671673 1.4235997 1 P 0 ;0,1=327,2=270.000000
L 0.35671673 1.4235997 0.3515502 1.42321644 1 P 0 ;0,1=327,2=270.000000
L 0.3515502 1.42321644 0.34483406 1.42398287 1 P 0 ;0,1=327,2=270.000000
L 0.34483406 1.42398287 0.34121624 1.42513337 1 P 0 ;0,1=327,2=270.000000
L 0.34121624 1.42513337 0.3376003 1.42704961 1 P 0 ;0,1=327,2=270.000000
L 0.3376003 1.42704961 0.33501663 1.42973307 1 P 0 ;0,1=327,2=270.000000
L 0.33501663 1.42973307 0.3345 1.43241654 1 P 0 ;0,1=327,2=270.000000
L 0.3345 1.43241654 0.33553317 1.4351 1 P 0 ;0,1=327,2=270.000000
L 0.33553317 1.4351 0.33811693 1.43701703 1 P 0 ;0,1=327,2=270.000000
L 0.3655 1.46073307 0.35878386 1.46149961 1 P 0 ;0,1=327,2=270.000000
L 0.35878386 1.46149961 0.35310079 1.4626501 1 P 0 ;0,1=327,2=270.000000
L 0.35310079 1.4626501 0.34793337 1.46418307 1 P 0 ;0,1=327,2=270.000000
L 0.34793337 1.46418307 0.3422503 1.4661 1 P 0 ;0,1=327,2=270.000000
L 0.3422503 1.4661 0.3345 1.46916673 1 P 0 ;0,1=327,2=270.000000
L 0.3345 1.46916673 0.3345 1.45383317 1 P 0 ;0,1=327,2=270.000000
L 0.507 0.86 0.507 0.95 1 P 0 
L 0.507 0.95 0.463 0.95 1 P 0 
L 0.463 0.95 0.463 0.86 1 P 0 
L 0.463 0.86 0.507 0.86 1 P 0 
L 0.3705 0.82583317 0.3395 0.82583317 1 P 0 ;0,1=328,2=270.000000
L 0.3395 0.82583317 0.3395 0.83541654 1 P 0 ;0,1=328,2=270.000000
L 0.3395 0.83541654 0.34105069 0.83848327 1 P 0 ;0,1=328,2=270.000000
L 0.34105069 0.83848327 0.34311693 0.8404002 1 P 0 ;0,1=328,2=270.000000
L 0.34311693 0.8404002 0.3472503 0.84116673 1 P 0 ;0,1=328,2=270.000000
L 0.3472503 0.84116673 0.35138366 0.8404002 1 P 0 ;0,1=328,2=270.000000
L 0.35138366 0.8404002 0.35396644 0.8381 1 P 0 ;0,1=328,2=270.000000
L 0.35396644 0.8381 0.35551713 0.83541654 1 P 0 ;0,1=328,2=270.000000
L 0.35551713 0.83541654 0.35551713 0.82583317 1 P 0 ;0,1=328,2=270.000000
L 0.35551713 0.83541654 0.3705 0.84116673 1 P 0 ;0,1=328,2=270.000000
L 0.36430039 0.85606663 0.36791722 0.85836614 1 P 0 ;0,1=328,2=270.000000
L 0.36791722 0.85836614 0.36998346 0.86143287 1 P 0 ;0,1=328,2=270.000000
L 0.36998346 0.86143287 0.3705 0.86488356 1 P 0 ;0,1=328,2=270.000000
L 0.3705 0.86488356 0.36998346 0.8679503 1 P 0 ;0,1=328,2=270.000000
L 0.36998346 0.8679503 0.36740069 0.87101703 1 P 0 ;0,1=328,2=270.000000
L 0.36740069 0.87101703 0.36430039 0.87293327 1 P 0 ;0,1=328,2=270.000000
L 0.36430039 0.87293327 0.3612001 0.87331654 1 P 0 ;0,1=328,2=270.000000
L 0.3612001 0.87331654 0.35758425 0.87255 1 P 0 ;0,1=328,2=270.000000
L 0.35758425 0.87255 0.35500049 0.86986654 1 P 0 ;0,1=328,2=270.000000
L 0.35500049 0.86986654 0.35396644 0.86718307 1 P 0 ;0,1=328,2=270.000000
L 0.35396644 0.86718307 0.35396644 0.86373307 1 P 0 ;0,1=328,2=270.000000
L 0.35396644 0.86718307 0.35241683 0.86948327 1 P 0 ;0,1=328,2=270.000000
L 0.35241683 0.86948327 0.34983406 0.8714002 1 P 0 ;0,1=328,2=270.000000
L 0.34983406 0.8714002 0.34673376 0.87216673 1 P 0 ;0,1=328,2=270.000000
L 0.34673376 0.87216673 0.34363346 0.8714002 1 P 0 ;0,1=328,2=270.000000
L 0.34363346 0.8714002 0.34105069 0.86948327 1 P 0 ;0,1=328,2=270.000000
L 0.34105069 0.86948327 0.3395 0.86603327 1 P 0 ;0,1=328,2=270.000000
L 0.3395 0.86603327 0.34001663 0.86258337 1 P 0 ;0,1=328,2=270.000000
L 0.34001663 0.86258337 0.34208376 0.85913337 1 P 0 ;0,1=328,2=270.000000
L 0.3705 0.89473307 0.36378386 0.89549961 1 P 0 ;0,1=328,2=270.000000
L 0.36378386 0.89549961 0.35810079 0.8966501 1 P 0 ;0,1=328,2=270.000000
L 0.35810079 0.8966501 0.35293337 0.89818307 1 P 0 ;0,1=328,2=270.000000
L 0.35293337 0.89818307 0.3472503 0.9001 1 P 0 ;0,1=328,2=270.000000
L 0.3472503 0.9001 0.3395 0.90316673 1 P 0 ;0,1=328,2=270.000000
L 0.3395 0.90316673 0.3395 0.88783317 1 P 0 ;0,1=328,2=270.000000
L 0.3395 0.92649961 0.34053317 0.92343287 1 P 0 ;0,1=328,2=270.000000
L 0.34053317 0.92343287 0.34311693 0.92113337 1 P 0 ;0,1=328,2=270.000000
L 0.34311693 0.92113337 0.34621624 0.9195997 1 P 0 ;0,1=328,2=270.000000
L 0.34621624 0.9195997 0.35035059 0.9184499 1 P 0 ;0,1=328,2=270.000000
L 0.35035059 0.9184499 0.35500049 0.91806663 1 P 0 ;0,1=328,2=270.000000
L 0.35500049 0.91806663 0.35965049 0.9184499 1 P 0 ;0,1=328,2=270.000000
L 0.35965049 0.9184499 0.36378386 0.9195997 1 P 0 ;0,1=328,2=270.000000
L 0.36378386 0.9195997 0.36688415 0.92113337 1 P 0 ;0,1=328,2=270.000000
L 0.36688415 0.92113337 0.36946693 0.92343287 1 P 0 ;0,1=328,2=270.000000
L 0.36946693 0.92343287 0.3705 0.92649961 1 P 0 ;0,1=328,2=270.000000
L 0.3705 0.92649961 0.36946693 0.92956634 1 P 0 ;0,1=328,2=270.000000
L 0.36946693 0.92956634 0.36688415 0.93186654 1 P 0 ;0,1=328,2=270.000000
L 0.36688415 0.93186654 0.36378386 0.9334002 1 P 0 ;0,1=328,2=270.000000
L 0.36378386 0.9334002 0.35965049 0.93455 1 P 0 ;0,1=328,2=270.000000
L 0.35965049 0.93455 0.35500049 0.93493327 1 P 0 ;0,1=328,2=270.000000
L 0.35500049 0.93493327 0.35035059 0.93455 1 P 0 ;0,1=328,2=270.000000
L 0.35035059 0.93455 0.34621624 0.9334002 1 P 0 ;0,1=328,2=270.000000
L 0.34621624 0.9334002 0.34311693 0.93186654 1 P 0 ;0,1=328,2=270.000000
L 0.34311693 0.93186654 0.34053317 0.92956634 1 P 0 ;0,1=328,2=270.000000
L 0.34053317 0.92956634 0.3395 0.92649961 1 P 0 ;0,1=328,2=270.000000
L 0.5 2.545 0.5 2.635 1 P 0 
L 0.5 2.635 0.456 2.635 1 P 0 
L 0.456 2.635 0.456 2.545 1 P 0 
L 0.456 2.545 0.5 2.545 1 P 0 
L 0.4805 2.74583317 0.4495 2.74583317 1 P 0 ;0,1=329,2=270.000000
L 0.4495 2.74583317 0.4495 2.75541654 1 P 0 ;0,1=329,2=270.000000
L 0.4495 2.75541654 0.45105069 2.75848327 1 P 0 ;0,1=329,2=270.000000
L 0.45105069 2.75848327 0.45311693 2.7604002 1 P 0 ;0,1=329,2=270.000000
L 0.45311693 2.7604002 0.4572503 2.76116673 1 P 0 ;0,1=329,2=270.000000
L 0.4572503 2.76116673 0.46138366 2.7604002 1 P 0 ;0,1=329,2=270.000000
L 0.46138366 2.7604002 0.46396644 2.7581 1 P 0 ;0,1=329,2=270.000000
L 0.46396644 2.7581 0.46551713 2.75541654 1 P 0 ;0,1=329,2=270.000000
L 0.46551713 2.75541654 0.46551713 2.74583317 1 P 0 ;0,1=329,2=270.000000
L 0.46551713 2.75541654 0.4805 2.76116673 1 P 0 ;0,1=329,2=270.000000
L 0.47430039 2.77606663 0.47791722 2.77836614 1 P 0 ;0,1=329,2=270.000000
L 0.47791722 2.77836614 0.47998346 2.78143287 1 P 0 ;0,1=329,2=270.000000
L 0.47998346 2.78143287 0.4805 2.78488356 1 P 0 ;0,1=329,2=270.000000
L 0.4805 2.78488356 0.47998346 2.7879503 1 P 0 ;0,1=329,2=270.000000
L 0.47998346 2.7879503 0.47740069 2.79101703 1 P 0 ;0,1=329,2=270.000000
L 0.47740069 2.79101703 0.47430039 2.79293327 1 P 0 ;0,1=329,2=270.000000
L 0.47430039 2.79293327 0.4712001 2.79331654 1 P 0 ;0,1=329,2=270.000000
L 0.4712001 2.79331654 0.46758425 2.79255 1 P 0 ;0,1=329,2=270.000000
L 0.46758425 2.79255 0.46500049 2.78986654 1 P 0 ;0,1=329,2=270.000000
L 0.46500049 2.78986654 0.46396644 2.78718307 1 P 0 ;0,1=329,2=270.000000
L 0.46396644 2.78718307 0.46396644 2.78373307 1 P 0 ;0,1=329,2=270.000000
L 0.46396644 2.78718307 0.46241683 2.78948327 1 P 0 ;0,1=329,2=270.000000
L 0.46241683 2.78948327 0.45983406 2.7914002 1 P 0 ;0,1=329,2=270.000000
L 0.45983406 2.7914002 0.45673376 2.79216673 1 P 0 ;0,1=329,2=270.000000
L 0.45673376 2.79216673 0.45363346 2.7914002 1 P 0 ;0,1=329,2=270.000000
L 0.45363346 2.7914002 0.45105069 2.78948327 1 P 0 ;0,1=329,2=270.000000
L 0.45105069 2.78948327 0.4495 2.78603327 1 P 0 ;0,1=329,2=270.000000
L 0.4495 2.78603327 0.45001663 2.78258337 1 P 0 ;0,1=329,2=270.000000
L 0.45001663 2.78258337 0.45208376 2.77913337 1 P 0 ;0,1=329,2=270.000000
L 0.4805 2.81473307 0.47378386 2.81549961 1 P 0 ;0,1=329,2=270.000000
L 0.47378386 2.81549961 0.46810079 2.8166501 1 P 0 ;0,1=329,2=270.000000
L 0.46810079 2.8166501 0.46293337 2.81818307 1 P 0 ;0,1=329,2=270.000000
L 0.46293337 2.81818307 0.4572503 2.8201 1 P 0 ;0,1=329,2=270.000000
L 0.4572503 2.8201 0.4495 2.82316673 1 P 0 ;0,1=329,2=270.000000
L 0.4495 2.82316673 0.4495 2.80783317 1 P 0 ;0,1=329,2=270.000000
L 0.4805 2.84649961 0.4495 2.84649961 1 P 0 ;0,1=329,2=270.000000
L 0.4495 2.84649961 0.4556997 2.8418999 1 P 0 ;0,1=329,2=270.000000
L 0.4805 2.8418999 0.4805 2.85109931 1 P 0 ;0,1=329,2=270.000000
L 0.502 2.025 0.502 2.115 1 P 0 
L 0.502 2.115 0.458 2.115 1 P 0 
L 0.458 2.115 0.458 2.025 1 P 0 
L 0.458 2.025 0.502 2.025 1 P 0 
L 0.3705 1.99583317 0.3395 1.99583317 1 P 0 ;0,1=330,2=270.000000
L 0.3395 1.99583317 0.3395 2.00541654 1 P 0 ;0,1=330,2=270.000000
L 0.3395 2.00541654 0.34105069 2.00848327 1 P 0 ;0,1=330,2=270.000000
L 0.34105069 2.00848327 0.34311693 2.0104002 1 P 0 ;0,1=330,2=270.000000
L 0.34311693 2.0104002 0.3472503 2.01116673 1 P 0 ;0,1=330,2=270.000000
L 0.3472503 2.01116673 0.35138366 2.0104002 1 P 0 ;0,1=330,2=270.000000
L 0.35138366 2.0104002 0.35396644 2.0081 1 P 0 ;0,1=330,2=270.000000
L 0.35396644 2.0081 0.35551713 2.00541654 1 P 0 ;0,1=330,2=270.000000
L 0.35551713 2.00541654 0.35551713 1.99583317 1 P 0 ;0,1=330,2=270.000000
L 0.35551713 2.00541654 0.3705 2.01116673 1 P 0 ;0,1=330,2=270.000000
L 0.36430039 2.02606663 0.36791722 2.02836614 1 P 0 ;0,1=330,2=270.000000
L 0.36791722 2.02836614 0.36998346 2.03143287 1 P 0 ;0,1=330,2=270.000000
L 0.36998346 2.03143287 0.3705 2.03488356 1 P 0 ;0,1=330,2=270.000000
L 0.3705 2.03488356 0.36998346 2.0379503 1 P 0 ;0,1=330,2=270.000000
L 0.36998346 2.0379503 0.36740069 2.04101703 1 P 0 ;0,1=330,2=270.000000
L 0.36740069 2.04101703 0.36430039 2.04293327 1 P 0 ;0,1=330,2=270.000000
L 0.36430039 2.04293327 0.3612001 2.04331654 1 P 0 ;0,1=330,2=270.000000
L 0.3612001 2.04331654 0.35758425 2.04255 1 P 0 ;0,1=330,2=270.000000
L 0.35758425 2.04255 0.35500049 2.03986654 1 P 0 ;0,1=330,2=270.000000
L 0.35500049 2.03986654 0.35396644 2.03718307 1 P 0 ;0,1=330,2=270.000000
L 0.35396644 2.03718307 0.35396644 2.03373307 1 P 0 ;0,1=330,2=270.000000
L 0.35396644 2.03718307 0.35241683 2.03948327 1 P 0 ;0,1=330,2=270.000000
L 0.35241683 2.03948327 0.34983406 2.0414002 1 P 0 ;0,1=330,2=270.000000
L 0.34983406 2.0414002 0.34673376 2.04216673 1 P 0 ;0,1=330,2=270.000000
L 0.34673376 2.04216673 0.34363346 2.0414002 1 P 0 ;0,1=330,2=270.000000
L 0.34363346 2.0414002 0.34105069 2.03948327 1 P 0 ;0,1=330,2=270.000000
L 0.34105069 2.03948327 0.3395 2.03603327 1 P 0 ;0,1=330,2=270.000000
L 0.3395 2.03603327 0.34001663 2.03258337 1 P 0 ;0,1=330,2=270.000000
L 0.34001663 2.03258337 0.34208376 2.02913337 1 P 0 ;0,1=330,2=270.000000
L 0.3705 2.06473307 0.36378386 2.06549961 1 P 0 ;0,1=330,2=270.000000
L 0.36378386 2.06549961 0.35810079 2.0666501 1 P 0 ;0,1=330,2=270.000000
L 0.35810079 2.0666501 0.35293337 2.06818307 1 P 0 ;0,1=330,2=270.000000
L 0.35293337 2.06818307 0.3472503 2.0701 1 P 0 ;0,1=330,2=270.000000
L 0.3472503 2.0701 0.3395 2.07316673 1 P 0 ;0,1=330,2=270.000000
L 0.3395 2.07316673 0.3395 2.05783317 1 P 0 ;0,1=330,2=270.000000
L 0.34466654 2.08921644 0.34156722 2.09151663 1 P 0 ;0,1=330,2=270.000000
L 0.34156722 2.09151663 0.34001663 2.0942001 1 P 0 ;0,1=330,2=270.000000
L 0.34001663 2.0942001 0.3395 2.09726683 1 P 0 ;0,1=330,2=270.000000
L 0.3395 2.09726683 0.34053317 2.1011 1 P 0 ;0,1=330,2=270.000000
L 0.34053317 2.1011 0.34311693 2.10378346 1 P 0 ;0,1=330,2=270.000000
L 0.34311693 2.10378346 0.34621624 2.10455 1 P 0 ;0,1=330,2=270.000000
L 0.34621624 2.10455 0.34931742 2.10416673 1 P 0 ;0,1=330,2=270.000000
L 0.34931742 2.10416673 0.3519002 2.10263307 1 P 0 ;0,1=330,2=270.000000
L 0.3519002 2.10263307 0.35706673 2.09496663 1 P 0 ;0,1=330,2=270.000000
L 0.35706673 2.09496663 0.36068356 2.09151663 1 P 0 ;0,1=330,2=270.000000
L 0.36068356 2.09151663 0.36585108 2.08921644 1 P 0 ;0,1=330,2=270.000000
L 0.36585108 2.08921644 0.3705 2.0884499 1 P 0 ;0,1=330,2=270.000000
L 0.3705 2.0884499 0.3705 2.10455 1 P 0 ;0,1=330,2=270.000000
L 1.411 4.12 1.501 4.12 1 P 0 
L 1.501 4.12 1.501 4.164 1 P 0 
L 1.501 4.164 1.411 4.164 1 P 0 
L 1.411 4.164 1.411 4.12 1 P 0 
L 1.25633317 4.1645 1.25633317 4.1955 1 P 0 ;0,1=331,2=0.000000
L 1.25633317 4.1955 1.26591654 4.1955 1 P 0 ;0,1=331,2=0.000000
L 1.26591654 4.1955 1.26898327 4.19394931 1 P 0 ;0,1=331,2=0.000000
L 1.26898327 4.19394931 1.2709002 4.19188307 1 P 0 ;0,1=331,2=0.000000
L 1.2709002 4.19188307 1.27166673 4.1877497 1 P 0 ;0,1=331,2=0.000000
L 1.27166673 4.1877497 1.2709002 4.18361634 1 P 0 ;0,1=331,2=0.000000
L 1.2709002 4.18361634 1.2686 4.18103356 1 P 0 ;0,1=331,2=0.000000
L 1.2686 4.18103356 1.26591654 4.17948287 1 P 0 ;0,1=331,2=0.000000
L 1.26591654 4.17948287 1.25633317 4.17948287 1 P 0 ;0,1=331,2=0.000000
L 1.26591654 4.17948287 1.27166673 4.1645 1 P 0 ;0,1=331,2=0.000000
L 1.28656663 4.17069961 1.28886614 4.16708278 1 P 0 ;0,1=331,2=0.000000
L 1.28886614 4.16708278 1.29193287 4.16501654 1 P 0 ;0,1=331,2=0.000000
L 1.29193287 4.16501654 1.29538356 4.1645 1 P 0 ;0,1=331,2=0.000000
L 1.29538356 4.1645 1.2984503 4.16501654 1 P 0 ;0,1=331,2=0.000000
L 1.2984503 4.16501654 1.30151703 4.16759931 1 P 0 ;0,1=331,2=0.000000
L 1.30151703 4.16759931 1.30343327 4.17069961 1 P 0 ;0,1=331,2=0.000000
L 1.30343327 4.17069961 1.30381654 4.1737999 1 P 0 ;0,1=331,2=0.000000
L 1.30381654 4.1737999 1.30305 4.17741575 1 P 0 ;0,1=331,2=0.000000
L 1.30305 4.17741575 1.30036654 4.17999951 1 P 0 ;0,1=331,2=0.000000
L 1.30036654 4.17999951 1.29768307 4.18103356 1 P 0 ;0,1=331,2=0.000000
L 1.29768307 4.18103356 1.29423307 4.18103356 1 P 0 ;0,1=331,2=0.000000
L 1.29768307 4.18103356 1.29998327 4.18258317 1 P 0 ;0,1=331,2=0.000000
L 1.29998327 4.18258317 1.3019002 4.18516594 1 P 0 ;0,1=331,2=0.000000
L 1.3019002 4.18516594 1.30266673 4.18826624 1 P 0 ;0,1=331,2=0.000000
L 1.30266673 4.18826624 1.3019002 4.19136654 1 P 0 ;0,1=331,2=0.000000
L 1.3019002 4.19136654 1.29998327 4.19394931 1 P 0 ;0,1=331,2=0.000000
L 1.29998327 4.19394931 1.29653327 4.1955 1 P 0 ;0,1=331,2=0.000000
L 1.29653327 4.1955 1.29308337 4.19498337 1 P 0 ;0,1=331,2=0.000000
L 1.29308337 4.19498337 1.28963337 4.19291624 1 P 0 ;0,1=331,2=0.000000
L 1.3306 4.1645 1.3306 4.1955 1 P 0 ;0,1=331,2=0.000000
L 1.3306 4.1955 1.31641624 4.17328327 1 P 0 ;0,1=331,2=0.000000
L 1.31641624 4.17328327 1.33558366 4.17328327 1 P 0 ;0,1=331,2=0.000000
L 0.352 3.165 0.352 3.255 1 P 0 
L 0.352 3.255 0.308 3.255 1 P 0 
L 0.308 3.255 0.308 3.165 1 P 0 
L 0.308 3.165 0.352 3.165 1 P 0 
L 0.3205 3.05083317 0.2895 3.05083317 1 P 0 ;0,1=332,2=270.000000
L 0.2895 3.05083317 0.2895 3.06041654 1 P 0 ;0,1=332,2=270.000000
L 0.2895 3.06041654 0.29105069 3.06348327 1 P 0 ;0,1=332,2=270.000000
L 0.29105069 3.06348327 0.29311693 3.0654002 1 P 0 ;0,1=332,2=270.000000
L 0.29311693 3.0654002 0.2972503 3.06616673 1 P 0 ;0,1=332,2=270.000000
L 0.2972503 3.06616673 0.30138366 3.0654002 1 P 0 ;0,1=332,2=270.000000
L 0.30138366 3.0654002 0.30396644 3.0631 1 P 0 ;0,1=332,2=270.000000
L 0.30396644 3.0631 0.30551713 3.06041654 1 P 0 ;0,1=332,2=270.000000
L 0.30551713 3.06041654 0.30551713 3.05083317 1 P 0 ;0,1=332,2=270.000000
L 0.30551713 3.06041654 0.3205 3.06616673 1 P 0 ;0,1=332,2=270.000000
L 0.31430039 3.08106663 0.31791722 3.08336614 1 P 0 ;0,1=332,2=270.000000
L 0.31791722 3.08336614 0.31998346 3.08643287 1 P 0 ;0,1=332,2=270.000000
L 0.31998346 3.08643287 0.3205 3.08988356 1 P 0 ;0,1=332,2=270.000000
L 0.3205 3.08988356 0.31998346 3.0929503 1 P 0 ;0,1=332,2=270.000000
L 0.31998346 3.0929503 0.31740069 3.09601703 1 P 0 ;0,1=332,2=270.000000
L 0.31740069 3.09601703 0.31430039 3.09793327 1 P 0 ;0,1=332,2=270.000000
L 0.31430039 3.09793327 0.3112001 3.09831654 1 P 0 ;0,1=332,2=270.000000
L 0.3112001 3.09831654 0.30758425 3.09755 1 P 0 ;0,1=332,2=270.000000
L 0.30758425 3.09755 0.30500049 3.09486654 1 P 0 ;0,1=332,2=270.000000
L 0.30500049 3.09486654 0.30396644 3.09218307 1 P 0 ;0,1=332,2=270.000000
L 0.30396644 3.09218307 0.30396644 3.08873307 1 P 0 ;0,1=332,2=270.000000
L 0.30396644 3.09218307 0.30241683 3.09448327 1 P 0 ;0,1=332,2=270.000000
L 0.30241683 3.09448327 0.29983406 3.0964002 1 P 0 ;0,1=332,2=270.000000
L 0.29983406 3.0964002 0.29673376 3.09716673 1 P 0 ;0,1=332,2=270.000000
L 0.29673376 3.09716673 0.29363346 3.0964002 1 P 0 ;0,1=332,2=270.000000
L 0.29363346 3.0964002 0.29105069 3.09448327 1 P 0 ;0,1=332,2=270.000000
L 0.29105069 3.09448327 0.2895 3.09103327 1 P 0 ;0,1=332,2=270.000000
L 0.2895 3.09103327 0.29001663 3.08758337 1 P 0 ;0,1=332,2=270.000000
L 0.29001663 3.08758337 0.29208376 3.08413337 1 P 0 ;0,1=332,2=270.000000
L 0.31688415 3.11398287 0.31946693 3.11666634 1 P 0 ;0,1=332,2=270.000000
L 0.31946693 3.11666634 0.3205 3.11973307 1 P 0 ;0,1=332,2=270.000000
L 0.3205 3.11973307 0.31946693 3.1227998 1 P 0 ;0,1=332,2=270.000000
L 0.31946693 3.1227998 0.31636762 3.12548327 1 P 0 ;0,1=332,2=270.000000
L 0.31636762 3.12548327 0.31171673 3.1274002 1 P 0 ;0,1=332,2=270.000000
L 0.31171673 3.1274002 0.30706673 3.12816673 1 P 0 ;0,1=332,2=270.000000
L 0.30706673 3.12816673 0.30138366 3.12816673 1 P 0 ;0,1=332,2=270.000000
L 0.30138366 3.12816673 0.29673376 3.1274002 1 P 0 ;0,1=332,2=270.000000
L 0.29673376 3.1274002 0.2926003 3.12548327 1 P 0 ;0,1=332,2=270.000000
L 0.2926003 3.12548327 0.29053317 3.12318307 1 P 0 ;0,1=332,2=270.000000
L 0.29053317 3.12318307 0.2895 3.12049961 1 P 0 ;0,1=332,2=270.000000
L 0.2895 3.12049961 0.29053317 3.11743287 1 P 0 ;0,1=332,2=270.000000
L 0.29053317 3.11743287 0.2926003 3.11513337 1 P 0 ;0,1=332,2=270.000000
L 0.2926003 3.11513337 0.2956997 3.1135997 1 P 0 ;0,1=332,2=270.000000
L 0.2956997 3.1135997 0.29983406 3.11283317 1 P 0 ;0,1=332,2=270.000000
L 0.29983406 3.11283317 0.3034499 3.1135997 1 P 0 ;0,1=332,2=270.000000
L 0.3034499 3.1135997 0.30706673 3.11551663 1 P 0 ;0,1=332,2=270.000000
L 0.30706673 3.11551663 0.30913396 3.11781683 1 P 0 ;0,1=332,2=270.000000
L 0.30913396 3.11781683 0.30965049 3.12049961 1 P 0 ;0,1=332,2=270.000000
L 0.30965049 3.12049961 0.30861732 3.12356634 1 P 0 ;0,1=332,2=270.000000
L 0.30861732 3.12356634 0.30603366 3.12586654 1 P 0 ;0,1=332,2=270.000000
L 0.30603366 3.12586654 0.30138366 3.12816673 1 P 0 ;0,1=332,2=270.000000
L 0.31688415 3.14498287 0.31946693 3.14766634 1 P 0 ;0,1=332,2=270.000000
L 0.31946693 3.14766634 0.3205 3.15073307 1 P 0 ;0,1=332,2=270.000000
L 0.3205 3.15073307 0.31946693 3.1537998 1 P 0 ;0,1=332,2=270.000000
L 0.31946693 3.1537998 0.31636762 3.15648327 1 P 0 ;0,1=332,2=270.000000
L 0.31636762 3.15648327 0.31171673 3.1584002 1 P 0 ;0,1=332,2=270.000000
L 0.31171673 3.1584002 0.30706673 3.15916673 1 P 0 ;0,1=332,2=270.000000
L 0.30706673 3.15916673 0.30138366 3.15916673 1 P 0 ;0,1=332,2=270.000000
L 0.30138366 3.15916673 0.29673376 3.1584002 1 P 0 ;0,1=332,2=270.000000
L 0.29673376 3.1584002 0.2926003 3.15648327 1 P 0 ;0,1=332,2=270.000000
L 0.2926003 3.15648327 0.29053317 3.15418307 1 P 0 ;0,1=332,2=270.000000
L 0.29053317 3.15418307 0.2895 3.15149961 1 P 0 ;0,1=332,2=270.000000
L 0.2895 3.15149961 0.29053317 3.14843287 1 P 0 ;0,1=332,2=270.000000
L 0.29053317 3.14843287 0.2926003 3.14613337 1 P 0 ;0,1=332,2=270.000000
L 0.2926003 3.14613337 0.2956997 3.1445997 1 P 0 ;0,1=332,2=270.000000
L 0.2956997 3.1445997 0.29983406 3.14383317 1 P 0 ;0,1=332,2=270.000000
L 0.29983406 3.14383317 0.3034499 3.1445997 1 P 0 ;0,1=332,2=270.000000
L 0.3034499 3.1445997 0.30706673 3.14651663 1 P 0 ;0,1=332,2=270.000000
L 0.30706673 3.14651663 0.30913396 3.14881683 1 P 0 ;0,1=332,2=270.000000
L 0.30913396 3.14881683 0.30965049 3.15149961 1 P 0 ;0,1=332,2=270.000000
L 0.30965049 3.15149961 0.30861732 3.15456634 1 P 0 ;0,1=332,2=270.000000
L 0.30861732 3.15456634 0.30603366 3.15686654 1 P 0 ;0,1=332,2=270.000000
L 0.30603366 3.15686654 0.30138366 3.15916673 1 P 0 ;0,1=332,2=270.000000
L 0.302 3.255 0.258 3.255 1 P 0 
L 0.302 3.165 0.302 3.255 1 P 0 
L 0.258 3.255 0.258 3.165 1 P 0 
L 0.258 3.165 0.302 3.165 1 P 0 
L 0.2805 3.05083317 0.2495 3.05083317 1 P 0 ;0,1=333,2=270.000000
L 0.2495 3.05083317 0.2495 3.06041654 1 P 0 ;0,1=333,2=270.000000
L 0.2495 3.06041654 0.25105069 3.06348327 1 P 0 ;0,1=333,2=270.000000
L 0.25105069 3.06348327 0.25311693 3.0654002 1 P 0 ;0,1=333,2=270.000000
L 0.25311693 3.0654002 0.2572503 3.06616673 1 P 0 ;0,1=333,2=270.000000
L 0.2572503 3.06616673 0.26138366 3.0654002 1 P 0 ;0,1=333,2=270.000000
L 0.26138366 3.0654002 0.26396644 3.0631 1 P 0 ;0,1=333,2=270.000000
L 0.26396644 3.0631 0.26551713 3.06041654 1 P 0 ;0,1=333,2=270.000000
L 0.26551713 3.06041654 0.26551713 3.05083317 1 P 0 ;0,1=333,2=270.000000
L 0.26551713 3.06041654 0.2805 3.06616673 1 P 0 ;0,1=333,2=270.000000
L 0.2805 3.0941 0.2495 3.0941 1 P 0 ;0,1=333,2=270.000000
L 0.2495 3.0941 0.27171673 3.07991624 1 P 0 ;0,1=333,2=270.000000
L 0.27171673 3.07991624 0.27171673 3.09908366 1 P 0 ;0,1=333,2=270.000000
L 0.25466654 3.11321644 0.25156722 3.11551663 1 P 0 ;0,1=333,2=270.000000
L 0.25156722 3.11551663 0.25001663 3.1182001 1 P 0 ;0,1=333,2=270.000000
L 0.25001663 3.1182001 0.2495 3.12126683 1 P 0 ;0,1=333,2=270.000000
L 0.2495 3.12126683 0.25053317 3.1251 1 P 0 ;0,1=333,2=270.000000
L 0.25053317 3.1251 0.25311693 3.12778346 1 P 0 ;0,1=333,2=270.000000
L 0.25311693 3.12778346 0.25621624 3.12855 1 P 0 ;0,1=333,2=270.000000
L 0.25621624 3.12855 0.25931742 3.12816673 1 P 0 ;0,1=333,2=270.000000
L 0.25931742 3.12816673 0.2619002 3.12663307 1 P 0 ;0,1=333,2=270.000000
L 0.2619002 3.12663307 0.26706673 3.11896663 1 P 0 ;0,1=333,2=270.000000
L 0.26706673 3.11896663 0.27068356 3.11551663 1 P 0 ;0,1=333,2=270.000000
L 0.27068356 3.11551663 0.27585108 3.11321644 1 P 0 ;0,1=333,2=270.000000
L 0.27585108 3.11321644 0.2805 3.1124499 1 P 0 ;0,1=333,2=270.000000
L 0.2805 3.1124499 0.2805 3.12855 1 P 0 ;0,1=333,2=270.000000
L 0.2805 3.15073307 0.27378386 3.15149961 1 P 0 ;0,1=333,2=270.000000
L 0.27378386 3.15149961 0.26810079 3.1526501 1 P 0 ;0,1=333,2=270.000000
L 0.26810079 3.1526501 0.26293337 3.15418307 1 P 0 ;0,1=333,2=270.000000
L 0.26293337 3.15418307 0.2572503 3.1561 1 P 0 ;0,1=333,2=270.000000
L 0.2572503 3.1561 0.2495 3.15916673 1 P 0 ;0,1=333,2=270.000000
L 0.2495 3.15916673 0.2495 3.14383317 1 P 0 ;0,1=333,2=270.000000
L 0.252 3.255 0.208 3.255 1 P 0 
L 0.252 3.165 0.252 3.255 1 P 0 
L 0.208 3.255 0.208 3.165 1 P 0 
L 0.208 3.165 0.252 3.165 1 P 0 
L 0.2305 3.05083317 0.1995 3.05083317 1 P 0 ;0,1=334,2=270.000000
L 0.1995 3.05083317 0.1995 3.06041654 1 P 0 ;0,1=334,2=270.000000
L 0.1995 3.06041654 0.20105069 3.06348327 1 P 0 ;0,1=334,2=270.000000
L 0.20105069 3.06348327 0.20311693 3.0654002 1 P 0 ;0,1=334,2=270.000000
L 0.20311693 3.0654002 0.2072503 3.06616673 1 P 0 ;0,1=334,2=270.000000
L 0.2072503 3.06616673 0.21138366 3.0654002 1 P 0 ;0,1=334,2=270.000000
L 0.21138366 3.0654002 0.21396644 3.0631 1 P 0 ;0,1=334,2=270.000000
L 0.21396644 3.0631 0.21551713 3.06041654 1 P 0 ;0,1=334,2=270.000000
L 0.21551713 3.06041654 0.21551713 3.05083317 1 P 0 ;0,1=334,2=270.000000
L 0.21551713 3.06041654 0.2305 3.06616673 1 P 0 ;0,1=334,2=270.000000
L 0.2305 3.0941 0.1995 3.0941 1 P 0 ;0,1=334,2=270.000000
L 0.1995 3.0941 0.22171673 3.07991624 1 P 0 ;0,1=334,2=270.000000
L 0.22171673 3.07991624 0.22171673 3.09908366 1 P 0 ;0,1=334,2=270.000000
L 0.20466654 3.11321644 0.20156722 3.11551663 1 P 0 ;0,1=334,2=270.000000
L 0.20156722 3.11551663 0.20001663 3.1182001 1 P 0 ;0,1=334,2=270.000000
L 0.20001663 3.1182001 0.1995 3.12126683 1 P 0 ;0,1=334,2=270.000000
L 0.1995 3.12126683 0.20053317 3.1251 1 P 0 ;0,1=334,2=270.000000
L 0.20053317 3.1251 0.20311693 3.12778346 1 P 0 ;0,1=334,2=270.000000
L 0.20311693 3.12778346 0.20621624 3.12855 1 P 0 ;0,1=334,2=270.000000
L 0.20621624 3.12855 0.20931742 3.12816673 1 P 0 ;0,1=334,2=270.000000
L 0.20931742 3.12816673 0.2119002 3.12663307 1 P 0 ;0,1=334,2=270.000000
L 0.2119002 3.12663307 0.21706673 3.11896663 1 P 0 ;0,1=334,2=270.000000
L 0.21706673 3.11896663 0.22068356 3.11551663 1 P 0 ;0,1=334,2=270.000000
L 0.22068356 3.11551663 0.22585108 3.11321644 1 P 0 ;0,1=334,2=270.000000
L 0.22585108 3.11321644 0.2305 3.1124499 1 P 0 ;0,1=334,2=270.000000
L 0.2305 3.1124499 0.2305 3.12855 1 P 0 ;0,1=334,2=270.000000
L 0.22585108 3.14306663 0.22843386 3.14536614 1 P 0 ;0,1=334,2=270.000000
L 0.22843386 3.14536614 0.22998346 3.14804961 1 P 0 ;0,1=334,2=270.000000
L 0.22998346 3.14804961 0.2305 3.15149961 1 P 0 ;0,1=334,2=270.000000
L 0.2305 3.15149961 0.22946693 3.1549503 1 P 0 ;0,1=334,2=270.000000
L 0.22946693 3.1549503 0.22740069 3.15763307 1 P 0 ;0,1=334,2=270.000000
L 0.22740069 3.15763307 0.22378386 3.15955 1 P 0 ;0,1=334,2=270.000000
L 0.22378386 3.15955 0.21965049 3.15993327 1 P 0 ;0,1=334,2=270.000000
L 0.21965049 3.15993327 0.21551713 3.15916673 1 P 0 ;0,1=334,2=270.000000
L 0.21551713 3.15916673 0.21293337 3.1572498 1 P 0 ;0,1=334,2=270.000000
L 0.21293337 3.1572498 0.21086713 3.15456634 1 P 0 ;0,1=334,2=270.000000
L 0.21086713 3.15456634 0.21035059 3.15188356 1 P 0 ;0,1=334,2=270.000000
L 0.21035059 3.15188356 0.21086713 3.1492001 1 P 0 ;0,1=334,2=270.000000
L 0.21086713 3.1492001 0.21293337 3.1457501 1 P 0 ;0,1=334,2=270.000000
L 0.21293337 3.1457501 0.1995 3.1468999 1 P 0 ;0,1=334,2=270.000000
L 0.1995 3.1468999 0.1995 3.1572498 1 P 0 ;0,1=334,2=270.000000
L 0.402 3.255 0.358 3.255 1 P 0 
L 0.402 3.165 0.402 3.255 1 P 0 
L 0.358 3.255 0.358 3.165 1 P 0 
L 0.358 3.165 0.402 3.165 1 P 0 
L 0.3905 3.05083317 0.3595 3.05083317 1 P 0 ;0,1=335,2=270.000000
L 0.3595 3.05083317 0.3595 3.06041654 1 P 0 ;0,1=335,2=270.000000
L 0.3595 3.06041654 0.36105069 3.06348327 1 P 0 ;0,1=335,2=270.000000
L 0.36105069 3.06348327 0.36311693 3.0654002 1 P 0 ;0,1=335,2=270.000000
L 0.36311693 3.0654002 0.3672503 3.06616673 1 P 0 ;0,1=335,2=270.000000
L 0.3672503 3.06616673 0.37138366 3.0654002 1 P 0 ;0,1=335,2=270.000000
L 0.37138366 3.0654002 0.37396644 3.0631 1 P 0 ;0,1=335,2=270.000000
L 0.37396644 3.0631 0.37551713 3.06041654 1 P 0 ;0,1=335,2=270.000000
L 0.37551713 3.06041654 0.37551713 3.05083317 1 P 0 ;0,1=335,2=270.000000
L 0.37551713 3.06041654 0.3905 3.06616673 1 P 0 ;0,1=335,2=270.000000
L 0.3905 3.0941 0.3595 3.0941 1 P 0 ;0,1=335,2=270.000000
L 0.3595 3.0941 0.38171673 3.07991624 1 P 0 ;0,1=335,2=270.000000
L 0.38171673 3.07991624 0.38171673 3.09908366 1 P 0 ;0,1=335,2=270.000000
L 0.36466654 3.11321644 0.36156722 3.11551663 1 P 0 ;0,1=335,2=270.000000
L 0.36156722 3.11551663 0.36001663 3.1182001 1 P 0 ;0,1=335,2=270.000000
L 0.36001663 3.1182001 0.3595 3.12126683 1 P 0 ;0,1=335,2=270.000000
L 0.3595 3.12126683 0.36053317 3.1251 1 P 0 ;0,1=335,2=270.000000
L 0.36053317 3.1251 0.36311693 3.12778346 1 P 0 ;0,1=335,2=270.000000
L 0.36311693 3.12778346 0.36621624 3.12855 1 P 0 ;0,1=335,2=270.000000
L 0.36621624 3.12855 0.36931742 3.12816673 1 P 0 ;0,1=335,2=270.000000
L 0.36931742 3.12816673 0.3719002 3.12663307 1 P 0 ;0,1=335,2=270.000000
L 0.3719002 3.12663307 0.37706673 3.11896663 1 P 0 ;0,1=335,2=270.000000
L 0.37706673 3.11896663 0.38068356 3.11551663 1 P 0 ;0,1=335,2=270.000000
L 0.38068356 3.11551663 0.38585108 3.11321644 1 P 0 ;0,1=335,2=270.000000
L 0.38585108 3.11321644 0.3905 3.1124499 1 P 0 ;0,1=335,2=270.000000
L 0.3905 3.1124499 0.3905 3.12855 1 P 0 ;0,1=335,2=270.000000
L 0.37758425 3.14421644 0.37396644 3.1468999 1 P 0 ;0,1=335,2=270.000000
L 0.37396644 3.1468999 0.3719002 3.1492001 1 P 0 ;0,1=335,2=270.000000
L 0.3719002 3.1492001 0.37086713 3.15226683 1 P 0 ;0,1=335,2=270.000000
L 0.37086713 3.15226683 0.3719002 3.1549503 1 P 0 ;0,1=335,2=270.000000
L 0.3719002 3.1549503 0.37396644 3.15686654 1 P 0 ;0,1=335,2=270.000000
L 0.37396644 3.15686654 0.37706673 3.1584002 1 P 0 ;0,1=335,2=270.000000
L 0.37706673 3.1584002 0.38068356 3.15878346 1 P 0 ;0,1=335,2=270.000000
L 0.38068356 3.15878346 0.38378386 3.1584002 1 P 0 ;0,1=335,2=270.000000
L 0.38378386 3.1584002 0.38688415 3.15686654 1 P 0 ;0,1=335,2=270.000000
L 0.38688415 3.15686654 0.38946693 3.15456634 1 P 0 ;0,1=335,2=270.000000
L 0.38946693 3.15456634 0.3905 3.15188356 1 P 0 ;0,1=335,2=270.000000
L 0.3905 3.15188356 0.38946693 3.14881683 1 P 0 ;0,1=335,2=270.000000
L 0.38946693 3.14881683 0.38636762 3.14613337 1 P 0 ;0,1=335,2=270.000000
L 0.38636762 3.14613337 0.38171673 3.1445997 1 P 0 ;0,1=335,2=270.000000
L 0.38171673 3.1445997 0.3765502 3.14421644 1 P 0 ;0,1=335,2=270.000000
L 0.3765502 3.14421644 0.36983406 3.14498287 1 P 0 ;0,1=335,2=270.000000
L 0.36983406 3.14498287 0.36621624 3.14613337 1 P 0 ;0,1=335,2=270.000000
L 0.36621624 3.14613337 0.3626003 3.14804961 1 P 0 ;0,1=335,2=270.000000
L 0.3626003 3.14804961 0.36001663 3.15073307 1 P 0 ;0,1=335,2=270.000000
L 0.36001663 3.15073307 0.3595 3.15341654 1 P 0 ;0,1=335,2=270.000000
L 0.3595 3.15341654 0.36053317 3.1561 1 P 0 ;0,1=335,2=270.000000
L 0.36053317 3.1561 0.36311693 3.15801703 1 P 0 ;0,1=335,2=270.000000
L 0.452 3.255 0.408 3.255 1 P 0 
L 0.452 3.165 0.452 3.255 1 P 0 
L 0.408 3.255 0.408 3.165 1 P 0 
L 0.408 3.165 0.452 3.165 1 P 0 
L 0.4855 3.05083317 0.4545 3.05083317 1 P 0 ;0,1=336,2=270.000000
L 0.4545 3.05083317 0.4545 3.06041654 1 P 0 ;0,1=336,2=270.000000
L 0.4545 3.06041654 0.45605069 3.06348327 1 P 0 ;0,1=336,2=270.000000
L 0.45605069 3.06348327 0.45811693 3.0654002 1 P 0 ;0,1=336,2=270.000000
L 0.45811693 3.0654002 0.4622503 3.06616673 1 P 0 ;0,1=336,2=270.000000
L 0.4622503 3.06616673 0.46638366 3.0654002 1 P 0 ;0,1=336,2=270.000000
L 0.46638366 3.0654002 0.46896644 3.0631 1 P 0 ;0,1=336,2=270.000000
L 0.46896644 3.0631 0.47051713 3.06041654 1 P 0 ;0,1=336,2=270.000000
L 0.47051713 3.06041654 0.47051713 3.05083317 1 P 0 ;0,1=336,2=270.000000
L 0.47051713 3.06041654 0.4855 3.06616673 1 P 0 ;0,1=336,2=270.000000
L 0.47930039 3.08106663 0.48291722 3.08336614 1 P 0 ;0,1=336,2=270.000000
L 0.48291722 3.08336614 0.48498346 3.08643287 1 P 0 ;0,1=336,2=270.000000
L 0.48498346 3.08643287 0.4855 3.08988356 1 P 0 ;0,1=336,2=270.000000
L 0.4855 3.08988356 0.48498346 3.0929503 1 P 0 ;0,1=336,2=270.000000
L 0.48498346 3.0929503 0.48240069 3.09601703 1 P 0 ;0,1=336,2=270.000000
L 0.48240069 3.09601703 0.47930039 3.09793327 1 P 0 ;0,1=336,2=270.000000
L 0.47930039 3.09793327 0.4762001 3.09831654 1 P 0 ;0,1=336,2=270.000000
L 0.4762001 3.09831654 0.47258425 3.09755 1 P 0 ;0,1=336,2=270.000000
L 0.47258425 3.09755 0.47000049 3.09486654 1 P 0 ;0,1=336,2=270.000000
L 0.47000049 3.09486654 0.46896644 3.09218307 1 P 0 ;0,1=336,2=270.000000
L 0.46896644 3.09218307 0.46896644 3.08873307 1 P 0 ;0,1=336,2=270.000000
L 0.46896644 3.09218307 0.46741683 3.09448327 1 P 0 ;0,1=336,2=270.000000
L 0.46741683 3.09448327 0.46483406 3.0964002 1 P 0 ;0,1=336,2=270.000000
L 0.46483406 3.0964002 0.46173376 3.09716673 1 P 0 ;0,1=336,2=270.000000
L 0.46173376 3.09716673 0.45863346 3.0964002 1 P 0 ;0,1=336,2=270.000000
L 0.45863346 3.0964002 0.45605069 3.09448327 1 P 0 ;0,1=336,2=270.000000
L 0.45605069 3.09448327 0.4545 3.09103327 1 P 0 ;0,1=336,2=270.000000
L 0.4545 3.09103327 0.45501663 3.08758337 1 P 0 ;0,1=336,2=270.000000
L 0.45501663 3.08758337 0.45708376 3.08413337 1 P 0 ;0,1=336,2=270.000000
L 0.48188415 3.11398287 0.48446693 3.11666634 1 P 0 ;0,1=336,2=270.000000
L 0.48446693 3.11666634 0.4855 3.11973307 1 P 0 ;0,1=336,2=270.000000
L 0.4855 3.11973307 0.48446693 3.1227998 1 P 0 ;0,1=336,2=270.000000
L 0.48446693 3.1227998 0.48136762 3.12548327 1 P 0 ;0,1=336,2=270.000000
L 0.48136762 3.12548327 0.47671673 3.1274002 1 P 0 ;0,1=336,2=270.000000
L 0.47671673 3.1274002 0.47206673 3.12816673 1 P 0 ;0,1=336,2=270.000000
L 0.47206673 3.12816673 0.46638366 3.12816673 1 P 0 ;0,1=336,2=270.000000
L 0.46638366 3.12816673 0.46173376 3.1274002 1 P 0 ;0,1=336,2=270.000000
L 0.46173376 3.1274002 0.4576003 3.12548327 1 P 0 ;0,1=336,2=270.000000
L 0.4576003 3.12548327 0.45553317 3.12318307 1 P 0 ;0,1=336,2=270.000000
L 0.45553317 3.12318307 0.4545 3.12049961 1 P 0 ;0,1=336,2=270.000000
L 0.4545 3.12049961 0.45553317 3.11743287 1 P 0 ;0,1=336,2=270.000000
L 0.45553317 3.11743287 0.4576003 3.11513337 1 P 0 ;0,1=336,2=270.000000
L 0.4576003 3.11513337 0.4606997 3.1135997 1 P 0 ;0,1=336,2=270.000000
L 0.4606997 3.1135997 0.46483406 3.11283317 1 P 0 ;0,1=336,2=270.000000
L 0.46483406 3.11283317 0.4684499 3.1135997 1 P 0 ;0,1=336,2=270.000000
L 0.4684499 3.1135997 0.47206673 3.11551663 1 P 0 ;0,1=336,2=270.000000
L 0.47206673 3.11551663 0.47413396 3.11781683 1 P 0 ;0,1=336,2=270.000000
L 0.47413396 3.11781683 0.47465049 3.12049961 1 P 0 ;0,1=336,2=270.000000
L 0.47465049 3.12049961 0.47361732 3.12356634 1 P 0 ;0,1=336,2=270.000000
L 0.47361732 3.12356634 0.47103366 3.12586654 1 P 0 ;0,1=336,2=270.000000
L 0.47103366 3.12586654 0.46638366 3.12816673 1 P 0 ;0,1=336,2=270.000000
L 0.4855 3.15149961 0.48498346 3.15418307 1 P 0 ;0,1=336,2=270.000000
L 0.48498346 3.15418307 0.48343386 3.1572498 1 P 0 ;0,1=336,2=270.000000
L 0.48343386 3.1572498 0.48085108 3.15916673 1 P 0 ;0,1=336,2=270.000000
L 0.48085108 3.15916673 0.47723327 3.15993327 1 P 0 ;0,1=336,2=270.000000
L 0.47723327 3.15993327 0.47361732 3.15916673 1 P 0 ;0,1=336,2=270.000000
L 0.47361732 3.15916673 0.47051713 3.15686654 1 P 0 ;0,1=336,2=270.000000
L 0.47051713 3.15686654 0.46896644 3.15341654 1 P 0 ;0,1=336,2=270.000000
L 0.46896644 3.15341654 0.46896644 3.14958337 1 P 0 ;0,1=336,2=270.000000
L 0.46896644 3.14958337 0.46793337 3.14728317 1 P 0 ;0,1=336,2=270.000000
L 0.46793337 3.14728317 0.46535059 3.14536614 1 P 0 ;0,1=336,2=270.000000
L 0.46535059 3.14536614 0.46173376 3.1445997 1 P 0 ;0,1=336,2=270.000000
L 0.46173376 3.1445997 0.45811693 3.1457501 1 P 0 ;0,1=336,2=270.000000
L 0.45811693 3.1457501 0.45553317 3.14843287 1 P 0 ;0,1=336,2=270.000000
L 0.45553317 3.14843287 0.4545 3.15149961 1 P 0 ;0,1=336,2=270.000000
L 0.4545 3.15149961 0.45553317 3.15456634 1 P 0 ;0,1=336,2=270.000000
L 0.45553317 3.15456634 0.45811693 3.1572498 1 P 0 ;0,1=336,2=270.000000
L 0.45811693 3.1572498 0.46173376 3.1584002 1 P 0 ;0,1=336,2=270.000000
L 0.46173376 3.1584002 0.46535059 3.15763307 1 P 0 ;0,1=336,2=270.000000
L 0.46535059 3.15763307 0.46793337 3.15571673 1 P 0 ;0,1=336,2=270.000000
L 0.46793337 3.15571673 0.46896644 3.15341654 1 P 0 ;0,1=336,2=270.000000
L 0.46896644 3.15341654 0.46896644 3.14958337 1 P 0 ;0,1=336,2=270.000000
L 0.46896644 3.14958337 0.47051713 3.14613337 1 P 0 ;0,1=336,2=270.000000
L 0.47051713 3.14613337 0.47361732 3.14383317 1 P 0 ;0,1=336,2=270.000000
L 0.47361732 3.14383317 0.47723327 3.14306663 1 P 0 ;0,1=336,2=270.000000
L 0.47723327 3.14306663 0.48085108 3.14383317 1 P 0 ;0,1=336,2=270.000000
L 0.48085108 3.14383317 0.48343386 3.1457501 1 P 0 ;0,1=336,2=270.000000
L 0.48343386 3.1457501 0.48498346 3.14881683 1 P 0 ;0,1=336,2=270.000000
L 0.48498346 3.14881683 0.4855 3.15149961 1 P 0 ;0,1=336,2=270.000000
L 0.202 3.255 0.158 3.255 1 P 0 
L 0.202 3.165 0.202 3.255 1 P 0 
L 0.158 3.255 0.158 3.165 1 P 0 
L 0.158 3.165 0.202 3.165 1 P 0 
L 0.1555 3.05083317 0.1245 3.05083317 1 P 0 ;0,1=337,2=270.000000
L 0.1245 3.05083317 0.1245 3.06041654 1 P 0 ;0,1=337,2=270.000000
L 0.1245 3.06041654 0.12605069 3.06348327 1 P 0 ;0,1=337,2=270.000000
L 0.12605069 3.06348327 0.12811693 3.0654002 1 P 0 ;0,1=337,2=270.000000
L 0.12811693 3.0654002 0.1322503 3.06616673 1 P 0 ;0,1=337,2=270.000000
L 0.1322503 3.06616673 0.13638366 3.0654002 1 P 0 ;0,1=337,2=270.000000
L 0.13638366 3.0654002 0.13896644 3.0631 1 P 0 ;0,1=337,2=270.000000
L 0.13896644 3.0631 0.14051713 3.06041654 1 P 0 ;0,1=337,2=270.000000
L 0.14051713 3.06041654 0.14051713 3.05083317 1 P 0 ;0,1=337,2=270.000000
L 0.14051713 3.06041654 0.1555 3.06616673 1 P 0 ;0,1=337,2=270.000000
L 0.14930039 3.08106663 0.15291722 3.08336614 1 P 0 ;0,1=337,2=270.000000
L 0.15291722 3.08336614 0.15498346 3.08643287 1 P 0 ;0,1=337,2=270.000000
L 0.15498346 3.08643287 0.1555 3.08988356 1 P 0 ;0,1=337,2=270.000000
L 0.1555 3.08988356 0.15498346 3.0929503 1 P 0 ;0,1=337,2=270.000000
L 0.15498346 3.0929503 0.15240069 3.09601703 1 P 0 ;0,1=337,2=270.000000
L 0.15240069 3.09601703 0.14930039 3.09793327 1 P 0 ;0,1=337,2=270.000000
L 0.14930039 3.09793327 0.1462001 3.09831654 1 P 0 ;0,1=337,2=270.000000
L 0.1462001 3.09831654 0.14258425 3.09755 1 P 0 ;0,1=337,2=270.000000
L 0.14258425 3.09755 0.14000049 3.09486654 1 P 0 ;0,1=337,2=270.000000
L 0.14000049 3.09486654 0.13896644 3.09218307 1 P 0 ;0,1=337,2=270.000000
L 0.13896644 3.09218307 0.13896644 3.08873307 1 P 0 ;0,1=337,2=270.000000
L 0.13896644 3.09218307 0.13741683 3.09448327 1 P 0 ;0,1=337,2=270.000000
L 0.13741683 3.09448327 0.13483406 3.0964002 1 P 0 ;0,1=337,2=270.000000
L 0.13483406 3.0964002 0.13173376 3.09716673 1 P 0 ;0,1=337,2=270.000000
L 0.13173376 3.09716673 0.12863346 3.0964002 1 P 0 ;0,1=337,2=270.000000
L 0.12863346 3.0964002 0.12605069 3.09448327 1 P 0 ;0,1=337,2=270.000000
L 0.12605069 3.09448327 0.1245 3.09103327 1 P 0 ;0,1=337,2=270.000000
L 0.1245 3.09103327 0.12501663 3.08758337 1 P 0 ;0,1=337,2=270.000000
L 0.12501663 3.08758337 0.12708376 3.08413337 1 P 0 ;0,1=337,2=270.000000
L 0.15188415 3.11398287 0.15446693 3.11666634 1 P 0 ;0,1=337,2=270.000000
L 0.15446693 3.11666634 0.1555 3.11973307 1 P 0 ;0,1=337,2=270.000000
L 0.1555 3.11973307 0.15446693 3.1227998 1 P 0 ;0,1=337,2=270.000000
L 0.15446693 3.1227998 0.15136762 3.12548327 1 P 0 ;0,1=337,2=270.000000
L 0.15136762 3.12548327 0.14671673 3.1274002 1 P 0 ;0,1=337,2=270.000000
L 0.14671673 3.1274002 0.14206673 3.12816673 1 P 0 ;0,1=337,2=270.000000
L 0.14206673 3.12816673 0.13638366 3.12816673 1 P 0 ;0,1=337,2=270.000000
L 0.13638366 3.12816673 0.13173376 3.1274002 1 P 0 ;0,1=337,2=270.000000
L 0.13173376 3.1274002 0.1276003 3.12548327 1 P 0 ;0,1=337,2=270.000000
L 0.1276003 3.12548327 0.12553317 3.12318307 1 P 0 ;0,1=337,2=270.000000
L 0.12553317 3.12318307 0.1245 3.12049961 1 P 0 ;0,1=337,2=270.000000
L 0.1245 3.12049961 0.12553317 3.11743287 1 P 0 ;0,1=337,2=270.000000
L 0.12553317 3.11743287 0.1276003 3.11513337 1 P 0 ;0,1=337,2=270.000000
L 0.1276003 3.11513337 0.1306997 3.1135997 1 P 0 ;0,1=337,2=270.000000
L 0.1306997 3.1135997 0.13483406 3.11283317 1 P 0 ;0,1=337,2=270.000000
L 0.13483406 3.11283317 0.1384499 3.1135997 1 P 0 ;0,1=337,2=270.000000
L 0.1384499 3.1135997 0.14206673 3.11551663 1 P 0 ;0,1=337,2=270.000000
L 0.14206673 3.11551663 0.14413396 3.11781683 1 P 0 ;0,1=337,2=270.000000
L 0.14413396 3.11781683 0.14465049 3.12049961 1 P 0 ;0,1=337,2=270.000000
L 0.14465049 3.12049961 0.14361732 3.12356634 1 P 0 ;0,1=337,2=270.000000
L 0.14361732 3.12356634 0.14103366 3.12586654 1 P 0 ;0,1=337,2=270.000000
L 0.14103366 3.12586654 0.13638366 3.12816673 1 P 0 ;0,1=337,2=270.000000
L 0.1555 3.15073307 0.14878386 3.15149961 1 P 0 ;0,1=337,2=270.000000
L 0.14878386 3.15149961 0.14310079 3.1526501 1 P 0 ;0,1=337,2=270.000000
L 0.14310079 3.1526501 0.13793337 3.15418307 1 P 0 ;0,1=337,2=270.000000
L 0.13793337 3.15418307 0.1322503 3.1561 1 P 0 ;0,1=337,2=270.000000
L 0.1322503 3.1561 0.1245 3.15916673 1 P 0 ;0,1=337,2=270.000000
L 0.1245 3.15916673 0.1245 3.14383317 1 P 0 ;0,1=337,2=270.000000
L 0.309 2.73008002 0.265 2.73008002 1 P 0 
L 0.309 2.64008002 0.309 2.73008002 1 P 0 
L 0.265 2.73008002 0.265 2.64008002 1 P 0 
L 0.265 2.64008002 0.309 2.64008002 1 P 0 
L 0.2855 2.77083317 0.2545 2.77083317 1 P 0 ;0,1=338,2=270.000000
L 0.2545 2.77083317 0.2545 2.78041654 1 P 0 ;0,1=338,2=270.000000
L 0.2545 2.78041654 0.25605069 2.78348327 1 P 0 ;0,1=338,2=270.000000
L 0.25605069 2.78348327 0.25811693 2.7854002 1 P 0 ;0,1=338,2=270.000000
L 0.25811693 2.7854002 0.2622503 2.78616673 1 P 0 ;0,1=338,2=270.000000
L 0.2622503 2.78616673 0.26638366 2.7854002 1 P 0 ;0,1=338,2=270.000000
L 0.26638366 2.7854002 0.26896644 2.7831 1 P 0 ;0,1=338,2=270.000000
L 0.26896644 2.7831 0.27051713 2.78041654 1 P 0 ;0,1=338,2=270.000000
L 0.27051713 2.78041654 0.27051713 2.77083317 1 P 0 ;0,1=338,2=270.000000
L 0.27051713 2.78041654 0.2855 2.78616673 1 P 0 ;0,1=338,2=270.000000
L 0.27930039 2.80106663 0.28291722 2.80336614 1 P 0 ;0,1=338,2=270.000000
L 0.28291722 2.80336614 0.28498346 2.80643287 1 P 0 ;0,1=338,2=270.000000
L 0.28498346 2.80643287 0.2855 2.80988356 1 P 0 ;0,1=338,2=270.000000
L 0.2855 2.80988356 0.28498346 2.8129503 1 P 0 ;0,1=338,2=270.000000
L 0.28498346 2.8129503 0.28240069 2.81601703 1 P 0 ;0,1=338,2=270.000000
L 0.28240069 2.81601703 0.27930039 2.81793327 1 P 0 ;0,1=338,2=270.000000
L 0.27930039 2.81793327 0.2762001 2.81831654 1 P 0 ;0,1=338,2=270.000000
L 0.2762001 2.81831654 0.27258425 2.81755 1 P 0 ;0,1=338,2=270.000000
L 0.27258425 2.81755 0.27000049 2.81486654 1 P 0 ;0,1=338,2=270.000000
L 0.27000049 2.81486654 0.26896644 2.81218307 1 P 0 ;0,1=338,2=270.000000
L 0.26896644 2.81218307 0.26896644 2.80873307 1 P 0 ;0,1=338,2=270.000000
L 0.26896644 2.81218307 0.26741683 2.81448327 1 P 0 ;0,1=338,2=270.000000
L 0.26741683 2.81448327 0.26483406 2.8164002 1 P 0 ;0,1=338,2=270.000000
L 0.26483406 2.8164002 0.26173376 2.81716673 1 P 0 ;0,1=338,2=270.000000
L 0.26173376 2.81716673 0.25863346 2.8164002 1 P 0 ;0,1=338,2=270.000000
L 0.25863346 2.8164002 0.25605069 2.81448327 1 P 0 ;0,1=338,2=270.000000
L 0.25605069 2.81448327 0.2545 2.81103327 1 P 0 ;0,1=338,2=270.000000
L 0.2545 2.81103327 0.25501663 2.80758337 1 P 0 ;0,1=338,2=270.000000
L 0.25501663 2.80758337 0.25708376 2.80413337 1 P 0 ;0,1=338,2=270.000000
L 0.2855 2.83973307 0.27878386 2.84049961 1 P 0 ;0,1=338,2=270.000000
L 0.27878386 2.84049961 0.27310079 2.8416501 1 P 0 ;0,1=338,2=270.000000
L 0.27310079 2.8416501 0.26793337 2.84318307 1 P 0 ;0,1=338,2=270.000000
L 0.26793337 2.84318307 0.2622503 2.8451 1 P 0 ;0,1=338,2=270.000000
L 0.2622503 2.8451 0.2545 2.84816673 1 P 0 ;0,1=338,2=270.000000
L 0.2545 2.84816673 0.2545 2.83283317 1 P 0 ;0,1=338,2=270.000000
L 0.27258425 2.86421644 0.26896644 2.8668999 1 P 0 ;0,1=338,2=270.000000
L 0.26896644 2.8668999 0.2669002 2.8692001 1 P 0 ;0,1=338,2=270.000000
L 0.2669002 2.8692001 0.26586713 2.87226683 1 P 0 ;0,1=338,2=270.000000
L 0.26586713 2.87226683 0.2669002 2.8749503 1 P 0 ;0,1=338,2=270.000000
L 0.2669002 2.8749503 0.26896644 2.87686654 1 P 0 ;0,1=338,2=270.000000
L 0.26896644 2.87686654 0.27206673 2.8784002 1 P 0 ;0,1=338,2=270.000000
L 0.27206673 2.8784002 0.27568356 2.87878346 1 P 0 ;0,1=338,2=270.000000
L 0.27568356 2.87878346 0.27878386 2.8784002 1 P 0 ;0,1=338,2=270.000000
L 0.27878386 2.8784002 0.28188415 2.87686654 1 P 0 ;0,1=338,2=270.000000
L 0.28188415 2.87686654 0.28446693 2.87456634 1 P 0 ;0,1=338,2=270.000000
L 0.28446693 2.87456634 0.2855 2.87188356 1 P 0 ;0,1=338,2=270.000000
L 0.2855 2.87188356 0.28446693 2.86881683 1 P 0 ;0,1=338,2=270.000000
L 0.28446693 2.86881683 0.28136762 2.86613337 1 P 0 ;0,1=338,2=270.000000
L 0.28136762 2.86613337 0.27671673 2.8645997 1 P 0 ;0,1=338,2=270.000000
L 0.27671673 2.8645997 0.2715502 2.86421644 1 P 0 ;0,1=338,2=270.000000
L 0.2715502 2.86421644 0.26483406 2.86498287 1 P 0 ;0,1=338,2=270.000000
L 0.26483406 2.86498287 0.26121624 2.86613337 1 P 0 ;0,1=338,2=270.000000
L 0.26121624 2.86613337 0.2576003 2.86804961 1 P 0 ;0,1=338,2=270.000000
L 0.2576003 2.86804961 0.25501663 2.87073307 1 P 0 ;0,1=338,2=270.000000
L 0.25501663 2.87073307 0.2545 2.87341654 1 P 0 ;0,1=338,2=270.000000
L 0.2545 2.87341654 0.25553317 2.8761 1 P 0 ;0,1=338,2=270.000000
L 0.25553317 2.8761 0.25811693 2.87801703 1 P 0 ;0,1=338,2=270.000000
L 0.219 2.73008002 0.175 2.73008002 1 P 0 
L 0.219 2.64008002 0.219 2.73008002 1 P 0 
L 0.175 2.73008002 0.175 2.64008002 1 P 0 
L 0.175 2.64008002 0.219 2.64008002 1 P 0 
L 0.1905 2.77083317 0.1595 2.77083317 1 P 0 ;0,1=339,2=270.000000
L 0.1595 2.77083317 0.1595 2.78041654 1 P 0 ;0,1=339,2=270.000000
L 0.1595 2.78041654 0.16105069 2.78348327 1 P 0 ;0,1=339,2=270.000000
L 0.16105069 2.78348327 0.16311693 2.7854002 1 P 0 ;0,1=339,2=270.000000
L 0.16311693 2.7854002 0.1672503 2.78616673 1 P 0 ;0,1=339,2=270.000000
L 0.1672503 2.78616673 0.17138366 2.7854002 1 P 0 ;0,1=339,2=270.000000
L 0.17138366 2.7854002 0.17396644 2.7831 1 P 0 ;0,1=339,2=270.000000
L 0.17396644 2.7831 0.17551713 2.78041654 1 P 0 ;0,1=339,2=270.000000
L 0.17551713 2.78041654 0.17551713 2.77083317 1 P 0 ;0,1=339,2=270.000000
L 0.17551713 2.78041654 0.1905 2.78616673 1 P 0 ;0,1=339,2=270.000000
L 0.18430039 2.80106663 0.18791722 2.80336614 1 P 0 ;0,1=339,2=270.000000
L 0.18791722 2.80336614 0.18998346 2.80643287 1 P 0 ;0,1=339,2=270.000000
L 0.18998346 2.80643287 0.1905 2.80988356 1 P 0 ;0,1=339,2=270.000000
L 0.1905 2.80988356 0.18998346 2.8129503 1 P 0 ;0,1=339,2=270.000000
L 0.18998346 2.8129503 0.18740069 2.81601703 1 P 0 ;0,1=339,2=270.000000
L 0.18740069 2.81601703 0.18430039 2.81793327 1 P 0 ;0,1=339,2=270.000000
L 0.18430039 2.81793327 0.1812001 2.81831654 1 P 0 ;0,1=339,2=270.000000
L 0.1812001 2.81831654 0.17758425 2.81755 1 P 0 ;0,1=339,2=270.000000
L 0.17758425 2.81755 0.17500049 2.81486654 1 P 0 ;0,1=339,2=270.000000
L 0.17500049 2.81486654 0.17396644 2.81218307 1 P 0 ;0,1=339,2=270.000000
L 0.17396644 2.81218307 0.17396644 2.80873307 1 P 0 ;0,1=339,2=270.000000
L 0.17396644 2.81218307 0.17241683 2.81448327 1 P 0 ;0,1=339,2=270.000000
L 0.17241683 2.81448327 0.16983406 2.8164002 1 P 0 ;0,1=339,2=270.000000
L 0.16983406 2.8164002 0.16673376 2.81716673 1 P 0 ;0,1=339,2=270.000000
L 0.16673376 2.81716673 0.16363346 2.8164002 1 P 0 ;0,1=339,2=270.000000
L 0.16363346 2.8164002 0.16105069 2.81448327 1 P 0 ;0,1=339,2=270.000000
L 0.16105069 2.81448327 0.1595 2.81103327 1 P 0 ;0,1=339,2=270.000000
L 0.1595 2.81103327 0.16001663 2.80758337 1 P 0 ;0,1=339,2=270.000000
L 0.16001663 2.80758337 0.16208376 2.80413337 1 P 0 ;0,1=339,2=270.000000
L 0.18688415 2.83398287 0.18946693 2.83666634 1 P 0 ;0,1=339,2=270.000000
L 0.18946693 2.83666634 0.1905 2.83973307 1 P 0 ;0,1=339,2=270.000000
L 0.1905 2.83973307 0.18946693 2.8427998 1 P 0 ;0,1=339,2=270.000000
L 0.18946693 2.8427998 0.18636762 2.84548327 1 P 0 ;0,1=339,2=270.000000
L 0.18636762 2.84548327 0.18171673 2.8474002 1 P 0 ;0,1=339,2=270.000000
L 0.18171673 2.8474002 0.17706673 2.84816673 1 P 0 ;0,1=339,2=270.000000
L 0.17706673 2.84816673 0.17138366 2.84816673 1 P 0 ;0,1=339,2=270.000000
L 0.17138366 2.84816673 0.16673376 2.8474002 1 P 0 ;0,1=339,2=270.000000
L 0.16673376 2.8474002 0.1626003 2.84548327 1 P 0 ;0,1=339,2=270.000000
L 0.1626003 2.84548327 0.16053317 2.84318307 1 P 0 ;0,1=339,2=270.000000
L 0.16053317 2.84318307 0.1595 2.84049961 1 P 0 ;0,1=339,2=270.000000
L 0.1595 2.84049961 0.16053317 2.83743287 1 P 0 ;0,1=339,2=270.000000
L 0.16053317 2.83743287 0.1626003 2.83513337 1 P 0 ;0,1=339,2=270.000000
L 0.1626003 2.83513337 0.1656997 2.8335997 1 P 0 ;0,1=339,2=270.000000
L 0.1656997 2.8335997 0.16983406 2.83283317 1 P 0 ;0,1=339,2=270.000000
L 0.16983406 2.83283317 0.1734499 2.8335997 1 P 0 ;0,1=339,2=270.000000
L 0.1734499 2.8335997 0.17706673 2.83551663 1 P 0 ;0,1=339,2=270.000000
L 0.17706673 2.83551663 0.17913396 2.83781683 1 P 0 ;0,1=339,2=270.000000
L 0.17913396 2.83781683 0.17965049 2.84049961 1 P 0 ;0,1=339,2=270.000000
L 0.17965049 2.84049961 0.17861732 2.84356634 1 P 0 ;0,1=339,2=270.000000
L 0.17861732 2.84356634 0.17603366 2.84586654 1 P 0 ;0,1=339,2=270.000000
L 0.17603366 2.84586654 0.17138366 2.84816673 1 P 0 ;0,1=339,2=270.000000
L 0.1905 2.87149961 0.1595 2.87149961 1 P 0 ;0,1=339,2=270.000000
L 0.1595 2.87149961 0.1656997 2.8668999 1 P 0 ;0,1=339,2=270.000000
L 0.1905 2.8668999 0.1905 2.87609931 1 P 0 ;0,1=339,2=270.000000
L 0.264 2.73008002 0.22 2.73008002 1 P 0 
L 0.264 2.64008002 0.264 2.73008002 1 P 0 
L 0.22 2.73008002 0.22 2.64008002 1 P 0 
L 0.22 2.64008002 0.264 2.64008002 1 P 0 
L 0.2455 2.77083317 0.2145 2.77083317 1 P 0 ;0,1=340,2=270.000000
L 0.2145 2.77083317 0.2145 2.78041654 1 P 0 ;0,1=340,2=270.000000
L 0.2145 2.78041654 0.21605069 2.78348327 1 P 0 ;0,1=340,2=270.000000
L 0.21605069 2.78348327 0.21811693 2.7854002 1 P 0 ;0,1=340,2=270.000000
L 0.21811693 2.7854002 0.2222503 2.78616673 1 P 0 ;0,1=340,2=270.000000
L 0.2222503 2.78616673 0.22638366 2.7854002 1 P 0 ;0,1=340,2=270.000000
L 0.22638366 2.7854002 0.22896644 2.7831 1 P 0 ;0,1=340,2=270.000000
L 0.22896644 2.7831 0.23051713 2.78041654 1 P 0 ;0,1=340,2=270.000000
L 0.23051713 2.78041654 0.23051713 2.77083317 1 P 0 ;0,1=340,2=270.000000
L 0.23051713 2.78041654 0.2455 2.78616673 1 P 0 ;0,1=340,2=270.000000
L 0.23930039 2.80106663 0.24291722 2.80336614 1 P 0 ;0,1=340,2=270.000000
L 0.24291722 2.80336614 0.24498346 2.80643287 1 P 0 ;0,1=340,2=270.000000
L 0.24498346 2.80643287 0.2455 2.80988356 1 P 0 ;0,1=340,2=270.000000
L 0.2455 2.80988356 0.24498346 2.8129503 1 P 0 ;0,1=340,2=270.000000
L 0.24498346 2.8129503 0.24240069 2.81601703 1 P 0 ;0,1=340,2=270.000000
L 0.24240069 2.81601703 0.23930039 2.81793327 1 P 0 ;0,1=340,2=270.000000
L 0.23930039 2.81793327 0.2362001 2.81831654 1 P 0 ;0,1=340,2=270.000000
L 0.2362001 2.81831654 0.23258425 2.81755 1 P 0 ;0,1=340,2=270.000000
L 0.23258425 2.81755 0.23000049 2.81486654 1 P 0 ;0,1=340,2=270.000000
L 0.23000049 2.81486654 0.22896644 2.81218307 1 P 0 ;0,1=340,2=270.000000
L 0.22896644 2.81218307 0.22896644 2.80873307 1 P 0 ;0,1=340,2=270.000000
L 0.22896644 2.81218307 0.22741683 2.81448327 1 P 0 ;0,1=340,2=270.000000
L 0.22741683 2.81448327 0.22483406 2.8164002 1 P 0 ;0,1=340,2=270.000000
L 0.22483406 2.8164002 0.22173376 2.81716673 1 P 0 ;0,1=340,2=270.000000
L 0.22173376 2.81716673 0.21863346 2.8164002 1 P 0 ;0,1=340,2=270.000000
L 0.21863346 2.8164002 0.21605069 2.81448327 1 P 0 ;0,1=340,2=270.000000
L 0.21605069 2.81448327 0.2145 2.81103327 1 P 0 ;0,1=340,2=270.000000
L 0.2145 2.81103327 0.21501663 2.80758337 1 P 0 ;0,1=340,2=270.000000
L 0.21501663 2.80758337 0.21708376 2.80413337 1 P 0 ;0,1=340,2=270.000000
L 0.2455 2.83973307 0.23878386 2.84049961 1 P 0 ;0,1=340,2=270.000000
L 0.23878386 2.84049961 0.23310079 2.8416501 1 P 0 ;0,1=340,2=270.000000
L 0.23310079 2.8416501 0.22793337 2.84318307 1 P 0 ;0,1=340,2=270.000000
L 0.22793337 2.84318307 0.2222503 2.8451 1 P 0 ;0,1=340,2=270.000000
L 0.2222503 2.8451 0.2145 2.84816673 1 P 0 ;0,1=340,2=270.000000
L 0.2145 2.84816673 0.2145 2.83283317 1 P 0 ;0,1=340,2=270.000000
L 0.2455 2.8761 0.2145 2.8761 1 P 0 ;0,1=340,2=270.000000
L 0.2145 2.8761 0.23671673 2.86191624 1 P 0 ;0,1=340,2=270.000000
L 0.23671673 2.86191624 0.23671673 2.88108366 1 P 0 ;0,1=340,2=270.000000
L 0.81146998 1.862 0.72146998 1.862 1 P 0 
L 0.72146998 1.862 0.72146998 1.818 1 P 0 
L 0.72146998 1.818 0.81146998 1.818 1 P 0 
L 0.81146998 1.818 0.81146998 1.862 1 P 0 
L 0.85083317 1.8245 0.85083317 1.8555 1 P 0 ;0,1=341,2=0.000000
L 0.85083317 1.8555 0.86041654 1.8555 1 P 0 ;0,1=341,2=0.000000
L 0.86041654 1.8555 0.86348327 1.85394931 1 P 0 ;0,1=341,2=0.000000
L 0.86348327 1.85394931 0.8654002 1.85188307 1 P 0 ;0,1=341,2=0.000000
L 0.8654002 1.85188307 0.86616673 1.8477497 1 P 0 ;0,1=341,2=0.000000
L 0.86616673 1.8477497 0.8654002 1.84361634 1 P 0 ;0,1=341,2=0.000000
L 0.8654002 1.84361634 0.8631 1.84103356 1 P 0 ;0,1=341,2=0.000000
L 0.8631 1.84103356 0.86041654 1.83948287 1 P 0 ;0,1=341,2=0.000000
L 0.86041654 1.83948287 0.85083317 1.83948287 1 P 0 ;0,1=341,2=0.000000
L 0.86041654 1.83948287 0.86616673 1.8245 1 P 0 ;0,1=341,2=0.000000
L 0.8941 1.8245 0.8941 1.8555 1 P 0 ;0,1=341,2=0.000000
L 0.8941 1.8555 0.87991624 1.83328327 1 P 0 ;0,1=341,2=0.000000
L 0.87991624 1.83328327 0.89908366 1.83328327 1 P 0 ;0,1=341,2=0.000000
L 0.91321644 1.85033346 0.91551663 1.85343278 1 P 0 ;0,1=341,2=0.000000
L 0.91551663 1.85343278 0.9182001 1.85498337 1 P 0 ;0,1=341,2=0.000000
L 0.9182001 1.85498337 0.92126683 1.8555 1 P 0 ;0,1=341,2=0.000000
L 0.92126683 1.8555 0.9251 1.85446683 1 P 0 ;0,1=341,2=0.000000
L 0.9251 1.85446683 0.92778346 1.85188307 1 P 0 ;0,1=341,2=0.000000
L 0.92778346 1.85188307 0.92855 1.84878376 1 P 0 ;0,1=341,2=0.000000
L 0.92855 1.84878376 0.92816673 1.84568258 1 P 0 ;0,1=341,2=0.000000
L 0.92816673 1.84568258 0.92663307 1.8430998 1 P 0 ;0,1=341,2=0.000000
L 0.92663307 1.8430998 0.91896663 1.83793327 1 P 0 ;0,1=341,2=0.000000
L 0.91896663 1.83793327 0.91551663 1.83431644 1 P 0 ;0,1=341,2=0.000000
L 0.91551663 1.83431644 0.91321644 1.82914892 1 P 0 ;0,1=341,2=0.000000
L 0.91321644 1.82914892 0.9124499 1.8245 1 P 0 ;0,1=341,2=0.000000
L 0.9124499 1.8245 0.92855 1.8245 1 P 0 ;0,1=341,2=0.000000
L 0.9561 1.8245 0.9561 1.8555 1 P 0 ;0,1=341,2=0.000000
L 0.9561 1.8555 0.94191624 1.83328327 1 P 0 ;0,1=341,2=0.000000
L 0.94191624 1.83328327 0.96108366 1.83328327 1 P 0 ;0,1=341,2=0.000000
L 0.81146998 1.772 0.72146998 1.772 1 P 0 
L 0.72146998 1.772 0.72146998 1.728 1 P 0 
L 0.72146998 1.728 0.81146998 1.728 1 P 0 
L 0.81146998 1.728 0.81146998 1.772 1 P 0 
L 0.85083317 1.7295 0.85083317 1.7605 1 P 0 ;0,1=342,2=0.000000
L 0.85083317 1.7605 0.86041654 1.7605 1 P 0 ;0,1=342,2=0.000000
L 0.86041654 1.7605 0.86348327 1.75894931 1 P 0 ;0,1=342,2=0.000000
L 0.86348327 1.75894931 0.8654002 1.75688307 1 P 0 ;0,1=342,2=0.000000
L 0.8654002 1.75688307 0.86616673 1.7527497 1 P 0 ;0,1=342,2=0.000000
L 0.86616673 1.7527497 0.8654002 1.74861634 1 P 0 ;0,1=342,2=0.000000
L 0.8654002 1.74861634 0.8631 1.74603356 1 P 0 ;0,1=342,2=0.000000
L 0.8631 1.74603356 0.86041654 1.74448287 1 P 0 ;0,1=342,2=0.000000
L 0.86041654 1.74448287 0.85083317 1.74448287 1 P 0 ;0,1=342,2=0.000000
L 0.86041654 1.74448287 0.86616673 1.7295 1 P 0 ;0,1=342,2=0.000000
L 0.88106663 1.73569961 0.88336614 1.73208278 1 P 0 ;0,1=342,2=0.000000
L 0.88336614 1.73208278 0.88643287 1.73001654 1 P 0 ;0,1=342,2=0.000000
L 0.88643287 1.73001654 0.88988356 1.7295 1 P 0 ;0,1=342,2=0.000000
L 0.88988356 1.7295 0.8929503 1.73001654 1 P 0 ;0,1=342,2=0.000000
L 0.8929503 1.73001654 0.89601703 1.73259931 1 P 0 ;0,1=342,2=0.000000
L 0.89601703 1.73259931 0.89793327 1.73569961 1 P 0 ;0,1=342,2=0.000000
L 0.89793327 1.73569961 0.89831654 1.7387999 1 P 0 ;0,1=342,2=0.000000
L 0.89831654 1.7387999 0.89755 1.74241575 1 P 0 ;0,1=342,2=0.000000
L 0.89755 1.74241575 0.89486654 1.74499951 1 P 0 ;0,1=342,2=0.000000
L 0.89486654 1.74499951 0.89218307 1.74603356 1 P 0 ;0,1=342,2=0.000000
L 0.89218307 1.74603356 0.88873307 1.74603356 1 P 0 ;0,1=342,2=0.000000
L 0.89218307 1.74603356 0.89448327 1.74758317 1 P 0 ;0,1=342,2=0.000000
L 0.89448327 1.74758317 0.8964002 1.75016594 1 P 0 ;0,1=342,2=0.000000
L 0.8964002 1.75016594 0.89716673 1.75326624 1 P 0 ;0,1=342,2=0.000000
L 0.89716673 1.75326624 0.8964002 1.75636654 1 P 0 ;0,1=342,2=0.000000
L 0.8964002 1.75636654 0.89448327 1.75894931 1 P 0 ;0,1=342,2=0.000000
L 0.89448327 1.75894931 0.89103327 1.7605 1 P 0 ;0,1=342,2=0.000000
L 0.89103327 1.7605 0.88758337 1.75998337 1 P 0 ;0,1=342,2=0.000000
L 0.88758337 1.75998337 0.88413337 1.75791624 1 P 0 ;0,1=342,2=0.000000
L 0.91398287 1.73311585 0.91666634 1.73053307 1 P 0 ;0,1=342,2=0.000000
L 0.91666634 1.73053307 0.91973307 1.7295 1 P 0 ;0,1=342,2=0.000000
L 0.91973307 1.7295 0.9227998 1.73053307 1 P 0 ;0,1=342,2=0.000000
L 0.9227998 1.73053307 0.92548327 1.73363238 1 P 0 ;0,1=342,2=0.000000
L 0.92548327 1.73363238 0.9274002 1.73828327 1 P 0 ;0,1=342,2=0.000000
L 0.9274002 1.73828327 0.92816673 1.74293327 1 P 0 ;0,1=342,2=0.000000
L 0.92816673 1.74293327 0.92816673 1.74861634 1 P 0 ;0,1=342,2=0.000000
L 0.92816673 1.74861634 0.9274002 1.75326624 1 P 0 ;0,1=342,2=0.000000
L 0.9274002 1.75326624 0.92548327 1.7573997 1 P 0 ;0,1=342,2=0.000000
L 0.92548327 1.7573997 0.92318307 1.75946683 1 P 0 ;0,1=342,2=0.000000
L 0.92318307 1.75946683 0.92049961 1.7605 1 P 0 ;0,1=342,2=0.000000
L 0.92049961 1.7605 0.91743287 1.75946683 1 P 0 ;0,1=342,2=0.000000
L 0.91743287 1.75946683 0.91513337 1.7573997 1 P 0 ;0,1=342,2=0.000000
L 0.91513337 1.7573997 0.9135997 1.7543003 1 P 0 ;0,1=342,2=0.000000
L 0.9135997 1.7543003 0.91283317 1.75016594 1 P 0 ;0,1=342,2=0.000000
L 0.91283317 1.75016594 0.9135997 1.7465501 1 P 0 ;0,1=342,2=0.000000
L 0.9135997 1.7465501 0.91551663 1.74293327 1 P 0 ;0,1=342,2=0.000000
L 0.91551663 1.74293327 0.91781683 1.74086604 1 P 0 ;0,1=342,2=0.000000
L 0.91781683 1.74086604 0.92049961 1.74034951 1 P 0 ;0,1=342,2=0.000000
L 0.92049961 1.74034951 0.92356634 1.74138268 1 P 0 ;0,1=342,2=0.000000
L 0.92356634 1.74138268 0.92586654 1.74396634 1 P 0 ;0,1=342,2=0.000000
L 0.92586654 1.74396634 0.92816673 1.74861634 1 P 0 ;0,1=342,2=0.000000
L 0.9561 1.7295 0.9561 1.7605 1 P 0 ;0,1=342,2=0.000000
L 0.9561 1.7605 0.94191624 1.73828327 1 P 0 ;0,1=342,2=0.000000
L 0.94191624 1.73828327 0.96108366 1.73828327 1 P 0 ;0,1=342,2=0.000000
L 0.81146998 1.817 0.72146998 1.817 1 P 0 
L 0.72146998 1.817 0.72146998 1.773 1 P 0 
L 0.72146998 1.773 0.81146998 1.773 1 P 0 
L 0.81146998 1.773 0.81146998 1.817 1 P 0 
L 0.85083317 1.7845 0.85083317 1.8155 1 P 0 ;0,1=343,2=0.000000
L 0.85083317 1.8155 0.86041654 1.8155 1 P 0 ;0,1=343,2=0.000000
L 0.86041654 1.8155 0.86348327 1.81394931 1 P 0 ;0,1=343,2=0.000000
L 0.86348327 1.81394931 0.8654002 1.81188307 1 P 0 ;0,1=343,2=0.000000
L 0.8654002 1.81188307 0.86616673 1.8077497 1 P 0 ;0,1=343,2=0.000000
L 0.86616673 1.8077497 0.8654002 1.80361634 1 P 0 ;0,1=343,2=0.000000
L 0.8654002 1.80361634 0.8631 1.80103356 1 P 0 ;0,1=343,2=0.000000
L 0.8631 1.80103356 0.86041654 1.79948287 1 P 0 ;0,1=343,2=0.000000
L 0.86041654 1.79948287 0.85083317 1.79948287 1 P 0 ;0,1=343,2=0.000000
L 0.86041654 1.79948287 0.86616673 1.7845 1 P 0 ;0,1=343,2=0.000000
L 0.8941 1.7845 0.8941 1.8155 1 P 0 ;0,1=343,2=0.000000
L 0.8941 1.8155 0.87991624 1.79328327 1 P 0 ;0,1=343,2=0.000000
L 0.87991624 1.79328327 0.89908366 1.79328327 1 P 0 ;0,1=343,2=0.000000
L 0.92049961 1.8155 0.91743287 1.81446683 1 P 0 ;0,1=343,2=0.000000
L 0.91743287 1.81446683 0.91513337 1.81188307 1 P 0 ;0,1=343,2=0.000000
L 0.91513337 1.81188307 0.9135997 1.80878376 1 P 0 ;0,1=343,2=0.000000
L 0.9135997 1.80878376 0.9124499 1.80464941 1 P 0 ;0,1=343,2=0.000000
L 0.9124499 1.80464941 0.91206663 1.79999951 1 P 0 ;0,1=343,2=0.000000
L 0.91206663 1.79999951 0.9124499 1.79534951 1 P 0 ;0,1=343,2=0.000000
L 0.9124499 1.79534951 0.9135997 1.79121614 1 P 0 ;0,1=343,2=0.000000
L 0.9135997 1.79121614 0.91513337 1.78811585 1 P 0 ;0,1=343,2=0.000000
L 0.91513337 1.78811585 0.91743287 1.78553307 1 P 0 ;0,1=343,2=0.000000
L 0.91743287 1.78553307 0.92049961 1.7845 1 P 0 ;0,1=343,2=0.000000
L 0.92049961 1.7845 0.92356634 1.78553307 1 P 0 ;0,1=343,2=0.000000
L 0.92356634 1.78553307 0.92586654 1.78811585 1 P 0 ;0,1=343,2=0.000000
L 0.92586654 1.78811585 0.9274002 1.79121614 1 P 0 ;0,1=343,2=0.000000
L 0.9274002 1.79121614 0.92855 1.79534951 1 P 0 ;0,1=343,2=0.000000
L 0.92855 1.79534951 0.92893327 1.79999951 1 P 0 ;0,1=343,2=0.000000
L 0.92893327 1.79999951 0.92855 1.80464941 1 P 0 ;0,1=343,2=0.000000
L 0.92855 1.80464941 0.9274002 1.80878376 1 P 0 ;0,1=343,2=0.000000
L 0.9274002 1.80878376 0.92586654 1.81188307 1 P 0 ;0,1=343,2=0.000000
L 0.92586654 1.81188307 0.92356634 1.81446683 1 P 0 ;0,1=343,2=0.000000
L 0.92356634 1.81446683 0.92049961 1.8155 1 P 0 ;0,1=343,2=0.000000
L 0.95149961 1.8155 0.94843287 1.81446683 1 P 0 ;0,1=343,2=0.000000
L 0.94843287 1.81446683 0.94613337 1.81188307 1 P 0 ;0,1=343,2=0.000000
L 0.94613337 1.81188307 0.9445997 1.80878376 1 P 0 ;0,1=343,2=0.000000
L 0.9445997 1.80878376 0.9434499 1.80464941 1 P 0 ;0,1=343,2=0.000000
L 0.9434499 1.80464941 0.94306663 1.79999951 1 P 0 ;0,1=343,2=0.000000
L 0.94306663 1.79999951 0.9434499 1.79534951 1 P 0 ;0,1=343,2=0.000000
L 0.9434499 1.79534951 0.9445997 1.79121614 1 P 0 ;0,1=343,2=0.000000
L 0.9445997 1.79121614 0.94613337 1.78811585 1 P 0 ;0,1=343,2=0.000000
L 0.94613337 1.78811585 0.94843287 1.78553307 1 P 0 ;0,1=343,2=0.000000
L 0.94843287 1.78553307 0.95149961 1.7845 1 P 0 ;0,1=343,2=0.000000
L 0.95149961 1.7845 0.95456634 1.78553307 1 P 0 ;0,1=343,2=0.000000
L 0.95456634 1.78553307 0.95686654 1.78811585 1 P 0 ;0,1=343,2=0.000000
L 0.95686654 1.78811585 0.9584002 1.79121614 1 P 0 ;0,1=343,2=0.000000
L 0.9584002 1.79121614 0.95955 1.79534951 1 P 0 ;0,1=343,2=0.000000
L 0.95955 1.79534951 0.95993327 1.79999951 1 P 0 ;0,1=343,2=0.000000
L 0.95993327 1.79999951 0.95955 1.80464941 1 P 0 ;0,1=343,2=0.000000
L 0.95955 1.80464941 0.9584002 1.80878376 1 P 0 ;0,1=343,2=0.000000
L 0.9584002 1.80878376 0.95686654 1.81188307 1 P 0 ;0,1=343,2=0.000000
L 0.95686654 1.81188307 0.95456634 1.81446683 1 P 0 ;0,1=343,2=0.000000
L 0.95456634 1.81446683 0.95149961 1.8155 1 P 0 ;0,1=343,2=0.000000
L 0.213 1.50298002 0.213 1.59298002 1 P 0 
L 0.213 1.59298002 0.169 1.59298002 1 P 0 
L 0.169 1.59298002 0.169 1.50298002 1 P 0 
L 0.169 1.50298002 0.213 1.50298002 1 P 0 
L 0.2105 1.60166654 0.1855 1.60166654 1 P 0 ;0,1=344,2=270.000000
L 0.1855 1.60166654 0.1855 1.60833327 1 P 0 ;0,1=344,2=270.000000
L 0.1855 1.60833327 0.18675059 1.61046663 1 P 0 ;0,1=344,2=270.000000
L 0.18675059 1.61046663 0.18841683 1.6118001 1 P 0 ;0,1=344,2=270.000000
L 0.18841683 1.6118001 0.1917502 1.61233337 1 P 0 ;0,1=344,2=270.000000
L 0.1917502 1.61233337 0.19508366 1.6118001 1 P 0 ;0,1=344,2=270.000000
L 0.19508366 1.6118001 0.19716654 1.6102 1 P 0 ;0,1=344,2=270.000000
L 0.19716654 1.6102 0.19841703 1.60833327 1 P 0 ;0,1=344,2=270.000000
L 0.19841703 1.60833327 0.19841703 1.60166654 1 P 0 ;0,1=344,2=270.000000
L 0.19841703 1.60833327 0.2105 1.61233337 1 P 0 ;0,1=344,2=270.000000
L 0.20550039 1.62313327 0.20841713 1.62473297 1 P 0 ;0,1=344,2=270.000000
L 0.20841713 1.62473297 0.21008346 1.62686634 1 P 0 ;0,1=344,2=270.000000
L 0.21008346 1.62686634 0.2105 1.62926683 1 P 0 ;0,1=344,2=270.000000
L 0.2105 1.62926683 0.21008346 1.6314002 1 P 0 ;0,1=344,2=270.000000
L 0.21008346 1.6314002 0.20800059 1.63353356 1 P 0 ;0,1=344,2=270.000000
L 0.20800059 1.63353356 0.20550039 1.63486663 1 P 0 ;0,1=344,2=270.000000
L 0.20550039 1.63486663 0.2030001 1.63513317 1 P 0 ;0,1=344,2=270.000000
L 0.2030001 1.63513317 0.20008406 1.6346 1 P 0 ;0,1=344,2=270.000000
L 0.20008406 1.6346 0.19800039 1.63273327 1 P 0 ;0,1=344,2=270.000000
L 0.19800039 1.63273327 0.19716654 1.63086644 1 P 0 ;0,1=344,2=270.000000
L 0.19716654 1.63086644 0.19716654 1.62846654 1 P 0 ;0,1=344,2=270.000000
L 0.19716654 1.63086644 0.19591673 1.63246663 1 P 0 ;0,1=344,2=270.000000
L 0.19591673 1.63246663 0.19383386 1.6338001 1 P 0 ;0,1=344,2=270.000000
L 0.19383386 1.6338001 0.19133366 1.63433337 1 P 0 ;0,1=344,2=270.000000
L 0.19133366 1.63433337 0.18883346 1.6338001 1 P 0 ;0,1=344,2=270.000000
L 0.18883346 1.6338001 0.18675059 1.63246663 1 P 0 ;0,1=344,2=270.000000
L 0.18675059 1.63246663 0.1855 1.63006663 1 P 0 ;0,1=344,2=270.000000
L 0.1855 1.63006663 0.18591663 1.62766663 1 P 0 ;0,1=344,2=270.000000
L 0.18591663 1.62766663 0.18758366 1.62526663 1 P 0 ;0,1=344,2=270.000000
L 0.2105 1.6509997 0.21008346 1.65286644 1 P 0 ;0,1=344,2=270.000000
L 0.21008346 1.65286644 0.20883376 1.6549998 1 P 0 ;0,1=344,2=270.000000
L 0.20883376 1.6549998 0.20675089 1.65633337 1 P 0 ;0,1=344,2=270.000000
L 0.20675089 1.65633337 0.20383327 1.65686663 1 P 0 ;0,1=344,2=270.000000
L 0.20383327 1.65686663 0.20091722 1.65633337 1 P 0 ;0,1=344,2=270.000000
L 0.20091722 1.65633337 0.19841703 1.65473327 1 P 0 ;0,1=344,2=270.000000
L 0.19841703 1.65473327 0.19716654 1.65233327 1 P 0 ;0,1=344,2=270.000000
L 0.19716654 1.65233327 0.19716654 1.64966663 1 P 0 ;0,1=344,2=270.000000
L 0.19716654 1.64966663 0.19633337 1.64806654 1 P 0 ;0,1=344,2=270.000000
L 0.19633337 1.64806654 0.19425049 1.64673297 1 P 0 ;0,1=344,2=270.000000
L 0.19425049 1.64673297 0.19133366 1.6461998 1 P 0 ;0,1=344,2=270.000000
L 0.19133366 1.6461998 0.18841683 1.6470001 1 P 0 ;0,1=344,2=270.000000
L 0.18841683 1.6470001 0.18633317 1.64886634 1 P 0 ;0,1=344,2=270.000000
L 0.18633317 1.64886634 0.1855 1.6509997 1 P 0 ;0,1=344,2=270.000000
L 0.1855 1.6509997 0.18633317 1.65313307 1 P 0 ;0,1=344,2=270.000000
L 0.18633317 1.65313307 0.18841683 1.6549998 1 P 0 ;0,1=344,2=270.000000
L 0.18841683 1.6549998 0.19133366 1.6558001 1 P 0 ;0,1=344,2=270.000000
L 0.19133366 1.6558001 0.19425049 1.65526644 1 P 0 ;0,1=344,2=270.000000
L 0.19425049 1.65526644 0.19633337 1.65393337 1 P 0 ;0,1=344,2=270.000000
L 0.19633337 1.65393337 0.19716654 1.65233327 1 P 0 ;0,1=344,2=270.000000
L 0.19716654 1.65233327 0.19716654 1.64966663 1 P 0 ;0,1=344,2=270.000000
L 0.19716654 1.64966663 0.19841703 1.64726663 1 P 0 ;0,1=344,2=270.000000
L 0.19841703 1.64726663 0.20091722 1.64566654 1 P 0 ;0,1=344,2=270.000000
L 0.20091722 1.64566654 0.20383327 1.64513327 1 P 0 ;0,1=344,2=270.000000
L 0.20383327 1.64513327 0.20675089 1.64566654 1 P 0 ;0,1=344,2=270.000000
L 0.20675089 1.64566654 0.20883376 1.6470001 1 P 0 ;0,1=344,2=270.000000
L 0.20883376 1.6470001 0.21008346 1.64913346 1 P 0 ;0,1=344,2=270.000000
L 0.21008346 1.64913346 0.2105 1.6509997 1 P 0 ;0,1=344,2=270.000000
L 0.20675089 1.66713327 0.20883376 1.66873297 1 P 0 ;0,1=344,2=270.000000
L 0.20883376 1.66873297 0.21008346 1.6705997 1 P 0 ;0,1=344,2=270.000000
L 0.21008346 1.6705997 0.2105 1.6729997 1 P 0 ;0,1=344,2=270.000000
L 0.2105 1.6729997 0.20966693 1.6754002 1 P 0 ;0,1=344,2=270.000000
L 0.20966693 1.6754002 0.20800059 1.67726644 1 P 0 ;0,1=344,2=270.000000
L 0.20800059 1.67726644 0.20508376 1.6786 1 P 0 ;0,1=344,2=270.000000
L 0.20508376 1.6786 0.20175039 1.67886663 1 P 0 ;0,1=344,2=270.000000
L 0.20175039 1.67886663 0.19841703 1.67833337 1 P 0 ;0,1=344,2=270.000000
L 0.19841703 1.67833337 0.19633337 1.6769998 1 P 0 ;0,1=344,2=270.000000
L 0.19633337 1.6769998 0.19466703 1.67513307 1 P 0 ;0,1=344,2=270.000000
L 0.19466703 1.67513307 0.19425049 1.67326683 1 P 0 ;0,1=344,2=270.000000
L 0.19425049 1.67326683 0.19466703 1.6714 1 P 0 ;0,1=344,2=270.000000
L 0.19466703 1.6714 0.19633337 1.6690001 1 P 0 ;0,1=344,2=270.000000
L 0.19633337 1.6690001 0.1855 1.6697999 1 P 0 ;0,1=344,2=270.000000
L 0.1855 1.6697999 0.1855 1.6769998 1 P 0 ;0,1=344,2=270.000000
L 0.258 1.50298002 0.258 1.59298002 1 P 0 
L 0.258 1.59298002 0.214 1.59298002 1 P 0 
L 0.214 1.59298002 0.214 1.50298002 1 P 0 
L 0.214 1.50298002 0.258 1.50298002 1 P 0 
L 0.2505 1.60166654 0.2255 1.60166654 1 P 0 ;0,1=345,2=270.000000
L 0.2255 1.60166654 0.2255 1.60833327 1 P 0 ;0,1=345,2=270.000000
L 0.2255 1.60833327 0.22675059 1.61046663 1 P 0 ;0,1=345,2=270.000000
L 0.22675059 1.61046663 0.22841683 1.6118001 1 P 0 ;0,1=345,2=270.000000
L 0.22841683 1.6118001 0.2317502 1.61233337 1 P 0 ;0,1=345,2=270.000000
L 0.2317502 1.61233337 0.23508366 1.6118001 1 P 0 ;0,1=345,2=270.000000
L 0.23508366 1.6118001 0.23716654 1.6102 1 P 0 ;0,1=345,2=270.000000
L 0.23716654 1.6102 0.23841703 1.60833327 1 P 0 ;0,1=345,2=270.000000
L 0.23841703 1.60833327 0.23841703 1.60166654 1 P 0 ;0,1=345,2=270.000000
L 0.23841703 1.60833327 0.2505 1.61233337 1 P 0 ;0,1=345,2=270.000000
L 0.2505 1.6289997 0.2255 1.6289997 1 P 0 ;0,1=345,2=270.000000
L 0.2255 1.6289997 0.2304997 1.6257999 1 P 0 ;0,1=345,2=270.000000
L 0.2505 1.6257999 0.2505 1.63219951 1 P 0 ;0,1=345,2=270.000000
L 0.22966663 1.64593317 0.22716713 1.64753327 1 P 0 ;0,1=345,2=270.000000
L 0.22716713 1.64753327 0.22591663 1.6494 1 P 0 ;0,1=345,2=270.000000
L 0.22591663 1.6494 0.2255 1.65153337 1 P 0 ;0,1=345,2=270.000000
L 0.2255 1.65153337 0.22633317 1.6542 1 P 0 ;0,1=345,2=270.000000
L 0.22633317 1.6542 0.22841683 1.65606673 1 P 0 ;0,1=345,2=270.000000
L 0.22841683 1.65606673 0.23091634 1.6566 1 P 0 ;0,1=345,2=270.000000
L 0.23091634 1.6566 0.23341732 1.65633337 1 P 0 ;0,1=345,2=270.000000
L 0.23341732 1.65633337 0.2355002 1.65526644 1 P 0 ;0,1=345,2=270.000000
L 0.2355002 1.65526644 0.23966673 1.64993327 1 P 0 ;0,1=345,2=270.000000
L 0.23966673 1.64993327 0.24258356 1.64753327 1 P 0 ;0,1=345,2=270.000000
L 0.24258356 1.64753327 0.24675089 1.64593317 1 P 0 ;0,1=345,2=270.000000
L 0.24675089 1.64593317 0.2505 1.6453999 1 P 0 ;0,1=345,2=270.000000
L 0.2505 1.6453999 0.2505 1.6566 1 P 0 ;0,1=345,2=270.000000
L 0.2505 1.6762 0.2255 1.6762 1 P 0 ;0,1=345,2=270.000000
L 0.2255 1.6762 0.24341673 1.66633297 1 P 0 ;0,1=345,2=270.000000
L 0.24341673 1.66633297 0.24341673 1.67966693 1 P 0 ;0,1=345,2=270.000000
L 0.303 1.50298002 0.303 1.59298002 1 P 0 
L 0.303 1.59298002 0.259 1.59298002 1 P 0 
L 0.259 1.59298002 0.259 1.50298002 1 P 0 
L 0.259 1.50298002 0.303 1.50298002 1 P 0 
L 0.2955 1.60166654 0.2705 1.60166654 1 P 0 ;0,1=346,2=270.000000
L 0.2705 1.60166654 0.2705 1.60833327 1 P 0 ;0,1=346,2=270.000000
L 0.2705 1.60833327 0.27175059 1.61046663 1 P 0 ;0,1=346,2=270.000000
L 0.27175059 1.61046663 0.27341683 1.6118001 1 P 0 ;0,1=346,2=270.000000
L 0.27341683 1.6118001 0.2767502 1.61233337 1 P 0 ;0,1=346,2=270.000000
L 0.2767502 1.61233337 0.28008366 1.6118001 1 P 0 ;0,1=346,2=270.000000
L 0.28008366 1.6118001 0.28216654 1.6102 1 P 0 ;0,1=346,2=270.000000
L 0.28216654 1.6102 0.28341703 1.60833327 1 P 0 ;0,1=346,2=270.000000
L 0.28341703 1.60833327 0.28341703 1.60166654 1 P 0 ;0,1=346,2=270.000000
L 0.28341703 1.60833327 0.2955 1.61233337 1 P 0 ;0,1=346,2=270.000000
L 0.27466663 1.62393317 0.27216713 1.62553327 1 P 0 ;0,1=346,2=270.000000
L 0.27216713 1.62553327 0.27091663 1.6274 1 P 0 ;0,1=346,2=270.000000
L 0.27091663 1.6274 0.2705 1.62953337 1 P 0 ;0,1=346,2=270.000000
L 0.2705 1.62953337 0.27133317 1.6322 1 P 0 ;0,1=346,2=270.000000
L 0.27133317 1.6322 0.27341683 1.63406673 1 P 0 ;0,1=346,2=270.000000
L 0.27341683 1.63406673 0.27591634 1.6346 1 P 0 ;0,1=346,2=270.000000
L 0.27591634 1.6346 0.27841732 1.63433337 1 P 0 ;0,1=346,2=270.000000
L 0.27841732 1.63433337 0.2805002 1.63326644 1 P 0 ;0,1=346,2=270.000000
L 0.2805002 1.63326644 0.28466673 1.62793327 1 P 0 ;0,1=346,2=270.000000
L 0.28466673 1.62793327 0.28758356 1.62553327 1 P 0 ;0,1=346,2=270.000000
L 0.28758356 1.62553327 0.29175089 1.62393317 1 P 0 ;0,1=346,2=270.000000
L 0.29175089 1.62393317 0.2955 1.6233999 1 P 0 ;0,1=346,2=270.000000
L 0.2955 1.6233999 0.2955 1.6346 1 P 0 ;0,1=346,2=270.000000
L 0.2955 1.65046654 0.29008376 1.6509997 1 P 0 ;0,1=346,2=270.000000
L 0.29008376 1.6509997 0.28550069 1.6518 1 P 0 ;0,1=346,2=270.000000
L 0.28550069 1.6518 0.28133337 1.65286644 1 P 0 ;0,1=346,2=270.000000
L 0.28133337 1.65286644 0.2767502 1.6542 1 P 0 ;0,1=346,2=270.000000
L 0.2767502 1.6542 0.2705 1.65633337 1 P 0 ;0,1=346,2=270.000000
L 0.2705 1.65633337 0.2705 1.64566654 1 P 0 ;0,1=346,2=270.000000
L 0.27466663 1.66793317 0.27216713 1.66953327 1 P 0 ;0,1=346,2=270.000000
L 0.27216713 1.66953327 0.27091663 1.6714 1 P 0 ;0,1=346,2=270.000000
L 0.27091663 1.6714 0.2705 1.67353337 1 P 0 ;0,1=346,2=270.000000
L 0.2705 1.67353337 0.27133317 1.6762 1 P 0 ;0,1=346,2=270.000000
L 0.27133317 1.6762 0.27341683 1.67806673 1 P 0 ;0,1=346,2=270.000000
L 0.27341683 1.67806673 0.27591634 1.6786 1 P 0 ;0,1=346,2=270.000000
L 0.27591634 1.6786 0.27841732 1.67833337 1 P 0 ;0,1=346,2=270.000000
L 0.27841732 1.67833337 0.2805002 1.67726644 1 P 0 ;0,1=346,2=270.000000
L 0.2805002 1.67726644 0.28466673 1.67193327 1 P 0 ;0,1=346,2=270.000000
L 0.28466673 1.67193327 0.28758356 1.66953327 1 P 0 ;0,1=346,2=270.000000
L 0.28758356 1.66953327 0.29175089 1.66793317 1 P 0 ;0,1=346,2=270.000000
L 0.29175089 1.66793317 0.2955 1.6673999 1 P 0 ;0,1=346,2=270.000000
L 0.2955 1.6673999 0.2955 1.6786 1 P 0 ;0,1=346,2=270.000000
L 0.845 1.072 0.755 1.072 1 P 0 
L 0.755 1.072 0.755 1.028 1 P 0 
L 0.755 1.028 0.845 1.028 1 P 0 
L 0.845 1.028 0.845 1.072 1 P 0 
L 0.88083317 1.0095 0.88083317 1.0405 1 P 0 ;0,1=347,2=0.000000
L 0.88083317 1.0405 0.89041654 1.0405 1 P 0 ;0,1=347,2=0.000000
L 0.89041654 1.0405 0.89348327 1.03894931 1 P 0 ;0,1=347,2=0.000000
L 0.89348327 1.03894931 0.8954002 1.03688307 1 P 0 ;0,1=347,2=0.000000
L 0.8954002 1.03688307 0.89616673 1.0327497 1 P 0 ;0,1=347,2=0.000000
L 0.89616673 1.0327497 0.8954002 1.02861634 1 P 0 ;0,1=347,2=0.000000
L 0.8954002 1.02861634 0.8931 1.02603356 1 P 0 ;0,1=347,2=0.000000
L 0.8931 1.02603356 0.89041654 1.02448287 1 P 0 ;0,1=347,2=0.000000
L 0.89041654 1.02448287 0.88083317 1.02448287 1 P 0 ;0,1=347,2=0.000000
L 0.89041654 1.02448287 0.89616673 1.0095 1 P 0 ;0,1=347,2=0.000000
L 0.91106663 1.01569961 0.91336614 1.01208278 1 P 0 ;0,1=347,2=0.000000
L 0.91336614 1.01208278 0.91643287 1.01001654 1 P 0 ;0,1=347,2=0.000000
L 0.91643287 1.01001654 0.91988356 1.0095 1 P 0 ;0,1=347,2=0.000000
L 0.91988356 1.0095 0.9229503 1.01001654 1 P 0 ;0,1=347,2=0.000000
L 0.9229503 1.01001654 0.92601703 1.01259931 1 P 0 ;0,1=347,2=0.000000
L 0.92601703 1.01259931 0.92793327 1.01569961 1 P 0 ;0,1=347,2=0.000000
L 0.92793327 1.01569961 0.92831654 1.0187999 1 P 0 ;0,1=347,2=0.000000
L 0.92831654 1.0187999 0.92755 1.02241575 1 P 0 ;0,1=347,2=0.000000
L 0.92755 1.02241575 0.92486654 1.02499951 1 P 0 ;0,1=347,2=0.000000
L 0.92486654 1.02499951 0.92218307 1.02603356 1 P 0 ;0,1=347,2=0.000000
L 0.92218307 1.02603356 0.91873307 1.02603356 1 P 0 ;0,1=347,2=0.000000
L 0.92218307 1.02603356 0.92448327 1.02758317 1 P 0 ;0,1=347,2=0.000000
L 0.92448327 1.02758317 0.9264002 1.03016594 1 P 0 ;0,1=347,2=0.000000
L 0.9264002 1.03016594 0.92716673 1.03326624 1 P 0 ;0,1=347,2=0.000000
L 0.92716673 1.03326624 0.9264002 1.03636654 1 P 0 ;0,1=347,2=0.000000
L 0.9264002 1.03636654 0.92448327 1.03894931 1 P 0 ;0,1=347,2=0.000000
L 0.92448327 1.03894931 0.92103327 1.0405 1 P 0 ;0,1=347,2=0.000000
L 0.92103327 1.0405 0.91758337 1.03998337 1 P 0 ;0,1=347,2=0.000000
L 0.91758337 1.03998337 0.91413337 1.03791624 1 P 0 ;0,1=347,2=0.000000
L 0.95049961 1.0095 0.95318307 1.01001654 1 P 0 ;0,1=347,2=0.000000
L 0.95318307 1.01001654 0.9562498 1.01156614 1 P 0 ;0,1=347,2=0.000000
L 0.9562498 1.01156614 0.95816673 1.01414892 1 P 0 ;0,1=347,2=0.000000
L 0.95816673 1.01414892 0.95893327 1.01776673 1 P 0 ;0,1=347,2=0.000000
L 0.95893327 1.01776673 0.95816673 1.02138268 1 P 0 ;0,1=347,2=0.000000
L 0.95816673 1.02138268 0.95586654 1.02448287 1 P 0 ;0,1=347,2=0.000000
L 0.95586654 1.02448287 0.95241654 1.02603356 1 P 0 ;0,1=347,2=0.000000
L 0.95241654 1.02603356 0.94858337 1.02603356 1 P 0 ;0,1=347,2=0.000000
L 0.94858337 1.02603356 0.94628317 1.02706663 1 P 0 ;0,1=347,2=0.000000
L 0.94628317 1.02706663 0.94436614 1.02964941 1 P 0 ;0,1=347,2=0.000000
L 0.94436614 1.02964941 0.9435997 1.03326624 1 P 0 ;0,1=347,2=0.000000
L 0.9435997 1.03326624 0.9447501 1.03688307 1 P 0 ;0,1=347,2=0.000000
L 0.9447501 1.03688307 0.94743287 1.03946683 1 P 0 ;0,1=347,2=0.000000
L 0.94743287 1.03946683 0.95049961 1.0405 1 P 0 ;0,1=347,2=0.000000
L 0.95049961 1.0405 0.95356634 1.03946683 1 P 0 ;0,1=347,2=0.000000
L 0.95356634 1.03946683 0.9562498 1.03688307 1 P 0 ;0,1=347,2=0.000000
L 0.9562498 1.03688307 0.9574002 1.03326624 1 P 0 ;0,1=347,2=0.000000
L 0.9574002 1.03326624 0.95663307 1.02964941 1 P 0 ;0,1=347,2=0.000000
L 0.95663307 1.02964941 0.95471673 1.02706663 1 P 0 ;0,1=347,2=0.000000
L 0.95471673 1.02706663 0.95241654 1.02603356 1 P 0 ;0,1=347,2=0.000000
L 0.95241654 1.02603356 0.94858337 1.02603356 1 P 0 ;0,1=347,2=0.000000
L 0.94858337 1.02603356 0.94513337 1.02448287 1 P 0 ;0,1=347,2=0.000000
L 0.94513337 1.02448287 0.94283317 1.02138268 1 P 0 ;0,1=347,2=0.000000
L 0.94283317 1.02138268 0.94206663 1.01776673 1 P 0 ;0,1=347,2=0.000000
L 0.94206663 1.01776673 0.94283317 1.01414892 1 P 0 ;0,1=347,2=0.000000
L 0.94283317 1.01414892 0.9447501 1.01156614 1 P 0 ;0,1=347,2=0.000000
L 0.9447501 1.01156614 0.94781683 1.01001654 1 P 0 ;0,1=347,2=0.000000
L 0.94781683 1.01001654 0.95049961 1.0095 1 P 0 ;0,1=347,2=0.000000
L 0.98149961 1.0095 0.98418307 1.01001654 1 P 0 ;0,1=347,2=0.000000
L 0.98418307 1.01001654 0.9872498 1.01156614 1 P 0 ;0,1=347,2=0.000000
L 0.9872498 1.01156614 0.98916673 1.01414892 1 P 0 ;0,1=347,2=0.000000
L 0.98916673 1.01414892 0.98993327 1.01776673 1 P 0 ;0,1=347,2=0.000000
L 0.98993327 1.01776673 0.98916673 1.02138268 1 P 0 ;0,1=347,2=0.000000
L 0.98916673 1.02138268 0.98686654 1.02448287 1 P 0 ;0,1=347,2=0.000000
L 0.98686654 1.02448287 0.98341654 1.02603356 1 P 0 ;0,1=347,2=0.000000
L 0.98341654 1.02603356 0.97958337 1.02603356 1 P 0 ;0,1=347,2=0.000000
L 0.97958337 1.02603356 0.97728317 1.02706663 1 P 0 ;0,1=347,2=0.000000
L 0.97728317 1.02706663 0.97536614 1.02964941 1 P 0 ;0,1=347,2=0.000000
L 0.97536614 1.02964941 0.9745997 1.03326624 1 P 0 ;0,1=347,2=0.000000
L 0.9745997 1.03326624 0.9757501 1.03688307 1 P 0 ;0,1=347,2=0.000000
L 0.9757501 1.03688307 0.97843287 1.03946683 1 P 0 ;0,1=347,2=0.000000
L 0.97843287 1.03946683 0.98149961 1.0405 1 P 0 ;0,1=347,2=0.000000
L 0.98149961 1.0405 0.98456634 1.03946683 1 P 0 ;0,1=347,2=0.000000
L 0.98456634 1.03946683 0.9872498 1.03688307 1 P 0 ;0,1=347,2=0.000000
L 0.9872498 1.03688307 0.9884002 1.03326624 1 P 0 ;0,1=347,2=0.000000
L 0.9884002 1.03326624 0.98763307 1.02964941 1 P 0 ;0,1=347,2=0.000000
L 0.98763307 1.02964941 0.98571673 1.02706663 1 P 0 ;0,1=347,2=0.000000
L 0.98571673 1.02706663 0.98341654 1.02603356 1 P 0 ;0,1=347,2=0.000000
L 0.98341654 1.02603356 0.97958337 1.02603356 1 P 0 ;0,1=347,2=0.000000
L 0.97958337 1.02603356 0.97613337 1.02448287 1 P 0 ;0,1=347,2=0.000000
L 0.97613337 1.02448287 0.97383317 1.02138268 1 P 0 ;0,1=347,2=0.000000
L 0.97383317 1.02138268 0.97306663 1.01776673 1 P 0 ;0,1=347,2=0.000000
L 0.97306663 1.01776673 0.97383317 1.01414892 1 P 0 ;0,1=347,2=0.000000
L 0.97383317 1.01414892 0.9757501 1.01156614 1 P 0 ;0,1=347,2=0.000000
L 0.9757501 1.01156614 0.97881683 1.01001654 1 P 0 ;0,1=347,2=0.000000
L 0.97881683 1.01001654 0.98149961 1.0095 1 P 0 ;0,1=347,2=0.000000
L 0.845 1.122 0.755 1.122 1 P 0 
L 0.755 1.122 0.755 1.078 1 P 0 
L 0.755 1.078 0.845 1.078 1 P 0 
L 0.845 1.078 0.845 1.122 1 P 0 
L 0.85583317 1.0645 0.85583317 1.0955 1 P 0 ;0,1=348,2=0.000000
L 0.85583317 1.0955 0.86541654 1.0955 1 P 0 ;0,1=348,2=0.000000
L 0.86541654 1.0955 0.86848327 1.09394931 1 P 0 ;0,1=348,2=0.000000
L 0.86848327 1.09394931 0.8704002 1.09188307 1 P 0 ;0,1=348,2=0.000000
L 0.8704002 1.09188307 0.87116673 1.0877497 1 P 0 ;0,1=348,2=0.000000
L 0.87116673 1.0877497 0.8704002 1.08361634 1 P 0 ;0,1=348,2=0.000000
L 0.8704002 1.08361634 0.8681 1.08103356 1 P 0 ;0,1=348,2=0.000000
L 0.8681 1.08103356 0.86541654 1.07948287 1 P 0 ;0,1=348,2=0.000000
L 0.86541654 1.07948287 0.85583317 1.07948287 1 P 0 ;0,1=348,2=0.000000
L 0.86541654 1.07948287 0.87116673 1.0645 1 P 0 ;0,1=348,2=0.000000
L 0.88721644 1.09033346 0.88951663 1.09343278 1 P 0 ;0,1=348,2=0.000000
L 0.88951663 1.09343278 0.8922001 1.09498337 1 P 0 ;0,1=348,2=0.000000
L 0.8922001 1.09498337 0.89526683 1.0955 1 P 0 ;0,1=348,2=0.000000
L 0.89526683 1.0955 0.8991 1.09446683 1 P 0 ;0,1=348,2=0.000000
L 0.8991 1.09446683 0.90178346 1.09188307 1 P 0 ;0,1=348,2=0.000000
L 0.90178346 1.09188307 0.90255 1.08878376 1 P 0 ;0,1=348,2=0.000000
L 0.90255 1.08878376 0.90216673 1.08568258 1 P 0 ;0,1=348,2=0.000000
L 0.90216673 1.08568258 0.90063307 1.0830998 1 P 0 ;0,1=348,2=0.000000
L 0.90063307 1.0830998 0.89296663 1.07793327 1 P 0 ;0,1=348,2=0.000000
L 0.89296663 1.07793327 0.88951663 1.07431644 1 P 0 ;0,1=348,2=0.000000
L 0.88951663 1.07431644 0.88721644 1.06914892 1 P 0 ;0,1=348,2=0.000000
L 0.88721644 1.06914892 0.8864499 1.0645 1 P 0 ;0,1=348,2=0.000000
L 0.8864499 1.0645 0.90255 1.0645 1 P 0 ;0,1=348,2=0.000000
L 0.92473307 1.0645 0.92549961 1.07121614 1 P 0 ;0,1=348,2=0.000000
L 0.92549961 1.07121614 0.9266501 1.07689921 1 P 0 ;0,1=348,2=0.000000
L 0.9266501 1.07689921 0.92818307 1.08206663 1 P 0 ;0,1=348,2=0.000000
L 0.92818307 1.08206663 0.9301 1.0877497 1 P 0 ;0,1=348,2=0.000000
L 0.9301 1.0877497 0.93316673 1.0955 1 P 0 ;0,1=348,2=0.000000
L 0.93316673 1.0955 0.91783317 1.0955 1 P 0 ;0,1=348,2=0.000000
L 0.94806663 1.07069961 0.95036614 1.06708278 1 P 0 ;0,1=348,2=0.000000
L 0.95036614 1.06708278 0.95343287 1.06501654 1 P 0 ;0,1=348,2=0.000000
L 0.95343287 1.06501654 0.95688356 1.0645 1 P 0 ;0,1=348,2=0.000000
L 0.95688356 1.0645 0.9599503 1.06501654 1 P 0 ;0,1=348,2=0.000000
L 0.9599503 1.06501654 0.96301703 1.06759931 1 P 0 ;0,1=348,2=0.000000
L 0.96301703 1.06759931 0.96493327 1.07069961 1 P 0 ;0,1=348,2=0.000000
L 0.96493327 1.07069961 0.96531654 1.0737999 1 P 0 ;0,1=348,2=0.000000
L 0.96531654 1.0737999 0.96455 1.07741575 1 P 0 ;0,1=348,2=0.000000
L 0.96455 1.07741575 0.96186654 1.07999951 1 P 0 ;0,1=348,2=0.000000
L 0.96186654 1.07999951 0.95918307 1.08103356 1 P 0 ;0,1=348,2=0.000000
L 0.95918307 1.08103356 0.95573307 1.08103356 1 P 0 ;0,1=348,2=0.000000
L 0.95918307 1.08103356 0.96148327 1.08258317 1 P 0 ;0,1=348,2=0.000000
L 0.96148327 1.08258317 0.9634002 1.08516594 1 P 0 ;0,1=348,2=0.000000
L 0.9634002 1.08516594 0.96416673 1.08826624 1 P 0 ;0,1=348,2=0.000000
L 0.96416673 1.08826624 0.9634002 1.09136654 1 P 0 ;0,1=348,2=0.000000
L 0.9634002 1.09136654 0.96148327 1.09394931 1 P 0 ;0,1=348,2=0.000000
L 0.96148327 1.09394931 0.95803327 1.0955 1 P 0 ;0,1=348,2=0.000000
L 0.95803327 1.0955 0.95458337 1.09498337 1 P 0 ;0,1=348,2=0.000000
L 0.95458337 1.09498337 0.95113337 1.09291624 1 P 0 ;0,1=348,2=0.000000
L 0.845 1.172 0.755 1.172 1 P 0 
L 0.755 1.172 0.755 1.128 1 P 0 
L 0.755 1.128 0.845 1.128 1 P 0 
L 0.845 1.128 0.845 1.172 1 P 0 
L 0.85583317 1.1145 0.85583317 1.1455 1 P 0 ;0,1=349,2=0.000000
L 0.85583317 1.1455 0.86541654 1.1455 1 P 0 ;0,1=349,2=0.000000
L 0.86541654 1.1455 0.86848327 1.14394931 1 P 0 ;0,1=349,2=0.000000
L 0.86848327 1.14394931 0.8704002 1.14188307 1 P 0 ;0,1=349,2=0.000000
L 0.8704002 1.14188307 0.87116673 1.1377497 1 P 0 ;0,1=349,2=0.000000
L 0.87116673 1.1377497 0.8704002 1.13361634 1 P 0 ;0,1=349,2=0.000000
L 0.8704002 1.13361634 0.8681 1.13103356 1 P 0 ;0,1=349,2=0.000000
L 0.8681 1.13103356 0.86541654 1.12948287 1 P 0 ;0,1=349,2=0.000000
L 0.86541654 1.12948287 0.85583317 1.12948287 1 P 0 ;0,1=349,2=0.000000
L 0.86541654 1.12948287 0.87116673 1.1145 1 P 0 ;0,1=349,2=0.000000
L 0.88606663 1.12069961 0.88836614 1.11708278 1 P 0 ;0,1=349,2=0.000000
L 0.88836614 1.11708278 0.89143287 1.11501654 1 P 0 ;0,1=349,2=0.000000
L 0.89143287 1.11501654 0.89488356 1.1145 1 P 0 ;0,1=349,2=0.000000
L 0.89488356 1.1145 0.8979503 1.11501654 1 P 0 ;0,1=349,2=0.000000
L 0.8979503 1.11501654 0.90101703 1.11759931 1 P 0 ;0,1=349,2=0.000000
L 0.90101703 1.11759931 0.90293327 1.12069961 1 P 0 ;0,1=349,2=0.000000
L 0.90293327 1.12069961 0.90331654 1.1237999 1 P 0 ;0,1=349,2=0.000000
L 0.90331654 1.1237999 0.90255 1.12741575 1 P 0 ;0,1=349,2=0.000000
L 0.90255 1.12741575 0.89986654 1.12999951 1 P 0 ;0,1=349,2=0.000000
L 0.89986654 1.12999951 0.89718307 1.13103356 1 P 0 ;0,1=349,2=0.000000
L 0.89718307 1.13103356 0.89373307 1.13103356 1 P 0 ;0,1=349,2=0.000000
L 0.89718307 1.13103356 0.89948327 1.13258317 1 P 0 ;0,1=349,2=0.000000
L 0.89948327 1.13258317 0.9014002 1.13516594 1 P 0 ;0,1=349,2=0.000000
L 0.9014002 1.13516594 0.90216673 1.13826624 1 P 0 ;0,1=349,2=0.000000
L 0.90216673 1.13826624 0.9014002 1.14136654 1 P 0 ;0,1=349,2=0.000000
L 0.9014002 1.14136654 0.89948327 1.14394931 1 P 0 ;0,1=349,2=0.000000
L 0.89948327 1.14394931 0.89603327 1.1455 1 P 0 ;0,1=349,2=0.000000
L 0.89603327 1.1455 0.89258337 1.14498337 1 P 0 ;0,1=349,2=0.000000
L 0.89258337 1.14498337 0.88913337 1.14291624 1 P 0 ;0,1=349,2=0.000000
L 0.92473307 1.1145 0.92549961 1.12121614 1 P 0 ;0,1=349,2=0.000000
L 0.92549961 1.12121614 0.9266501 1.12689921 1 P 0 ;0,1=349,2=0.000000
L 0.9266501 1.12689921 0.92818307 1.13206663 1 P 0 ;0,1=349,2=0.000000
L 0.92818307 1.13206663 0.9301 1.1377497 1 P 0 ;0,1=349,2=0.000000
L 0.9301 1.1377497 0.93316673 1.1455 1 P 0 ;0,1=349,2=0.000000
L 0.93316673 1.1455 0.91783317 1.1455 1 P 0 ;0,1=349,2=0.000000
L 0.94806663 1.12069961 0.95036614 1.11708278 1 P 0 ;0,1=349,2=0.000000
L 0.95036614 1.11708278 0.95343287 1.11501654 1 P 0 ;0,1=349,2=0.000000
L 0.95343287 1.11501654 0.95688356 1.1145 1 P 0 ;0,1=349,2=0.000000
L 0.95688356 1.1145 0.9599503 1.11501654 1 P 0 ;0,1=349,2=0.000000
L 0.9599503 1.11501654 0.96301703 1.11759931 1 P 0 ;0,1=349,2=0.000000
L 0.96301703 1.11759931 0.96493327 1.12069961 1 P 0 ;0,1=349,2=0.000000
L 0.96493327 1.12069961 0.96531654 1.1237999 1 P 0 ;0,1=349,2=0.000000
L 0.96531654 1.1237999 0.96455 1.12741575 1 P 0 ;0,1=349,2=0.000000
L 0.96455 1.12741575 0.96186654 1.12999951 1 P 0 ;0,1=349,2=0.000000
L 0.96186654 1.12999951 0.95918307 1.13103356 1 P 0 ;0,1=349,2=0.000000
L 0.95918307 1.13103356 0.95573307 1.13103356 1 P 0 ;0,1=349,2=0.000000
L 0.95918307 1.13103356 0.96148327 1.13258317 1 P 0 ;0,1=349,2=0.000000
L 0.96148327 1.13258317 0.9634002 1.13516594 1 P 0 ;0,1=349,2=0.000000
L 0.9634002 1.13516594 0.96416673 1.13826624 1 P 0 ;0,1=349,2=0.000000
L 0.96416673 1.13826624 0.9634002 1.14136654 1 P 0 ;0,1=349,2=0.000000
L 0.9634002 1.14136654 0.96148327 1.14394931 1 P 0 ;0,1=349,2=0.000000
L 0.96148327 1.14394931 0.95803327 1.1455 1 P 0 ;0,1=349,2=0.000000
L 0.95803327 1.1455 0.95458337 1.14498337 1 P 0 ;0,1=349,2=0.000000
L 0.95458337 1.14498337 0.95113337 1.14291624 1 P 0 ;0,1=349,2=0.000000
L 5.89 1.003 5.98 1.003 1 P 0 
L 5.98 1.003 5.98 1.047 1 P 0 
L 5.98 1.047 5.89 1.047 1 P 0 
L 5.89 1.047 5.89 1.003 1 P 0 
L 5.88133317 0.8995 5.88133317 0.9305 1 P 0 ;0,1=350,2=0.000000
L 5.88133317 0.9305 5.89091654 0.9305 1 P 0 ;0,1=350,2=0.000000
L 5.89091654 0.9305 5.89398327 0.92894931 1 P 0 ;0,1=350,2=0.000000
L 5.89398327 0.92894931 5.8959002 0.92688307 1 P 0 ;0,1=350,2=0.000000
L 5.8959002 0.92688307 5.89666673 0.9227497 1 P 0 ;0,1=350,2=0.000000
L 5.89666673 0.9227497 5.8959002 0.91861634 1 P 0 ;0,1=350,2=0.000000
L 5.8959002 0.91861634 5.8936 0.91603356 1 P 0 ;0,1=350,2=0.000000
L 5.8936 0.91603356 5.89091654 0.91448287 1 P 0 ;0,1=350,2=0.000000
L 5.89091654 0.91448287 5.88133317 0.91448287 1 P 0 ;0,1=350,2=0.000000
L 5.89091654 0.91448287 5.89666673 0.8995 1 P 0 ;0,1=350,2=0.000000
L 5.91271644 0.92533346 5.91501663 0.92843278 1 P 0 ;0,1=350,2=0.000000
L 5.91501663 0.92843278 5.9177001 0.92998337 1 P 0 ;0,1=350,2=0.000000
L 5.9177001 0.92998337 5.92076683 0.9305 1 P 0 ;0,1=350,2=0.000000
L 5.92076683 0.9305 5.9246 0.92946683 1 P 0 ;0,1=350,2=0.000000
L 5.9246 0.92946683 5.92728346 0.92688307 1 P 0 ;0,1=350,2=0.000000
L 5.92728346 0.92688307 5.92805 0.92378376 1 P 0 ;0,1=350,2=0.000000
L 5.92805 0.92378376 5.92766673 0.92068258 1 P 0 ;0,1=350,2=0.000000
L 5.92766673 0.92068258 5.92613307 0.9180998 1 P 0 ;0,1=350,2=0.000000
L 5.92613307 0.9180998 5.91846663 0.91293327 1 P 0 ;0,1=350,2=0.000000
L 5.91846663 0.91293327 5.91501663 0.90931644 1 P 0 ;0,1=350,2=0.000000
L 5.91501663 0.90931644 5.91271644 0.90414892 1 P 0 ;0,1=350,2=0.000000
L 5.91271644 0.90414892 5.9119499 0.8995 1 P 0 ;0,1=350,2=0.000000
L 5.9119499 0.8995 5.92805 0.8995 1 P 0 ;0,1=350,2=0.000000
L 5.95099961 0.8995 5.95099961 0.9305 1 P 0 ;0,1=350,2=0.000000
L 5.95099961 0.9305 5.9463999 0.9243003 1 P 0 ;0,1=350,2=0.000000
L 5.9463999 0.8995 5.95559931 0.8995 1 P 0 ;0,1=350,2=0.000000
L 5.89 1.147 5.89 1.103 1 P 0 
L 5.98 1.147 5.89 1.147 1 P 0 
L 5.89 1.103 5.98 1.103 1 P 0 
L 5.98 1.103 5.98 1.147 1 P 0 
L 5.85133317 1.1895 5.85133317 1.2205 1 P 0 ;0,1=351,2=0.000000
L 5.85133317 1.2205 5.86091654 1.2205 1 P 0 ;0,1=351,2=0.000000
L 5.86091654 1.2205 5.86398327 1.21894931 1 P 0 ;0,1=351,2=0.000000
L 5.86398327 1.21894931 5.8659002 1.21688307 1 P 0 ;0,1=351,2=0.000000
L 5.8659002 1.21688307 5.86666673 1.2127497 1 P 0 ;0,1=351,2=0.000000
L 5.86666673 1.2127497 5.8659002 1.20861634 1 P 0 ;0,1=351,2=0.000000
L 5.8659002 1.20861634 5.8636 1.20603356 1 P 0 ;0,1=351,2=0.000000
L 5.8636 1.20603356 5.86091654 1.20448287 1 P 0 ;0,1=351,2=0.000000
L 5.86091654 1.20448287 5.85133317 1.20448287 1 P 0 ;0,1=351,2=0.000000
L 5.86091654 1.20448287 5.86666673 1.1895 1 P 0 ;0,1=351,2=0.000000
L 5.88271644 1.21533346 5.88501663 1.21843278 1 P 0 ;0,1=351,2=0.000000
L 5.88501663 1.21843278 5.8877001 1.21998337 1 P 0 ;0,1=351,2=0.000000
L 5.8877001 1.21998337 5.89076683 1.2205 1 P 0 ;0,1=351,2=0.000000
L 5.89076683 1.2205 5.8946 1.21946683 1 P 0 ;0,1=351,2=0.000000
L 5.8946 1.21946683 5.89728346 1.21688307 1 P 0 ;0,1=351,2=0.000000
L 5.89728346 1.21688307 5.89805 1.21378376 1 P 0 ;0,1=351,2=0.000000
L 5.89805 1.21378376 5.89766673 1.21068258 1 P 0 ;0,1=351,2=0.000000
L 5.89766673 1.21068258 5.89613307 1.2080998 1 P 0 ;0,1=351,2=0.000000
L 5.89613307 1.2080998 5.88846663 1.20293327 1 P 0 ;0,1=351,2=0.000000
L 5.88846663 1.20293327 5.88501663 1.19931644 1 P 0 ;0,1=351,2=0.000000
L 5.88501663 1.19931644 5.88271644 1.19414892 1 P 0 ;0,1=351,2=0.000000
L 5.88271644 1.19414892 5.8819499 1.1895 1 P 0 ;0,1=351,2=0.000000
L 5.8819499 1.1895 5.89805 1.1895 1 P 0 ;0,1=351,2=0.000000
L 5.92099961 1.2205 5.91793287 1.21946683 1 P 0 ;0,1=351,2=0.000000
L 5.91793287 1.21946683 5.91563337 1.21688307 1 P 0 ;0,1=351,2=0.000000
L 5.91563337 1.21688307 5.9140997 1.21378376 1 P 0 ;0,1=351,2=0.000000
L 5.9140997 1.21378376 5.9129499 1.20964941 1 P 0 ;0,1=351,2=0.000000
L 5.9129499 1.20964941 5.91256663 1.20499951 1 P 0 ;0,1=351,2=0.000000
L 5.91256663 1.20499951 5.9129499 1.20034951 1 P 0 ;0,1=351,2=0.000000
L 5.9129499 1.20034951 5.9140997 1.19621614 1 P 0 ;0,1=351,2=0.000000
L 5.9140997 1.19621614 5.91563337 1.19311585 1 P 0 ;0,1=351,2=0.000000
L 5.91563337 1.19311585 5.91793287 1.19053307 1 P 0 ;0,1=351,2=0.000000
L 5.91793287 1.19053307 5.92099961 1.1895 1 P 0 ;0,1=351,2=0.000000
L 5.92099961 1.1895 5.92406634 1.19053307 1 P 0 ;0,1=351,2=0.000000
L 5.92406634 1.19053307 5.92636654 1.19311585 1 P 0 ;0,1=351,2=0.000000
L 5.92636654 1.19311585 5.9279002 1.19621614 1 P 0 ;0,1=351,2=0.000000
L 5.9279002 1.19621614 5.92905 1.20034951 1 P 0 ;0,1=351,2=0.000000
L 5.92905 1.20034951 5.92943327 1.20499951 1 P 0 ;0,1=351,2=0.000000
L 5.92943327 1.20499951 5.92905 1.20964941 1 P 0 ;0,1=351,2=0.000000
L 5.92905 1.20964941 5.9279002 1.21378376 1 P 0 ;0,1=351,2=0.000000
L 5.9279002 1.21378376 5.92636654 1.21688307 1 P 0 ;0,1=351,2=0.000000
L 5.92636654 1.21688307 5.92406634 1.21946683 1 P 0 ;0,1=351,2=0.000000
L 5.92406634 1.21946683 5.92099961 1.2205 1 P 0 ;0,1=351,2=0.000000
L 0.70848002 2.687 0.70848002 2.731 1 P 0 
L 0.70848002 2.731 0.61848002 2.731 1 P 0 
L 0.61848002 2.731 0.61848002 2.687 1 P 0 
L 0.61848002 2.687 0.70848002 2.687 1 P 0 
L 0.55766654 2.7075 0.55766654 2.7325 1 P 0 ;0,1=352,2=0.000000
L 0.55766654 2.7325 0.56433327 2.7325 1 P 0 ;0,1=352,2=0.000000
L 0.56433327 2.7325 0.56646663 2.73124941 1 P 0 ;0,1=352,2=0.000000
L 0.56646663 2.73124941 0.5678001 2.72958317 1 P 0 ;0,1=352,2=0.000000
L 0.5678001 2.72958317 0.56833337 2.7262498 1 P 0 ;0,1=352,2=0.000000
L 0.56833337 2.7262498 0.5678001 2.72291634 1 P 0 ;0,1=352,2=0.000000
L 0.5678001 2.72291634 0.5662 2.72083346 1 P 0 ;0,1=352,2=0.000000
L 0.5662 2.72083346 0.56433327 2.71958297 1 P 0 ;0,1=352,2=0.000000
L 0.56433327 2.71958297 0.55766654 2.71958297 1 P 0 ;0,1=352,2=0.000000
L 0.56433327 2.71958297 0.56833337 2.7075 1 P 0 ;0,1=352,2=0.000000
L 0.58446654 2.7075 0.5849997 2.71291624 1 P 0 ;0,1=352,2=0.000000
L 0.5849997 2.71291624 0.5858 2.71749931 1 P 0 ;0,1=352,2=0.000000
L 0.5858 2.71749931 0.58686644 2.72166663 1 P 0 ;0,1=352,2=0.000000
L 0.58686644 2.72166663 0.5882 2.7262498 1 P 0 ;0,1=352,2=0.000000
L 0.5882 2.7262498 0.59033337 2.7325 1 P 0 ;0,1=352,2=0.000000
L 0.59033337 2.7325 0.57966654 2.7325 1 P 0 ;0,1=352,2=0.000000
L 0.6069997 2.7325 0.60486634 2.73166683 1 P 0 ;0,1=352,2=0.000000
L 0.60486634 2.73166683 0.60326663 2.72958317 1 P 0 ;0,1=352,2=0.000000
L 0.60326663 2.72958317 0.6021998 2.72708366 1 P 0 ;0,1=352,2=0.000000
L 0.6021998 2.72708366 0.6013999 2.72374951 1 P 0 ;0,1=352,2=0.000000
L 0.6013999 2.72374951 0.60113327 2.71999961 1 P 0 ;0,1=352,2=0.000000
L 0.60113327 2.71999961 0.6013999 2.71624961 1 P 0 ;0,1=352,2=0.000000
L 0.6013999 2.71624961 0.6021998 2.71291624 1 P 0 ;0,1=352,2=0.000000
L 0.6021998 2.71291624 0.60326663 2.71041604 1 P 0 ;0,1=352,2=0.000000
L 0.60326663 2.71041604 0.60486634 2.70833307 1 P 0 ;0,1=352,2=0.000000
L 0.60486634 2.70833307 0.6069997 2.7075 1 P 0 ;0,1=352,2=0.000000
L 0.6069997 2.7075 0.60913307 2.70833307 1 P 0 ;0,1=352,2=0.000000
L 0.60913307 2.70833307 0.61073327 2.71041604 1 P 0 ;0,1=352,2=0.000000
L 0.61073327 2.71041604 0.6118001 2.71291624 1 P 0 ;0,1=352,2=0.000000
L 0.6118001 2.71291624 0.6126 2.71624961 1 P 0 ;0,1=352,2=0.000000
L 0.6126 2.71624961 0.61286663 2.71999961 1 P 0 ;0,1=352,2=0.000000
L 0.61286663 2.71999961 0.6126 2.72374951 1 P 0 ;0,1=352,2=0.000000
L 0.6126 2.72374951 0.6118001 2.72708366 1 P 0 ;0,1=352,2=0.000000
L 0.6118001 2.72708366 0.61073327 2.72958317 1 P 0 ;0,1=352,2=0.000000
L 0.61073327 2.72958317 0.60913307 2.73166683 1 P 0 ;0,1=352,2=0.000000
L 0.60913307 2.73166683 0.6069997 2.7325 1 P 0 ;0,1=352,2=0.000000
L 0.70848002 2.642 0.70848002 2.686 1 P 0 
L 0.70848002 2.686 0.61848002 2.686 1 P 0 
L 0.61848002 2.642 0.70848002 2.642 1 P 0 
L 0.61848002 2.686 0.61848002 2.642 1 P 0 
L 0.55766654 2.6725 0.55766654 2.6975 1 P 0 ;0,1=353,2=0.000000
L 0.55766654 2.6975 0.56433327 2.6975 1 P 0 ;0,1=353,2=0.000000
L 0.56433327 2.6975 0.56646663 2.69624941 1 P 0 ;0,1=353,2=0.000000
L 0.56646663 2.69624941 0.5678001 2.69458317 1 P 0 ;0,1=353,2=0.000000
L 0.5678001 2.69458317 0.56833337 2.6912498 1 P 0 ;0,1=353,2=0.000000
L 0.56833337 2.6912498 0.5678001 2.68791634 1 P 0 ;0,1=353,2=0.000000
L 0.5678001 2.68791634 0.5662 2.68583346 1 P 0 ;0,1=353,2=0.000000
L 0.5662 2.68583346 0.56433327 2.68458297 1 P 0 ;0,1=353,2=0.000000
L 0.56433327 2.68458297 0.55766654 2.68458297 1 P 0 ;0,1=353,2=0.000000
L 0.56433327 2.68458297 0.56833337 2.6725 1 P 0 ;0,1=353,2=0.000000
L 0.58446654 2.6725 0.5849997 2.67791624 1 P 0 ;0,1=353,2=0.000000
L 0.5849997 2.67791624 0.5858 2.68249931 1 P 0 ;0,1=353,2=0.000000
L 0.5858 2.68249931 0.58686644 2.68666663 1 P 0 ;0,1=353,2=0.000000
L 0.58686644 2.68666663 0.5882 2.6912498 1 P 0 ;0,1=353,2=0.000000
L 0.5882 2.6912498 0.59033337 2.6975 1 P 0 ;0,1=353,2=0.000000
L 0.59033337 2.6975 0.57966654 2.6975 1 P 0 ;0,1=353,2=0.000000
L 0.60193317 2.69333337 0.60353327 2.69583287 1 P 0 ;0,1=353,2=0.000000
L 0.60353327 2.69583287 0.6054 2.69708337 1 P 0 ;0,1=353,2=0.000000
L 0.6054 2.69708337 0.60753337 2.6975 1 P 0 ;0,1=353,2=0.000000
L 0.60753337 2.6975 0.6102 2.69666683 1 P 0 ;0,1=353,2=0.000000
L 0.6102 2.69666683 0.61206673 2.69458317 1 P 0 ;0,1=353,2=0.000000
L 0.61206673 2.69458317 0.6126 2.69208366 1 P 0 ;0,1=353,2=0.000000
L 0.6126 2.69208366 0.61233337 2.68958268 1 P 0 ;0,1=353,2=0.000000
L 0.61233337 2.68958268 0.61126644 2.6874998 1 P 0 ;0,1=353,2=0.000000
L 0.61126644 2.6874998 0.60593327 2.68333327 1 P 0 ;0,1=353,2=0.000000
L 0.60593327 2.68333327 0.60353327 2.68041644 1 P 0 ;0,1=353,2=0.000000
L 0.60353327 2.68041644 0.60193317 2.67624911 1 P 0 ;0,1=353,2=0.000000
L 0.60193317 2.67624911 0.6013999 2.6725 1 P 0 ;0,1=353,2=0.000000
L 0.6013999 2.6725 0.6126 2.6725 1 P 0 ;0,1=353,2=0.000000
L 0.53651998 2.209 0.53651998 2.299 1 P 0 
L 0.53651998 2.299 0.49251998 2.299 1 P 0 
L 0.49251998 2.299 0.49251998 2.209 1 P 0 
L 0.49251998 2.209 0.53651998 2.209 1 P 0 
L 0.4355 2.18583317 0.4045 2.18583317 1 P 0 ;0,1=354,2=270.000000
L 0.4045 2.18583317 0.4045 2.19541654 1 P 0 ;0,1=354,2=270.000000
L 0.4045 2.19541654 0.40605069 2.19848327 1 P 0 ;0,1=354,2=270.000000
L 0.40605069 2.19848327 0.40811693 2.2004002 1 P 0 ;0,1=354,2=270.000000
L 0.40811693 2.2004002 0.4122503 2.20116673 1 P 0 ;0,1=354,2=270.000000
L 0.4122503 2.20116673 0.41638366 2.2004002 1 P 0 ;0,1=354,2=270.000000
L 0.41638366 2.2004002 0.41896644 2.1981 1 P 0 ;0,1=354,2=270.000000
L 0.41896644 2.1981 0.42051713 2.19541654 1 P 0 ;0,1=354,2=270.000000
L 0.42051713 2.19541654 0.42051713 2.18583317 1 P 0 ;0,1=354,2=270.000000
L 0.42051713 2.19541654 0.4355 2.20116673 1 P 0 ;0,1=354,2=270.000000
L 0.42930039 2.21606663 0.43291722 2.21836614 1 P 0 ;0,1=354,2=270.000000
L 0.43291722 2.21836614 0.43498346 2.22143287 1 P 0 ;0,1=354,2=270.000000
L 0.43498346 2.22143287 0.4355 2.22488356 1 P 0 ;0,1=354,2=270.000000
L 0.4355 2.22488356 0.43498346 2.2279503 1 P 0 ;0,1=354,2=270.000000
L 0.43498346 2.2279503 0.43240069 2.23101703 1 P 0 ;0,1=354,2=270.000000
L 0.43240069 2.23101703 0.42930039 2.23293327 1 P 0 ;0,1=354,2=270.000000
L 0.42930039 2.23293327 0.4262001 2.23331654 1 P 0 ;0,1=354,2=270.000000
L 0.4262001 2.23331654 0.42258425 2.23255 1 P 0 ;0,1=354,2=270.000000
L 0.42258425 2.23255 0.42000049 2.22986654 1 P 0 ;0,1=354,2=270.000000
L 0.42000049 2.22986654 0.41896644 2.22718307 1 P 0 ;0,1=354,2=270.000000
L 0.41896644 2.22718307 0.41896644 2.22373307 1 P 0 ;0,1=354,2=270.000000
L 0.41896644 2.22718307 0.41741683 2.22948327 1 P 0 ;0,1=354,2=270.000000
L 0.41741683 2.22948327 0.41483406 2.2314002 1 P 0 ;0,1=354,2=270.000000
L 0.41483406 2.2314002 0.41173376 2.23216673 1 P 0 ;0,1=354,2=270.000000
L 0.41173376 2.23216673 0.40863346 2.2314002 1 P 0 ;0,1=354,2=270.000000
L 0.40863346 2.2314002 0.40605069 2.22948327 1 P 0 ;0,1=354,2=270.000000
L 0.40605069 2.22948327 0.4045 2.22603327 1 P 0 ;0,1=354,2=270.000000
L 0.4045 2.22603327 0.40501663 2.22258337 1 P 0 ;0,1=354,2=270.000000
L 0.40501663 2.22258337 0.40708376 2.21913337 1 P 0 ;0,1=354,2=270.000000
L 0.4355 2.25549961 0.43498346 2.25818307 1 P 0 ;0,1=354,2=270.000000
L 0.43498346 2.25818307 0.43343386 2.2612498 1 P 0 ;0,1=354,2=270.000000
L 0.43343386 2.2612498 0.43085108 2.26316673 1 P 0 ;0,1=354,2=270.000000
L 0.43085108 2.26316673 0.42723327 2.26393327 1 P 0 ;0,1=354,2=270.000000
L 0.42723327 2.26393327 0.42361732 2.26316673 1 P 0 ;0,1=354,2=270.000000
L 0.42361732 2.26316673 0.42051713 2.26086654 1 P 0 ;0,1=354,2=270.000000
L 0.42051713 2.26086654 0.41896644 2.25741654 1 P 0 ;0,1=354,2=270.000000
L 0.41896644 2.25741654 0.41896644 2.25358337 1 P 0 ;0,1=354,2=270.000000
L 0.41896644 2.25358337 0.41793337 2.25128317 1 P 0 ;0,1=354,2=270.000000
L 0.41793337 2.25128317 0.41535059 2.24936614 1 P 0 ;0,1=354,2=270.000000
L 0.41535059 2.24936614 0.41173376 2.2485997 1 P 0 ;0,1=354,2=270.000000
L 0.41173376 2.2485997 0.40811693 2.2497501 1 P 0 ;0,1=354,2=270.000000
L 0.40811693 2.2497501 0.40553317 2.25243287 1 P 0 ;0,1=354,2=270.000000
L 0.40553317 2.25243287 0.4045 2.25549961 1 P 0 ;0,1=354,2=270.000000
L 0.4045 2.25549961 0.40553317 2.25856634 1 P 0 ;0,1=354,2=270.000000
L 0.40553317 2.25856634 0.40811693 2.2612498 1 P 0 ;0,1=354,2=270.000000
L 0.40811693 2.2612498 0.41173376 2.2624002 1 P 0 ;0,1=354,2=270.000000
L 0.41173376 2.2624002 0.41535059 2.26163307 1 P 0 ;0,1=354,2=270.000000
L 0.41535059 2.26163307 0.41793337 2.25971673 1 P 0 ;0,1=354,2=270.000000
L 0.41793337 2.25971673 0.41896644 2.25741654 1 P 0 ;0,1=354,2=270.000000
L 0.41896644 2.25741654 0.41896644 2.25358337 1 P 0 ;0,1=354,2=270.000000
L 0.41896644 2.25358337 0.42051713 2.25013337 1 P 0 ;0,1=354,2=270.000000
L 0.42051713 2.25013337 0.42361732 2.24783317 1 P 0 ;0,1=354,2=270.000000
L 0.42361732 2.24783317 0.42723327 2.24706663 1 P 0 ;0,1=354,2=270.000000
L 0.42723327 2.24706663 0.43085108 2.24783317 1 P 0 ;0,1=354,2=270.000000
L 0.43085108 2.24783317 0.43343386 2.2497501 1 P 0 ;0,1=354,2=270.000000
L 0.43343386 2.2497501 0.43498346 2.25281683 1 P 0 ;0,1=354,2=270.000000
L 0.43498346 2.25281683 0.4355 2.25549961 1 P 0 ;0,1=354,2=270.000000
L 0.4355 2.28649961 0.4045 2.28649961 1 P 0 ;0,1=354,2=270.000000
L 0.4045 2.28649961 0.4106997 2.2818999 1 P 0 ;0,1=354,2=270.000000
L 0.4355 2.2818999 0.4355 2.29109931 1 P 0 ;0,1=354,2=270.000000
L 0.553 2.115 0.553 2.025 1 P 0 
L 0.553 2.025 0.597 2.025 1 P 0 
L 0.597 2.025 0.597 2.115 1 P 0 
L 0.597 2.115 0.553 2.115 1 P 0 
L 0.4505 1.99583317 0.4195 1.99583317 1 P 0 ;0,1=355,2=270.000000
L 0.4195 1.99583317 0.4195 2.00541654 1 P 0 ;0,1=355,2=270.000000
L 0.4195 2.00541654 0.42105069 2.00848327 1 P 0 ;0,1=355,2=270.000000
L 0.42105069 2.00848327 0.42311693 2.0104002 1 P 0 ;0,1=355,2=270.000000
L 0.42311693 2.0104002 0.4272503 2.01116673 1 P 0 ;0,1=355,2=270.000000
L 0.4272503 2.01116673 0.43138366 2.0104002 1 P 0 ;0,1=355,2=270.000000
L 0.43138366 2.0104002 0.43396644 2.0081 1 P 0 ;0,1=355,2=270.000000
L 0.43396644 2.0081 0.43551713 2.00541654 1 P 0 ;0,1=355,2=270.000000
L 0.43551713 2.00541654 0.43551713 1.99583317 1 P 0 ;0,1=355,2=270.000000
L 0.43551713 2.00541654 0.4505 2.01116673 1 P 0 ;0,1=355,2=270.000000
L 0.44430039 2.02606663 0.44791722 2.02836614 1 P 0 ;0,1=355,2=270.000000
L 0.44791722 2.02836614 0.44998346 2.03143287 1 P 0 ;0,1=355,2=270.000000
L 0.44998346 2.03143287 0.4505 2.03488356 1 P 0 ;0,1=355,2=270.000000
L 0.4505 2.03488356 0.44998346 2.0379503 1 P 0 ;0,1=355,2=270.000000
L 0.44998346 2.0379503 0.44740069 2.04101703 1 P 0 ;0,1=355,2=270.000000
L 0.44740069 2.04101703 0.44430039 2.04293327 1 P 0 ;0,1=355,2=270.000000
L 0.44430039 2.04293327 0.4412001 2.04331654 1 P 0 ;0,1=355,2=270.000000
L 0.4412001 2.04331654 0.43758425 2.04255 1 P 0 ;0,1=355,2=270.000000
L 0.43758425 2.04255 0.43500049 2.03986654 1 P 0 ;0,1=355,2=270.000000
L 0.43500049 2.03986654 0.43396644 2.03718307 1 P 0 ;0,1=355,2=270.000000
L 0.43396644 2.03718307 0.43396644 2.03373307 1 P 0 ;0,1=355,2=270.000000
L 0.43396644 2.03718307 0.43241683 2.03948327 1 P 0 ;0,1=355,2=270.000000
L 0.43241683 2.03948327 0.42983406 2.0414002 1 P 0 ;0,1=355,2=270.000000
L 0.42983406 2.0414002 0.42673376 2.04216673 1 P 0 ;0,1=355,2=270.000000
L 0.42673376 2.04216673 0.42363346 2.0414002 1 P 0 ;0,1=355,2=270.000000
L 0.42363346 2.0414002 0.42105069 2.03948327 1 P 0 ;0,1=355,2=270.000000
L 0.42105069 2.03948327 0.4195 2.03603327 1 P 0 ;0,1=355,2=270.000000
L 0.4195 2.03603327 0.42001663 2.03258337 1 P 0 ;0,1=355,2=270.000000
L 0.42001663 2.03258337 0.42208376 2.02913337 1 P 0 ;0,1=355,2=270.000000
L 0.44430039 2.05706663 0.44791722 2.05936614 1 P 0 ;0,1=355,2=270.000000
L 0.44791722 2.05936614 0.44998346 2.06243287 1 P 0 ;0,1=355,2=270.000000
L 0.44998346 2.06243287 0.4505 2.06588356 1 P 0 ;0,1=355,2=270.000000
L 0.4505 2.06588356 0.44998346 2.0689503 1 P 0 ;0,1=355,2=270.000000
L 0.44998346 2.0689503 0.44740069 2.07201703 1 P 0 ;0,1=355,2=270.000000
L 0.44740069 2.07201703 0.44430039 2.07393327 1 P 0 ;0,1=355,2=270.000000
L 0.44430039 2.07393327 0.4412001 2.07431654 1 P 0 ;0,1=355,2=270.000000
L 0.4412001 2.07431654 0.43758425 2.07355 1 P 0 ;0,1=355,2=270.000000
L 0.43758425 2.07355 0.43500049 2.07086654 1 P 0 ;0,1=355,2=270.000000
L 0.43500049 2.07086654 0.43396644 2.06818307 1 P 0 ;0,1=355,2=270.000000
L 0.43396644 2.06818307 0.43396644 2.06473307 1 P 0 ;0,1=355,2=270.000000
L 0.43396644 2.06818307 0.43241683 2.07048327 1 P 0 ;0,1=355,2=270.000000
L 0.43241683 2.07048327 0.42983406 2.0724002 1 P 0 ;0,1=355,2=270.000000
L 0.42983406 2.0724002 0.42673376 2.07316673 1 P 0 ;0,1=355,2=270.000000
L 0.42673376 2.07316673 0.42363346 2.0724002 1 P 0 ;0,1=355,2=270.000000
L 0.42363346 2.0724002 0.42105069 2.07048327 1 P 0 ;0,1=355,2=270.000000
L 0.42105069 2.07048327 0.4195 2.06703327 1 P 0 ;0,1=355,2=270.000000
L 0.4195 2.06703327 0.42001663 2.06358337 1 P 0 ;0,1=355,2=270.000000
L 0.42001663 2.06358337 0.42208376 2.06013337 1 P 0 ;0,1=355,2=270.000000
L 0.4505 2.09649961 0.4195 2.09649961 1 P 0 ;0,1=355,2=270.000000
L 0.4195 2.09649961 0.4256997 2.0918999 1 P 0 ;0,1=355,2=270.000000
L 0.4505 2.0918999 0.4505 2.10109931 1 P 0 ;0,1=355,2=270.000000
L 0.58 1.628 0.58 1.672 1 P 0 
L 0.49 1.628 0.58 1.628 1 P 0 
L 0.58 1.672 0.49 1.672 1 P 0 
L 0.49 1.672 0.49 1.628 1 P 0 
L 0.49666654 1.5925 0.49666654 1.6175 1 P 0 ;0,1=356,2=0.000000
L 0.49666654 1.6175 0.50333327 1.6175 1 P 0 ;0,1=356,2=0.000000
L 0.50333327 1.6175 0.50546663 1.61624941 1 P 0 ;0,1=356,2=0.000000
L 0.50546663 1.61624941 0.5068001 1.61458317 1 P 0 ;0,1=356,2=0.000000
L 0.5068001 1.61458317 0.50733337 1.6112498 1 P 0 ;0,1=356,2=0.000000
L 0.50733337 1.6112498 0.5068001 1.60791634 1 P 0 ;0,1=356,2=0.000000
L 0.5068001 1.60791634 0.5052 1.60583346 1 P 0 ;0,1=356,2=0.000000
L 0.5052 1.60583346 0.50333327 1.60458297 1 P 0 ;0,1=356,2=0.000000
L 0.50333327 1.60458297 0.49666654 1.60458297 1 P 0 ;0,1=356,2=0.000000
L 0.50333327 1.60458297 0.50733337 1.5925 1 P 0 ;0,1=356,2=0.000000
L 0.51813327 1.59749961 0.51973297 1.59458287 1 P 0 ;0,1=356,2=0.000000
L 0.51973297 1.59458287 0.52186634 1.59291654 1 P 0 ;0,1=356,2=0.000000
L 0.52186634 1.59291654 0.52426683 1.5925 1 P 0 ;0,1=356,2=0.000000
L 0.52426683 1.5925 0.5264002 1.59291654 1 P 0 ;0,1=356,2=0.000000
L 0.5264002 1.59291654 0.52853356 1.59499941 1 P 0 ;0,1=356,2=0.000000
L 0.52853356 1.59499941 0.52986663 1.59749961 1 P 0 ;0,1=356,2=0.000000
L 0.52986663 1.59749961 0.53013317 1.5999999 1 P 0 ;0,1=356,2=0.000000
L 0.53013317 1.5999999 0.5296 1.60291594 1 P 0 ;0,1=356,2=0.000000
L 0.5296 1.60291594 0.52773327 1.60499961 1 P 0 ;0,1=356,2=0.000000
L 0.52773327 1.60499961 0.52586644 1.60583346 1 P 0 ;0,1=356,2=0.000000
L 0.52586644 1.60583346 0.52346654 1.60583346 1 P 0 ;0,1=356,2=0.000000
L 0.52586644 1.60583346 0.52746663 1.60708327 1 P 0 ;0,1=356,2=0.000000
L 0.52746663 1.60708327 0.5288001 1.60916614 1 P 0 ;0,1=356,2=0.000000
L 0.5288001 1.60916614 0.52933337 1.61166634 1 P 0 ;0,1=356,2=0.000000
L 0.52933337 1.61166634 0.5288001 1.61416654 1 P 0 ;0,1=356,2=0.000000
L 0.5288001 1.61416654 0.52746663 1.61624941 1 P 0 ;0,1=356,2=0.000000
L 0.52746663 1.61624941 0.52506663 1.6175 1 P 0 ;0,1=356,2=0.000000
L 0.52506663 1.6175 0.52266663 1.61708337 1 P 0 ;0,1=356,2=0.000000
L 0.52266663 1.61708337 0.52026663 1.61541634 1 P 0 ;0,1=356,2=0.000000
L 0.5459997 1.5925 0.54786644 1.59291654 1 P 0 ;0,1=356,2=0.000000
L 0.54786644 1.59291654 0.5499998 1.59416624 1 P 0 ;0,1=356,2=0.000000
L 0.5499998 1.59416624 0.55133337 1.59624911 1 P 0 ;0,1=356,2=0.000000
L 0.55133337 1.59624911 0.55186663 1.59916673 1 P 0 ;0,1=356,2=0.000000
L 0.55186663 1.59916673 0.55133337 1.60208278 1 P 0 ;0,1=356,2=0.000000
L 0.55133337 1.60208278 0.54973327 1.60458297 1 P 0 ;0,1=356,2=0.000000
L 0.54973327 1.60458297 0.54733327 1.60583346 1 P 0 ;0,1=356,2=0.000000
L 0.54733327 1.60583346 0.54466663 1.60583346 1 P 0 ;0,1=356,2=0.000000
L 0.54466663 1.60583346 0.54306654 1.60666663 1 P 0 ;0,1=356,2=0.000000
L 0.54306654 1.60666663 0.54173297 1.60874951 1 P 0 ;0,1=356,2=0.000000
L 0.54173297 1.60874951 0.5411998 1.61166634 1 P 0 ;0,1=356,2=0.000000
L 0.5411998 1.61166634 0.5420001 1.61458317 1 P 0 ;0,1=356,2=0.000000
L 0.5420001 1.61458317 0.54386634 1.61666683 1 P 0 ;0,1=356,2=0.000000
L 0.54386634 1.61666683 0.5459997 1.6175 1 P 0 ;0,1=356,2=0.000000
L 0.5459997 1.6175 0.54813307 1.61666683 1 P 0 ;0,1=356,2=0.000000
L 0.54813307 1.61666683 0.5499998 1.61458317 1 P 0 ;0,1=356,2=0.000000
L 0.5499998 1.61458317 0.5508001 1.61166634 1 P 0 ;0,1=356,2=0.000000
L 0.5508001 1.61166634 0.55026644 1.60874951 1 P 0 ;0,1=356,2=0.000000
L 0.55026644 1.60874951 0.54893337 1.60666663 1 P 0 ;0,1=356,2=0.000000
L 0.54893337 1.60666663 0.54733327 1.60583346 1 P 0 ;0,1=356,2=0.000000
L 0.54733327 1.60583346 0.54466663 1.60583346 1 P 0 ;0,1=356,2=0.000000
L 0.54466663 1.60583346 0.54226663 1.60458297 1 P 0 ;0,1=356,2=0.000000
L 0.54226663 1.60458297 0.54066654 1.60208278 1 P 0 ;0,1=356,2=0.000000
L 0.54066654 1.60208278 0.54013327 1.59916673 1 P 0 ;0,1=356,2=0.000000
L 0.54013327 1.59916673 0.54066654 1.59624911 1 P 0 ;0,1=356,2=0.000000
L 0.54066654 1.59624911 0.5420001 1.59416624 1 P 0 ;0,1=356,2=0.000000
L 0.5420001 1.59416624 0.54413346 1.59291654 1 P 0 ;0,1=356,2=0.000000
L 0.54413346 1.59291654 0.5459997 1.5925 1 P 0 ;0,1=356,2=0.000000
L 0.56213327 1.59749961 0.56373297 1.59458287 1 P 0 ;0,1=356,2=0.000000
L 0.56373297 1.59458287 0.56586634 1.59291654 1 P 0 ;0,1=356,2=0.000000
L 0.56586634 1.59291654 0.56826683 1.5925 1 P 0 ;0,1=356,2=0.000000
L 0.56826683 1.5925 0.5704002 1.59291654 1 P 0 ;0,1=356,2=0.000000
L 0.5704002 1.59291654 0.57253356 1.59499941 1 P 0 ;0,1=356,2=0.000000
L 0.57253356 1.59499941 0.57386663 1.59749961 1 P 0 ;0,1=356,2=0.000000
L 0.57386663 1.59749961 0.57413317 1.5999999 1 P 0 ;0,1=356,2=0.000000
L 0.57413317 1.5999999 0.5736 1.60291594 1 P 0 ;0,1=356,2=0.000000
L 0.5736 1.60291594 0.57173327 1.60499961 1 P 0 ;0,1=356,2=0.000000
L 0.57173327 1.60499961 0.56986644 1.60583346 1 P 0 ;0,1=356,2=0.000000
L 0.56986644 1.60583346 0.56746654 1.60583346 1 P 0 ;0,1=356,2=0.000000
L 0.56986644 1.60583346 0.57146663 1.60708327 1 P 0 ;0,1=356,2=0.000000
L 0.57146663 1.60708327 0.5728001 1.60916614 1 P 0 ;0,1=356,2=0.000000
L 0.5728001 1.60916614 0.57333337 1.61166634 1 P 0 ;0,1=356,2=0.000000
L 0.57333337 1.61166634 0.5728001 1.61416654 1 P 0 ;0,1=356,2=0.000000
L 0.5728001 1.61416654 0.57146663 1.61624941 1 P 0 ;0,1=356,2=0.000000
L 0.57146663 1.61624941 0.56906663 1.6175 1 P 0 ;0,1=356,2=0.000000
L 0.56906663 1.6175 0.56666663 1.61708337 1 P 0 ;0,1=356,2=0.000000
L 0.56666663 1.61708337 0.56426663 1.61541634 1 P 0 ;0,1=356,2=0.000000
L 0.602 1.51 0.558 1.51 1 P 0 
L 0.558 1.51 0.558 1.42 1 P 0 
L 0.558 1.42 0.602 1.42 1 P 0 
L 0.602 1.42 0.602 1.51 1 P 0 
L 0.4455 1.36083317 0.4145 1.36083317 1 P 0 ;0,1=357,2=270.000000
L 0.4145 1.36083317 0.4145 1.37041654 1 P 0 ;0,1=357,2=270.000000
L 0.4145 1.37041654 0.41605069 1.37348327 1 P 0 ;0,1=357,2=270.000000
L 0.41605069 1.37348327 0.41811693 1.3754002 1 P 0 ;0,1=357,2=270.000000
L 0.41811693 1.3754002 0.4222503 1.37616673 1 P 0 ;0,1=357,2=270.000000
L 0.4222503 1.37616673 0.42638366 1.3754002 1 P 0 ;0,1=357,2=270.000000
L 0.42638366 1.3754002 0.42896644 1.3731 1 P 0 ;0,1=357,2=270.000000
L 0.42896644 1.3731 0.43051713 1.37041654 1 P 0 ;0,1=357,2=270.000000
L 0.43051713 1.37041654 0.43051713 1.36083317 1 P 0 ;0,1=357,2=270.000000
L 0.43051713 1.37041654 0.4455 1.37616673 1 P 0 ;0,1=357,2=270.000000
L 0.43930039 1.39106663 0.44291722 1.39336614 1 P 0 ;0,1=357,2=270.000000
L 0.44291722 1.39336614 0.44498346 1.39643287 1 P 0 ;0,1=357,2=270.000000
L 0.44498346 1.39643287 0.4455 1.39988356 1 P 0 ;0,1=357,2=270.000000
L 0.4455 1.39988356 0.44498346 1.4029503 1 P 0 ;0,1=357,2=270.000000
L 0.44498346 1.4029503 0.44240069 1.40601703 1 P 0 ;0,1=357,2=270.000000
L 0.44240069 1.40601703 0.43930039 1.40793327 1 P 0 ;0,1=357,2=270.000000
L 0.43930039 1.40793327 0.4362001 1.40831654 1 P 0 ;0,1=357,2=270.000000
L 0.4362001 1.40831654 0.43258425 1.40755 1 P 0 ;0,1=357,2=270.000000
L 0.43258425 1.40755 0.43000049 1.40486654 1 P 0 ;0,1=357,2=270.000000
L 0.43000049 1.40486654 0.42896644 1.40218307 1 P 0 ;0,1=357,2=270.000000
L 0.42896644 1.40218307 0.42896644 1.39873307 1 P 0 ;0,1=357,2=270.000000
L 0.42896644 1.40218307 0.42741683 1.40448327 1 P 0 ;0,1=357,2=270.000000
L 0.42741683 1.40448327 0.42483406 1.4064002 1 P 0 ;0,1=357,2=270.000000
L 0.42483406 1.4064002 0.42173376 1.40716673 1 P 0 ;0,1=357,2=270.000000
L 0.42173376 1.40716673 0.41863346 1.4064002 1 P 0 ;0,1=357,2=270.000000
L 0.41863346 1.4064002 0.41605069 1.40448327 1 P 0 ;0,1=357,2=270.000000
L 0.41605069 1.40448327 0.4145 1.40103327 1 P 0 ;0,1=357,2=270.000000
L 0.4145 1.40103327 0.41501663 1.39758337 1 P 0 ;0,1=357,2=270.000000
L 0.41501663 1.39758337 0.41708376 1.39413337 1 P 0 ;0,1=357,2=270.000000
L 0.43258425 1.42321644 0.42896644 1.4258999 1 P 0 ;0,1=357,2=270.000000
L 0.42896644 1.4258999 0.4269002 1.4282001 1 P 0 ;0,1=357,2=270.000000
L 0.4269002 1.4282001 0.42586713 1.43126683 1 P 0 ;0,1=357,2=270.000000
L 0.42586713 1.43126683 0.4269002 1.4339503 1 P 0 ;0,1=357,2=270.000000
L 0.4269002 1.4339503 0.42896644 1.43586654 1 P 0 ;0,1=357,2=270.000000
L 0.42896644 1.43586654 0.43206673 1.4374002 1 P 0 ;0,1=357,2=270.000000
L 0.43206673 1.4374002 0.43568356 1.43778346 1 P 0 ;0,1=357,2=270.000000
L 0.43568356 1.43778346 0.43878386 1.4374002 1 P 0 ;0,1=357,2=270.000000
L 0.43878386 1.4374002 0.44188415 1.43586654 1 P 0 ;0,1=357,2=270.000000
L 0.44188415 1.43586654 0.44446693 1.43356634 1 P 0 ;0,1=357,2=270.000000
L 0.44446693 1.43356634 0.4455 1.43088356 1 P 0 ;0,1=357,2=270.000000
L 0.4455 1.43088356 0.44446693 1.42781683 1 P 0 ;0,1=357,2=270.000000
L 0.44446693 1.42781683 0.44136762 1.42513337 1 P 0 ;0,1=357,2=270.000000
L 0.44136762 1.42513337 0.43671673 1.4235997 1 P 0 ;0,1=357,2=270.000000
L 0.43671673 1.4235997 0.4315502 1.42321644 1 P 0 ;0,1=357,2=270.000000
L 0.4315502 1.42321644 0.42483406 1.42398287 1 P 0 ;0,1=357,2=270.000000
L 0.42483406 1.42398287 0.42121624 1.42513337 1 P 0 ;0,1=357,2=270.000000
L 0.42121624 1.42513337 0.4176003 1.42704961 1 P 0 ;0,1=357,2=270.000000
L 0.4176003 1.42704961 0.41501663 1.42973307 1 P 0 ;0,1=357,2=270.000000
L 0.41501663 1.42973307 0.4145 1.43241654 1 P 0 ;0,1=357,2=270.000000
L 0.4145 1.43241654 0.41553317 1.4351 1 P 0 ;0,1=357,2=270.000000
L 0.41553317 1.4351 0.41811693 1.43701703 1 P 0 ;0,1=357,2=270.000000
L 0.44085108 1.45306663 0.44343386 1.45536614 1 P 0 ;0,1=357,2=270.000000
L 0.44343386 1.45536614 0.44498346 1.45804961 1 P 0 ;0,1=357,2=270.000000
L 0.44498346 1.45804961 0.4455 1.46149961 1 P 0 ;0,1=357,2=270.000000
L 0.4455 1.46149961 0.44446693 1.4649503 1 P 0 ;0,1=357,2=270.000000
L 0.44446693 1.4649503 0.44240069 1.46763307 1 P 0 ;0,1=357,2=270.000000
L 0.44240069 1.46763307 0.43878386 1.46955 1 P 0 ;0,1=357,2=270.000000
L 0.43878386 1.46955 0.43465049 1.46993327 1 P 0 ;0,1=357,2=270.000000
L 0.43465049 1.46993327 0.43051713 1.46916673 1 P 0 ;0,1=357,2=270.000000
L 0.43051713 1.46916673 0.42793337 1.4672498 1 P 0 ;0,1=357,2=270.000000
L 0.42793337 1.4672498 0.42586713 1.46456634 1 P 0 ;0,1=357,2=270.000000
L 0.42586713 1.46456634 0.42535059 1.46188356 1 P 0 ;0,1=357,2=270.000000
L 0.42535059 1.46188356 0.42586713 1.4592001 1 P 0 ;0,1=357,2=270.000000
L 0.42586713 1.4592001 0.42793337 1.4557501 1 P 0 ;0,1=357,2=270.000000
L 0.42793337 1.4557501 0.4145 1.4568999 1 P 0 ;0,1=357,2=270.000000
L 0.4145 1.4568999 0.4145 1.4672498 1 P 0 ;0,1=357,2=270.000000
L 0.527 1.0599 0.527 1.1499 1 P 0 
L 0.527 1.1499 0.483 1.1499 1 P 0 
L 0.483 1.1499 0.483 1.0599 1 P 0 
L 0.483 1.0599 0.527 1.0599 1 P 0 
L 0.4255 1.03083317 0.3945 1.03083317 1 P 0 ;0,1=358,2=270.000000
L 0.3945 1.03083317 0.3945 1.04041654 1 P 0 ;0,1=358,2=270.000000
L 0.3945 1.04041654 0.39605069 1.04348327 1 P 0 ;0,1=358,2=270.000000
L 0.39605069 1.04348327 0.39811693 1.0454002 1 P 0 ;0,1=358,2=270.000000
L 0.39811693 1.0454002 0.4022503 1.04616673 1 P 0 ;0,1=358,2=270.000000
L 0.4022503 1.04616673 0.40638366 1.0454002 1 P 0 ;0,1=358,2=270.000000
L 0.40638366 1.0454002 0.40896644 1.0431 1 P 0 ;0,1=358,2=270.000000
L 0.40896644 1.0431 0.41051713 1.04041654 1 P 0 ;0,1=358,2=270.000000
L 0.41051713 1.04041654 0.41051713 1.03083317 1 P 0 ;0,1=358,2=270.000000
L 0.41051713 1.04041654 0.4255 1.04616673 1 P 0 ;0,1=358,2=270.000000
L 0.41930039 1.06106663 0.42291722 1.06336614 1 P 0 ;0,1=358,2=270.000000
L 0.42291722 1.06336614 0.42498346 1.06643287 1 P 0 ;0,1=358,2=270.000000
L 0.42498346 1.06643287 0.4255 1.06988356 1 P 0 ;0,1=358,2=270.000000
L 0.4255 1.06988356 0.42498346 1.0729503 1 P 0 ;0,1=358,2=270.000000
L 0.42498346 1.0729503 0.42240069 1.07601703 1 P 0 ;0,1=358,2=270.000000
L 0.42240069 1.07601703 0.41930039 1.07793327 1 P 0 ;0,1=358,2=270.000000
L 0.41930039 1.07793327 0.4162001 1.07831654 1 P 0 ;0,1=358,2=270.000000
L 0.4162001 1.07831654 0.41258425 1.07755 1 P 0 ;0,1=358,2=270.000000
L 0.41258425 1.07755 0.41000049 1.07486654 1 P 0 ;0,1=358,2=270.000000
L 0.41000049 1.07486654 0.40896644 1.07218307 1 P 0 ;0,1=358,2=270.000000
L 0.40896644 1.07218307 0.40896644 1.06873307 1 P 0 ;0,1=358,2=270.000000
L 0.40896644 1.07218307 0.40741683 1.07448327 1 P 0 ;0,1=358,2=270.000000
L 0.40741683 1.07448327 0.40483406 1.0764002 1 P 0 ;0,1=358,2=270.000000
L 0.40483406 1.0764002 0.40173376 1.07716673 1 P 0 ;0,1=358,2=270.000000
L 0.40173376 1.07716673 0.39863346 1.0764002 1 P 0 ;0,1=358,2=270.000000
L 0.39863346 1.0764002 0.39605069 1.07448327 1 P 0 ;0,1=358,2=270.000000
L 0.39605069 1.07448327 0.3945 1.07103327 1 P 0 ;0,1=358,2=270.000000
L 0.3945 1.07103327 0.39501663 1.06758337 1 P 0 ;0,1=358,2=270.000000
L 0.39501663 1.06758337 0.39708376 1.06413337 1 P 0 ;0,1=358,2=270.000000
L 0.4255 1.09973307 0.41878386 1.10049961 1 P 0 ;0,1=358,2=270.000000
L 0.41878386 1.10049961 0.41310079 1.1016501 1 P 0 ;0,1=358,2=270.000000
L 0.41310079 1.1016501 0.40793337 1.10318307 1 P 0 ;0,1=358,2=270.000000
L 0.40793337 1.10318307 0.4022503 1.1051 1 P 0 ;0,1=358,2=270.000000
L 0.4022503 1.1051 0.3945 1.10816673 1 P 0 ;0,1=358,2=270.000000
L 0.3945 1.10816673 0.3945 1.09283317 1 P 0 ;0,1=358,2=270.000000
L 0.4255 1.13073307 0.41878386 1.13149961 1 P 0 ;0,1=358,2=270.000000
L 0.41878386 1.13149961 0.41310079 1.1326501 1 P 0 ;0,1=358,2=270.000000
L 0.41310079 1.1326501 0.40793337 1.13418307 1 P 0 ;0,1=358,2=270.000000
L 0.40793337 1.13418307 0.4022503 1.1361 1 P 0 ;0,1=358,2=270.000000
L 0.4022503 1.1361 0.3945 1.13916673 1 P 0 ;0,1=358,2=270.000000
L 0.3945 1.13916673 0.3945 1.12383317 1 P 0 ;0,1=358,2=270.000000
L 0.602 0.95 0.558 0.95 1 P 0 
L 0.558 0.95 0.558 0.86 1 P 0 
L 0.558 0.86 0.602 0.86 1 P 0 
L 0.602 0.86 0.602 0.95 1 P 0 
L 0.4505 0.82583317 0.4195 0.82583317 1 P 0 ;0,1=359,2=270.000000
L 0.4195 0.82583317 0.4195 0.83541654 1 P 0 ;0,1=359,2=270.000000
L 0.4195 0.83541654 0.42105069 0.83848327 1 P 0 ;0,1=359,2=270.000000
L 0.42105069 0.83848327 0.42311693 0.8404002 1 P 0 ;0,1=359,2=270.000000
L 0.42311693 0.8404002 0.4272503 0.84116673 1 P 0 ;0,1=359,2=270.000000
L 0.4272503 0.84116673 0.43138366 0.8404002 1 P 0 ;0,1=359,2=270.000000
L 0.43138366 0.8404002 0.43396644 0.8381 1 P 0 ;0,1=359,2=270.000000
L 0.43396644 0.8381 0.43551713 0.83541654 1 P 0 ;0,1=359,2=270.000000
L 0.43551713 0.83541654 0.43551713 0.82583317 1 P 0 ;0,1=359,2=270.000000
L 0.43551713 0.83541654 0.4505 0.84116673 1 P 0 ;0,1=359,2=270.000000
L 0.44430039 0.85606663 0.44791722 0.85836614 1 P 0 ;0,1=359,2=270.000000
L 0.44791722 0.85836614 0.44998346 0.86143287 1 P 0 ;0,1=359,2=270.000000
L 0.44998346 0.86143287 0.4505 0.86488356 1 P 0 ;0,1=359,2=270.000000
L 0.4505 0.86488356 0.44998346 0.8679503 1 P 0 ;0,1=359,2=270.000000
L 0.44998346 0.8679503 0.44740069 0.87101703 1 P 0 ;0,1=359,2=270.000000
L 0.44740069 0.87101703 0.44430039 0.87293327 1 P 0 ;0,1=359,2=270.000000
L 0.44430039 0.87293327 0.4412001 0.87331654 1 P 0 ;0,1=359,2=270.000000
L 0.4412001 0.87331654 0.43758425 0.87255 1 P 0 ;0,1=359,2=270.000000
L 0.43758425 0.87255 0.43500049 0.86986654 1 P 0 ;0,1=359,2=270.000000
L 0.43500049 0.86986654 0.43396644 0.86718307 1 P 0 ;0,1=359,2=270.000000
L 0.43396644 0.86718307 0.43396644 0.86373307 1 P 0 ;0,1=359,2=270.000000
L 0.43396644 0.86718307 0.43241683 0.86948327 1 P 0 ;0,1=359,2=270.000000
L 0.43241683 0.86948327 0.42983406 0.8714002 1 P 0 ;0,1=359,2=270.000000
L 0.42983406 0.8714002 0.42673376 0.87216673 1 P 0 ;0,1=359,2=270.000000
L 0.42673376 0.87216673 0.42363346 0.8714002 1 P 0 ;0,1=359,2=270.000000
L 0.42363346 0.8714002 0.42105069 0.86948327 1 P 0 ;0,1=359,2=270.000000
L 0.42105069 0.86948327 0.4195 0.86603327 1 P 0 ;0,1=359,2=270.000000
L 0.4195 0.86603327 0.42001663 0.86258337 1 P 0 ;0,1=359,2=270.000000
L 0.42001663 0.86258337 0.42208376 0.85913337 1 P 0 ;0,1=359,2=270.000000
L 0.43758425 0.88821644 0.43396644 0.8908999 1 P 0 ;0,1=359,2=270.000000
L 0.43396644 0.8908999 0.4319002 0.8932001 1 P 0 ;0,1=359,2=270.000000
L 0.4319002 0.8932001 0.43086713 0.89626683 1 P 0 ;0,1=359,2=270.000000
L 0.43086713 0.89626683 0.4319002 0.8989503 1 P 0 ;0,1=359,2=270.000000
L 0.4319002 0.8989503 0.43396644 0.90086654 1 P 0 ;0,1=359,2=270.000000
L 0.43396644 0.90086654 0.43706673 0.9024002 1 P 0 ;0,1=359,2=270.000000
L 0.43706673 0.9024002 0.44068356 0.90278346 1 P 0 ;0,1=359,2=270.000000
L 0.44068356 0.90278346 0.44378386 0.9024002 1 P 0 ;0,1=359,2=270.000000
L 0.44378386 0.9024002 0.44688415 0.90086654 1 P 0 ;0,1=359,2=270.000000
L 0.44688415 0.90086654 0.44946693 0.89856634 1 P 0 ;0,1=359,2=270.000000
L 0.44946693 0.89856634 0.4505 0.89588356 1 P 0 ;0,1=359,2=270.000000
L 0.4505 0.89588356 0.44946693 0.89281683 1 P 0 ;0,1=359,2=270.000000
L 0.44946693 0.89281683 0.44636762 0.89013337 1 P 0 ;0,1=359,2=270.000000
L 0.44636762 0.89013337 0.44171673 0.8885997 1 P 0 ;0,1=359,2=270.000000
L 0.44171673 0.8885997 0.4365502 0.88821644 1 P 0 ;0,1=359,2=270.000000
L 0.4365502 0.88821644 0.42983406 0.88898287 1 P 0 ;0,1=359,2=270.000000
L 0.42983406 0.88898287 0.42621624 0.89013337 1 P 0 ;0,1=359,2=270.000000
L 0.42621624 0.89013337 0.4226003 0.89204961 1 P 0 ;0,1=359,2=270.000000
L 0.4226003 0.89204961 0.42001663 0.89473307 1 P 0 ;0,1=359,2=270.000000
L 0.42001663 0.89473307 0.4195 0.89741654 1 P 0 ;0,1=359,2=270.000000
L 0.4195 0.89741654 0.42053317 0.9001 1 P 0 ;0,1=359,2=270.000000
L 0.42053317 0.9001 0.42311693 0.90201703 1 P 0 ;0,1=359,2=270.000000
L 0.4505 0.92649961 0.44998346 0.92918307 1 P 0 ;0,1=359,2=270.000000
L 0.44998346 0.92918307 0.44843386 0.9322498 1 P 0 ;0,1=359,2=270.000000
L 0.44843386 0.9322498 0.44585108 0.93416673 1 P 0 ;0,1=359,2=270.000000
L 0.44585108 0.93416673 0.44223327 0.93493327 1 P 0 ;0,1=359,2=270.000000
L 0.44223327 0.93493327 0.43861732 0.93416673 1 P 0 ;0,1=359,2=270.000000
L 0.43861732 0.93416673 0.43551713 0.93186654 1 P 0 ;0,1=359,2=270.000000
L 0.43551713 0.93186654 0.43396644 0.92841654 1 P 0 ;0,1=359,2=270.000000
L 0.43396644 0.92841654 0.43396644 0.92458337 1 P 0 ;0,1=359,2=270.000000
L 0.43396644 0.92458337 0.43293337 0.92228317 1 P 0 ;0,1=359,2=270.000000
L 0.43293337 0.92228317 0.43035059 0.92036614 1 P 0 ;0,1=359,2=270.000000
L 0.43035059 0.92036614 0.42673376 0.9195997 1 P 0 ;0,1=359,2=270.000000
L 0.42673376 0.9195997 0.42311693 0.9207501 1 P 0 ;0,1=359,2=270.000000
L 0.42311693 0.9207501 0.42053317 0.92343287 1 P 0 ;0,1=359,2=270.000000
L 0.42053317 0.92343287 0.4195 0.92649961 1 P 0 ;0,1=359,2=270.000000
L 0.4195 0.92649961 0.42053317 0.92956634 1 P 0 ;0,1=359,2=270.000000
L 0.42053317 0.92956634 0.42311693 0.9322498 1 P 0 ;0,1=359,2=270.000000
L 0.42311693 0.9322498 0.42673376 0.9334002 1 P 0 ;0,1=359,2=270.000000
L 0.42673376 0.9334002 0.43035059 0.93263307 1 P 0 ;0,1=359,2=270.000000
L 0.43035059 0.93263307 0.43293337 0.93071673 1 P 0 ;0,1=359,2=270.000000
L 0.43293337 0.93071673 0.43396644 0.92841654 1 P 0 ;0,1=359,2=270.000000
L 0.43396644 0.92841654 0.43396644 0.92458337 1 P 0 ;0,1=359,2=270.000000
L 0.43396644 0.92458337 0.43551713 0.92113337 1 P 0 ;0,1=359,2=270.000000
L 0.43551713 0.92113337 0.43861732 0.91883317 1 P 0 ;0,1=359,2=270.000000
L 0.43861732 0.91883317 0.44223327 0.91806663 1 P 0 ;0,1=359,2=270.000000
L 0.44223327 0.91806663 0.44585108 0.91883317 1 P 0 ;0,1=359,2=270.000000
L 0.44585108 0.91883317 0.44843386 0.9207501 1 P 0 ;0,1=359,2=270.000000
L 0.44843386 0.9207501 0.44998346 0.92381683 1 P 0 ;0,1=359,2=270.000000
L 0.44998346 0.92381683 0.4505 0.92649961 1 P 0 ;0,1=359,2=270.000000
L 0.354 2.64008002 0.354 2.73008002 1 P 0 
L 0.354 2.73008002 0.31 2.73008002 1 P 0 
L 0.31 2.73008002 0.31 2.64008002 1 P 0 
L 0.31 2.64008002 0.354 2.64008002 1 P 0 
L 0.3255 2.77083317 0.2945 2.77083317 1 P 0 ;0,1=360,2=270.000000
L 0.2945 2.77083317 0.2945 2.78041654 1 P 0 ;0,1=360,2=270.000000
L 0.2945 2.78041654 0.29605069 2.78348327 1 P 0 ;0,1=360,2=270.000000
L 0.29605069 2.78348327 0.29811693 2.7854002 1 P 0 ;0,1=360,2=270.000000
L 0.29811693 2.7854002 0.3022503 2.78616673 1 P 0 ;0,1=360,2=270.000000
L 0.3022503 2.78616673 0.30638366 2.7854002 1 P 0 ;0,1=360,2=270.000000
L 0.30638366 2.7854002 0.30896644 2.7831 1 P 0 ;0,1=360,2=270.000000
L 0.30896644 2.7831 0.31051713 2.78041654 1 P 0 ;0,1=360,2=270.000000
L 0.31051713 2.78041654 0.31051713 2.77083317 1 P 0 ;0,1=360,2=270.000000
L 0.31051713 2.78041654 0.3255 2.78616673 1 P 0 ;0,1=360,2=270.000000
L 0.31930039 2.80106663 0.32291722 2.80336614 1 P 0 ;0,1=360,2=270.000000
L 0.32291722 2.80336614 0.32498346 2.80643287 1 P 0 ;0,1=360,2=270.000000
L 0.32498346 2.80643287 0.3255 2.80988356 1 P 0 ;0,1=360,2=270.000000
L 0.3255 2.80988356 0.32498346 2.8129503 1 P 0 ;0,1=360,2=270.000000
L 0.32498346 2.8129503 0.32240069 2.81601703 1 P 0 ;0,1=360,2=270.000000
L 0.32240069 2.81601703 0.31930039 2.81793327 1 P 0 ;0,1=360,2=270.000000
L 0.31930039 2.81793327 0.3162001 2.81831654 1 P 0 ;0,1=360,2=270.000000
L 0.3162001 2.81831654 0.31258425 2.81755 1 P 0 ;0,1=360,2=270.000000
L 0.31258425 2.81755 0.31000049 2.81486654 1 P 0 ;0,1=360,2=270.000000
L 0.31000049 2.81486654 0.30896644 2.81218307 1 P 0 ;0,1=360,2=270.000000
L 0.30896644 2.81218307 0.30896644 2.80873307 1 P 0 ;0,1=360,2=270.000000
L 0.30896644 2.81218307 0.30741683 2.81448327 1 P 0 ;0,1=360,2=270.000000
L 0.30741683 2.81448327 0.30483406 2.8164002 1 P 0 ;0,1=360,2=270.000000
L 0.30483406 2.8164002 0.30173376 2.81716673 1 P 0 ;0,1=360,2=270.000000
L 0.30173376 2.81716673 0.29863346 2.8164002 1 P 0 ;0,1=360,2=270.000000
L 0.29863346 2.8164002 0.29605069 2.81448327 1 P 0 ;0,1=360,2=270.000000
L 0.29605069 2.81448327 0.2945 2.81103327 1 P 0 ;0,1=360,2=270.000000
L 0.2945 2.81103327 0.29501663 2.80758337 1 P 0 ;0,1=360,2=270.000000
L 0.29501663 2.80758337 0.29708376 2.80413337 1 P 0 ;0,1=360,2=270.000000
L 0.32188415 2.83398287 0.32446693 2.83666634 1 P 0 ;0,1=360,2=270.000000
L 0.32446693 2.83666634 0.3255 2.83973307 1 P 0 ;0,1=360,2=270.000000
L 0.3255 2.83973307 0.32446693 2.8427998 1 P 0 ;0,1=360,2=270.000000
L 0.32446693 2.8427998 0.32136762 2.84548327 1 P 0 ;0,1=360,2=270.000000
L 0.32136762 2.84548327 0.31671673 2.8474002 1 P 0 ;0,1=360,2=270.000000
L 0.31671673 2.8474002 0.31206673 2.84816673 1 P 0 ;0,1=360,2=270.000000
L 0.31206673 2.84816673 0.30638366 2.84816673 1 P 0 ;0,1=360,2=270.000000
L 0.30638366 2.84816673 0.30173376 2.8474002 1 P 0 ;0,1=360,2=270.000000
L 0.30173376 2.8474002 0.2976003 2.84548327 1 P 0 ;0,1=360,2=270.000000
L 0.2976003 2.84548327 0.29553317 2.84318307 1 P 0 ;0,1=360,2=270.000000
L 0.29553317 2.84318307 0.2945 2.84049961 1 P 0 ;0,1=360,2=270.000000
L 0.2945 2.84049961 0.29553317 2.83743287 1 P 0 ;0,1=360,2=270.000000
L 0.29553317 2.83743287 0.2976003 2.83513337 1 P 0 ;0,1=360,2=270.000000
L 0.2976003 2.83513337 0.3006997 2.8335997 1 P 0 ;0,1=360,2=270.000000
L 0.3006997 2.8335997 0.30483406 2.83283317 1 P 0 ;0,1=360,2=270.000000
L 0.30483406 2.83283317 0.3084499 2.8335997 1 P 0 ;0,1=360,2=270.000000
L 0.3084499 2.8335997 0.31206673 2.83551663 1 P 0 ;0,1=360,2=270.000000
L 0.31206673 2.83551663 0.31413396 2.83781683 1 P 0 ;0,1=360,2=270.000000
L 0.31413396 2.83781683 0.31465049 2.84049961 1 P 0 ;0,1=360,2=270.000000
L 0.31465049 2.84049961 0.31361732 2.84356634 1 P 0 ;0,1=360,2=270.000000
L 0.31361732 2.84356634 0.31103366 2.84586654 1 P 0 ;0,1=360,2=270.000000
L 0.31103366 2.84586654 0.30638366 2.84816673 1 P 0 ;0,1=360,2=270.000000
L 0.31930039 2.86306663 0.32291722 2.86536614 1 P 0 ;0,1=360,2=270.000000
L 0.32291722 2.86536614 0.32498346 2.86843287 1 P 0 ;0,1=360,2=270.000000
L 0.32498346 2.86843287 0.3255 2.87188356 1 P 0 ;0,1=360,2=270.000000
L 0.3255 2.87188356 0.32498346 2.8749503 1 P 0 ;0,1=360,2=270.000000
L 0.32498346 2.8749503 0.32240069 2.87801703 1 P 0 ;0,1=360,2=270.000000
L 0.32240069 2.87801703 0.31930039 2.87993327 1 P 0 ;0,1=360,2=270.000000
L 0.31930039 2.87993327 0.3162001 2.88031654 1 P 0 ;0,1=360,2=270.000000
L 0.3162001 2.88031654 0.31258425 2.87955 1 P 0 ;0,1=360,2=270.000000
L 0.31258425 2.87955 0.31000049 2.87686654 1 P 0 ;0,1=360,2=270.000000
L 0.31000049 2.87686654 0.30896644 2.87418307 1 P 0 ;0,1=360,2=270.000000
L 0.30896644 2.87418307 0.30896644 2.87073307 1 P 0 ;0,1=360,2=270.000000
L 0.30896644 2.87418307 0.30741683 2.87648327 1 P 0 ;0,1=360,2=270.000000
L 0.30741683 2.87648327 0.30483406 2.8784002 1 P 0 ;0,1=360,2=270.000000
L 0.30483406 2.8784002 0.30173376 2.87916673 1 P 0 ;0,1=360,2=270.000000
L 0.30173376 2.87916673 0.29863346 2.8784002 1 P 0 ;0,1=360,2=270.000000
L 0.29863346 2.8784002 0.29605069 2.87648327 1 P 0 ;0,1=360,2=270.000000
L 0.29605069 2.87648327 0.2945 2.87303327 1 P 0 ;0,1=360,2=270.000000
L 0.2945 2.87303327 0.29501663 2.86958337 1 P 0 ;0,1=360,2=270.000000
L 0.29501663 2.86958337 0.29708376 2.86613337 1 P 0 ;0,1=360,2=270.000000
L 0.444 2.73008002 0.4 2.73008002 1 P 0 
L 0.444 2.64008002 0.444 2.73008002 1 P 0 
L 0.4 2.73008002 0.4 2.64008002 1 P 0 
L 0.4 2.64008002 0.444 2.64008002 1 P 0 
L 0.4205 2.76583317 0.3895 2.76583317 1 P 0 ;0,1=361,2=270.000000
L 0.3895 2.76583317 0.3895 2.77541654 1 P 0 ;0,1=361,2=270.000000
L 0.3895 2.77541654 0.39105069 2.77848327 1 P 0 ;0,1=361,2=270.000000
L 0.39105069 2.77848327 0.39311693 2.7804002 1 P 0 ;0,1=361,2=270.000000
L 0.39311693 2.7804002 0.3972503 2.78116673 1 P 0 ;0,1=361,2=270.000000
L 0.3972503 2.78116673 0.40138366 2.7804002 1 P 0 ;0,1=361,2=270.000000
L 0.40138366 2.7804002 0.40396644 2.7781 1 P 0 ;0,1=361,2=270.000000
L 0.40396644 2.7781 0.40551713 2.77541654 1 P 0 ;0,1=361,2=270.000000
L 0.40551713 2.77541654 0.40551713 2.76583317 1 P 0 ;0,1=361,2=270.000000
L 0.40551713 2.77541654 0.4205 2.78116673 1 P 0 ;0,1=361,2=270.000000
L 0.41430039 2.79606663 0.41791722 2.79836614 1 P 0 ;0,1=361,2=270.000000
L 0.41791722 2.79836614 0.41998346 2.80143287 1 P 0 ;0,1=361,2=270.000000
L 0.41998346 2.80143287 0.4205 2.80488356 1 P 0 ;0,1=361,2=270.000000
L 0.4205 2.80488356 0.41998346 2.8079503 1 P 0 ;0,1=361,2=270.000000
L 0.41998346 2.8079503 0.41740069 2.81101703 1 P 0 ;0,1=361,2=270.000000
L 0.41740069 2.81101703 0.41430039 2.81293327 1 P 0 ;0,1=361,2=270.000000
L 0.41430039 2.81293327 0.4112001 2.81331654 1 P 0 ;0,1=361,2=270.000000
L 0.4112001 2.81331654 0.40758425 2.81255 1 P 0 ;0,1=361,2=270.000000
L 0.40758425 2.81255 0.40500049 2.80986654 1 P 0 ;0,1=361,2=270.000000
L 0.40500049 2.80986654 0.40396644 2.80718307 1 P 0 ;0,1=361,2=270.000000
L 0.40396644 2.80718307 0.40396644 2.80373307 1 P 0 ;0,1=361,2=270.000000
L 0.40396644 2.80718307 0.40241683 2.80948327 1 P 0 ;0,1=361,2=270.000000
L 0.40241683 2.80948327 0.39983406 2.8114002 1 P 0 ;0,1=361,2=270.000000
L 0.39983406 2.8114002 0.39673376 2.81216673 1 P 0 ;0,1=361,2=270.000000
L 0.39673376 2.81216673 0.39363346 2.8114002 1 P 0 ;0,1=361,2=270.000000
L 0.39363346 2.8114002 0.39105069 2.80948327 1 P 0 ;0,1=361,2=270.000000
L 0.39105069 2.80948327 0.3895 2.80603327 1 P 0 ;0,1=361,2=270.000000
L 0.3895 2.80603327 0.39001663 2.80258337 1 P 0 ;0,1=361,2=270.000000
L 0.39001663 2.80258337 0.39208376 2.79913337 1 P 0 ;0,1=361,2=270.000000
L 0.4205 2.83473307 0.41378386 2.83549961 1 P 0 ;0,1=361,2=270.000000
L 0.41378386 2.83549961 0.40810079 2.8366501 1 P 0 ;0,1=361,2=270.000000
L 0.40810079 2.8366501 0.40293337 2.83818307 1 P 0 ;0,1=361,2=270.000000
L 0.40293337 2.83818307 0.3972503 2.8401 1 P 0 ;0,1=361,2=270.000000
L 0.3972503 2.8401 0.3895 2.84316673 1 P 0 ;0,1=361,2=270.000000
L 0.3895 2.84316673 0.3895 2.82783317 1 P 0 ;0,1=361,2=270.000000
L 0.41585108 2.85806663 0.41843386 2.86036614 1 P 0 ;0,1=361,2=270.000000
L 0.41843386 2.86036614 0.41998346 2.86304961 1 P 0 ;0,1=361,2=270.000000
L 0.41998346 2.86304961 0.4205 2.86649961 1 P 0 ;0,1=361,2=270.000000
L 0.4205 2.86649961 0.41946693 2.8699503 1 P 0 ;0,1=361,2=270.000000
L 0.41946693 2.8699503 0.41740069 2.87263307 1 P 0 ;0,1=361,2=270.000000
L 0.41740069 2.87263307 0.41378386 2.87455 1 P 0 ;0,1=361,2=270.000000
L 0.41378386 2.87455 0.40965049 2.87493327 1 P 0 ;0,1=361,2=270.000000
L 0.40965049 2.87493327 0.40551713 2.87416673 1 P 0 ;0,1=361,2=270.000000
L 0.40551713 2.87416673 0.40293337 2.8722498 1 P 0 ;0,1=361,2=270.000000
L 0.40293337 2.8722498 0.40086713 2.86956634 1 P 0 ;0,1=361,2=270.000000
L 0.40086713 2.86956634 0.40035059 2.86688356 1 P 0 ;0,1=361,2=270.000000
L 0.40035059 2.86688356 0.40086713 2.8642001 1 P 0 ;0,1=361,2=270.000000
L 0.40086713 2.8642001 0.40293337 2.8607501 1 P 0 ;0,1=361,2=270.000000
L 0.40293337 2.8607501 0.3895 2.8618999 1 P 0 ;0,1=361,2=270.000000
L 0.3895 2.8618999 0.3895 2.8722498 1 P 0 ;0,1=361,2=270.000000
L 0.399 2.73008002 0.355 2.73008002 1 P 0 
L 0.399 2.64008002 0.399 2.73008002 1 P 0 
L 0.355 2.73008002 0.355 2.64008002 1 P 0 
L 0.355 2.64008002 0.399 2.64008002 1 P 0 
L 0.3655 2.77083317 0.3345 2.77083317 1 P 0 ;0,1=362,2=270.000000
L 0.3345 2.77083317 0.3345 2.78041654 1 P 0 ;0,1=362,2=270.000000
L 0.3345 2.78041654 0.33605069 2.78348327 1 P 0 ;0,1=362,2=270.000000
L 0.33605069 2.78348327 0.33811693 2.7854002 1 P 0 ;0,1=362,2=270.000000
L 0.33811693 2.7854002 0.3422503 2.78616673 1 P 0 ;0,1=362,2=270.000000
L 0.3422503 2.78616673 0.34638366 2.7854002 1 P 0 ;0,1=362,2=270.000000
L 0.34638366 2.7854002 0.34896644 2.7831 1 P 0 ;0,1=362,2=270.000000
L 0.34896644 2.7831 0.35051713 2.78041654 1 P 0 ;0,1=362,2=270.000000
L 0.35051713 2.78041654 0.35051713 2.77083317 1 P 0 ;0,1=362,2=270.000000
L 0.35051713 2.78041654 0.3655 2.78616673 1 P 0 ;0,1=362,2=270.000000
L 0.35930039 2.80106663 0.36291722 2.80336614 1 P 0 ;0,1=362,2=270.000000
L 0.36291722 2.80336614 0.36498346 2.80643287 1 P 0 ;0,1=362,2=270.000000
L 0.36498346 2.80643287 0.3655 2.80988356 1 P 0 ;0,1=362,2=270.000000
L 0.3655 2.80988356 0.36498346 2.8129503 1 P 0 ;0,1=362,2=270.000000
L 0.36498346 2.8129503 0.36240069 2.81601703 1 P 0 ;0,1=362,2=270.000000
L 0.36240069 2.81601703 0.35930039 2.81793327 1 P 0 ;0,1=362,2=270.000000
L 0.35930039 2.81793327 0.3562001 2.81831654 1 P 0 ;0,1=362,2=270.000000
L 0.3562001 2.81831654 0.35258425 2.81755 1 P 0 ;0,1=362,2=270.000000
L 0.35258425 2.81755 0.35000049 2.81486654 1 P 0 ;0,1=362,2=270.000000
L 0.35000049 2.81486654 0.34896644 2.81218307 1 P 0 ;0,1=362,2=270.000000
L 0.34896644 2.81218307 0.34896644 2.80873307 1 P 0 ;0,1=362,2=270.000000
L 0.34896644 2.81218307 0.34741683 2.81448327 1 P 0 ;0,1=362,2=270.000000
L 0.34741683 2.81448327 0.34483406 2.8164002 1 P 0 ;0,1=362,2=270.000000
L 0.34483406 2.8164002 0.34173376 2.81716673 1 P 0 ;0,1=362,2=270.000000
L 0.34173376 2.81716673 0.33863346 2.8164002 1 P 0 ;0,1=362,2=270.000000
L 0.33863346 2.8164002 0.33605069 2.81448327 1 P 0 ;0,1=362,2=270.000000
L 0.33605069 2.81448327 0.3345 2.81103327 1 P 0 ;0,1=362,2=270.000000
L 0.3345 2.81103327 0.33501663 2.80758337 1 P 0 ;0,1=362,2=270.000000
L 0.33501663 2.80758337 0.33708376 2.80413337 1 P 0 ;0,1=362,2=270.000000
L 0.36188415 2.83398287 0.36446693 2.83666634 1 P 0 ;0,1=362,2=270.000000
L 0.36446693 2.83666634 0.3655 2.83973307 1 P 0 ;0,1=362,2=270.000000
L 0.3655 2.83973307 0.36446693 2.8427998 1 P 0 ;0,1=362,2=270.000000
L 0.36446693 2.8427998 0.36136762 2.84548327 1 P 0 ;0,1=362,2=270.000000
L 0.36136762 2.84548327 0.35671673 2.8474002 1 P 0 ;0,1=362,2=270.000000
L 0.35671673 2.8474002 0.35206673 2.84816673 1 P 0 ;0,1=362,2=270.000000
L 0.35206673 2.84816673 0.34638366 2.84816673 1 P 0 ;0,1=362,2=270.000000
L 0.34638366 2.84816673 0.34173376 2.8474002 1 P 0 ;0,1=362,2=270.000000
L 0.34173376 2.8474002 0.3376003 2.84548327 1 P 0 ;0,1=362,2=270.000000
L 0.3376003 2.84548327 0.33553317 2.84318307 1 P 0 ;0,1=362,2=270.000000
L 0.33553317 2.84318307 0.3345 2.84049961 1 P 0 ;0,1=362,2=270.000000
L 0.3345 2.84049961 0.33553317 2.83743287 1 P 0 ;0,1=362,2=270.000000
L 0.33553317 2.83743287 0.3376003 2.83513337 1 P 0 ;0,1=362,2=270.000000
L 0.3376003 2.83513337 0.3406997 2.8335997 1 P 0 ;0,1=362,2=270.000000
L 0.3406997 2.8335997 0.34483406 2.83283317 1 P 0 ;0,1=362,2=270.000000
L 0.34483406 2.83283317 0.3484499 2.8335997 1 P 0 ;0,1=362,2=270.000000
L 0.3484499 2.8335997 0.35206673 2.83551663 1 P 0 ;0,1=362,2=270.000000
L 0.35206673 2.83551663 0.35413396 2.83781683 1 P 0 ;0,1=362,2=270.000000
L 0.35413396 2.83781683 0.35465049 2.84049961 1 P 0 ;0,1=362,2=270.000000
L 0.35465049 2.84049961 0.35361732 2.84356634 1 P 0 ;0,1=362,2=270.000000
L 0.35361732 2.84356634 0.35103366 2.84586654 1 P 0 ;0,1=362,2=270.000000
L 0.35103366 2.84586654 0.34638366 2.84816673 1 P 0 ;0,1=362,2=270.000000
L 0.33966654 2.86421644 0.33656722 2.86651663 1 P 0 ;0,1=362,2=270.000000
L 0.33656722 2.86651663 0.33501663 2.8692001 1 P 0 ;0,1=362,2=270.000000
L 0.33501663 2.8692001 0.3345 2.87226683 1 P 0 ;0,1=362,2=270.000000
L 0.3345 2.87226683 0.33553317 2.8761 1 P 0 ;0,1=362,2=270.000000
L 0.33553317 2.8761 0.33811693 2.87878346 1 P 0 ;0,1=362,2=270.000000
L 0.33811693 2.87878346 0.34121624 2.87955 1 P 0 ;0,1=362,2=270.000000
L 0.34121624 2.87955 0.34431742 2.87916673 1 P 0 ;0,1=362,2=270.000000
L 0.34431742 2.87916673 0.3469002 2.87763307 1 P 0 ;0,1=362,2=270.000000
L 0.3469002 2.87763307 0.35206673 2.86996663 1 P 0 ;0,1=362,2=270.000000
L 0.35206673 2.86996663 0.35568356 2.86651663 1 P 0 ;0,1=362,2=270.000000
L 0.35568356 2.86651663 0.36085108 2.86421644 1 P 0 ;0,1=362,2=270.000000
L 0.36085108 2.86421644 0.3655 2.8634499 1 P 0 ;0,1=362,2=270.000000
L 0.3655 2.8634499 0.3655 2.87955 1 P 0 ;0,1=362,2=270.000000
L 0.81146998 1.907 0.72146998 1.907 1 P 0 
L 0.72146998 1.907 0.72146998 1.863 1 P 0 
L 0.72146998 1.863 0.81146998 1.863 1 P 0 
L 0.81146998 1.863 0.81146998 1.907 1 P 0 
L 0.85083317 1.8695 0.85083317 1.9005 1 P 0 ;0,1=363,2=0.000000
L 0.85083317 1.9005 0.86041654 1.9005 1 P 0 ;0,1=363,2=0.000000
L 0.86041654 1.9005 0.86348327 1.89894931 1 P 0 ;0,1=363,2=0.000000
L 0.86348327 1.89894931 0.8654002 1.89688307 1 P 0 ;0,1=363,2=0.000000
L 0.8654002 1.89688307 0.86616673 1.8927497 1 P 0 ;0,1=363,2=0.000000
L 0.86616673 1.8927497 0.8654002 1.88861634 1 P 0 ;0,1=363,2=0.000000
L 0.8654002 1.88861634 0.8631 1.88603356 1 P 0 ;0,1=363,2=0.000000
L 0.8631 1.88603356 0.86041654 1.88448287 1 P 0 ;0,1=363,2=0.000000
L 0.86041654 1.88448287 0.85083317 1.88448287 1 P 0 ;0,1=363,2=0.000000
L 0.86041654 1.88448287 0.86616673 1.8695 1 P 0 ;0,1=363,2=0.000000
L 0.88106663 1.87569961 0.88336614 1.87208278 1 P 0 ;0,1=363,2=0.000000
L 0.88336614 1.87208278 0.88643287 1.87001654 1 P 0 ;0,1=363,2=0.000000
L 0.88643287 1.87001654 0.88988356 1.8695 1 P 0 ;0,1=363,2=0.000000
L 0.88988356 1.8695 0.8929503 1.87001654 1 P 0 ;0,1=363,2=0.000000
L 0.8929503 1.87001654 0.89601703 1.87259931 1 P 0 ;0,1=363,2=0.000000
L 0.89601703 1.87259931 0.89793327 1.87569961 1 P 0 ;0,1=363,2=0.000000
L 0.89793327 1.87569961 0.89831654 1.8787999 1 P 0 ;0,1=363,2=0.000000
L 0.89831654 1.8787999 0.89755 1.88241575 1 P 0 ;0,1=363,2=0.000000
L 0.89755 1.88241575 0.89486654 1.88499951 1 P 0 ;0,1=363,2=0.000000
L 0.89486654 1.88499951 0.89218307 1.88603356 1 P 0 ;0,1=363,2=0.000000
L 0.89218307 1.88603356 0.88873307 1.88603356 1 P 0 ;0,1=363,2=0.000000
L 0.89218307 1.88603356 0.89448327 1.88758317 1 P 0 ;0,1=363,2=0.000000
L 0.89448327 1.88758317 0.8964002 1.89016594 1 P 0 ;0,1=363,2=0.000000
L 0.8964002 1.89016594 0.89716673 1.89326624 1 P 0 ;0,1=363,2=0.000000
L 0.89716673 1.89326624 0.8964002 1.89636654 1 P 0 ;0,1=363,2=0.000000
L 0.8964002 1.89636654 0.89448327 1.89894931 1 P 0 ;0,1=363,2=0.000000
L 0.89448327 1.89894931 0.89103327 1.9005 1 P 0 ;0,1=363,2=0.000000
L 0.89103327 1.9005 0.88758337 1.89998337 1 P 0 ;0,1=363,2=0.000000
L 0.88758337 1.89998337 0.88413337 1.89791624 1 P 0 ;0,1=363,2=0.000000
L 0.91398287 1.87311585 0.91666634 1.87053307 1 P 0 ;0,1=363,2=0.000000
L 0.91666634 1.87053307 0.91973307 1.8695 1 P 0 ;0,1=363,2=0.000000
L 0.91973307 1.8695 0.9227998 1.87053307 1 P 0 ;0,1=363,2=0.000000
L 0.9227998 1.87053307 0.92548327 1.87363238 1 P 0 ;0,1=363,2=0.000000
L 0.92548327 1.87363238 0.9274002 1.87828327 1 P 0 ;0,1=363,2=0.000000
L 0.9274002 1.87828327 0.92816673 1.88293327 1 P 0 ;0,1=363,2=0.000000
L 0.92816673 1.88293327 0.92816673 1.88861634 1 P 0 ;0,1=363,2=0.000000
L 0.92816673 1.88861634 0.9274002 1.89326624 1 P 0 ;0,1=363,2=0.000000
L 0.9274002 1.89326624 0.92548327 1.8973997 1 P 0 ;0,1=363,2=0.000000
L 0.92548327 1.8973997 0.92318307 1.89946683 1 P 0 ;0,1=363,2=0.000000
L 0.92318307 1.89946683 0.92049961 1.9005 1 P 0 ;0,1=363,2=0.000000
L 0.92049961 1.9005 0.91743287 1.89946683 1 P 0 ;0,1=363,2=0.000000
L 0.91743287 1.89946683 0.91513337 1.8973997 1 P 0 ;0,1=363,2=0.000000
L 0.91513337 1.8973997 0.9135997 1.8943003 1 P 0 ;0,1=363,2=0.000000
L 0.9135997 1.8943003 0.91283317 1.89016594 1 P 0 ;0,1=363,2=0.000000
L 0.91283317 1.89016594 0.9135997 1.8865501 1 P 0 ;0,1=363,2=0.000000
L 0.9135997 1.8865501 0.91551663 1.88293327 1 P 0 ;0,1=363,2=0.000000
L 0.91551663 1.88293327 0.91781683 1.88086604 1 P 0 ;0,1=363,2=0.000000
L 0.91781683 1.88086604 0.92049961 1.88034951 1 P 0 ;0,1=363,2=0.000000
L 0.92049961 1.88034951 0.92356634 1.88138268 1 P 0 ;0,1=363,2=0.000000
L 0.92356634 1.88138268 0.92586654 1.88396634 1 P 0 ;0,1=363,2=0.000000
L 0.92586654 1.88396634 0.92816673 1.88861634 1 P 0 ;0,1=363,2=0.000000
L 0.94421644 1.88241575 0.9468999 1.88603356 1 P 0 ;0,1=363,2=0.000000
L 0.9468999 1.88603356 0.9492001 1.8880998 1 P 0 ;0,1=363,2=0.000000
L 0.9492001 1.8880998 0.95226683 1.88913287 1 P 0 ;0,1=363,2=0.000000
L 0.95226683 1.88913287 0.9549503 1.8880998 1 P 0 ;0,1=363,2=0.000000
L 0.9549503 1.8880998 0.95686654 1.88603356 1 P 0 ;0,1=363,2=0.000000
L 0.95686654 1.88603356 0.9584002 1.88293327 1 P 0 ;0,1=363,2=0.000000
L 0.9584002 1.88293327 0.95878346 1.87931644 1 P 0 ;0,1=363,2=0.000000
L 0.95878346 1.87931644 0.9584002 1.87621614 1 P 0 ;0,1=363,2=0.000000
L 0.9584002 1.87621614 0.95686654 1.87311585 1 P 0 ;0,1=363,2=0.000000
L 0.95686654 1.87311585 0.95456634 1.87053307 1 P 0 ;0,1=363,2=0.000000
L 0.95456634 1.87053307 0.95188356 1.8695 1 P 0 ;0,1=363,2=0.000000
L 0.95188356 1.8695 0.94881683 1.87053307 1 P 0 ;0,1=363,2=0.000000
L 0.94881683 1.87053307 0.94613337 1.87363238 1 P 0 ;0,1=363,2=0.000000
L 0.94613337 1.87363238 0.9445997 1.87828327 1 P 0 ;0,1=363,2=0.000000
L 0.9445997 1.87828327 0.94421644 1.8834498 1 P 0 ;0,1=363,2=0.000000
L 0.94421644 1.8834498 0.94498287 1.89016594 1 P 0 ;0,1=363,2=0.000000
L 0.94498287 1.89016594 0.94613337 1.89378376 1 P 0 ;0,1=363,2=0.000000
L 0.94613337 1.89378376 0.94804961 1.8973997 1 P 0 ;0,1=363,2=0.000000
L 0.94804961 1.8973997 0.95073307 1.89998337 1 P 0 ;0,1=363,2=0.000000
L 0.95073307 1.89998337 0.95341654 1.9005 1 P 0 ;0,1=363,2=0.000000
L 0.95341654 1.9005 0.9561 1.89946683 1 P 0 ;0,1=363,2=0.000000
L 0.9561 1.89946683 0.95801703 1.89688307 1 P 0 ;0,1=363,2=0.000000
L 0.81146998 1.997 0.72146998 1.997 1 P 0 
L 0.72146998 1.997 0.72146998 1.953 1 P 0 
L 0.72146998 1.953 0.81146998 1.953 1 P 0 
L 0.81146998 1.953 0.81146998 1.997 1 P 0 
L 0.82583317 1.9695 0.82583317 2.0005 1 P 0 ;0,1=364,2=0.000000
L 0.82583317 2.0005 0.83541654 2.0005 1 P 0 ;0,1=364,2=0.000000
L 0.83541654 2.0005 0.83848327 1.99894931 1 P 0 ;0,1=364,2=0.000000
L 0.83848327 1.99894931 0.8404002 1.99688307 1 P 0 ;0,1=364,2=0.000000
L 0.8404002 1.99688307 0.84116673 1.9927497 1 P 0 ;0,1=364,2=0.000000
L 0.84116673 1.9927497 0.8404002 1.98861634 1 P 0 ;0,1=364,2=0.000000
L 0.8404002 1.98861634 0.8381 1.98603356 1 P 0 ;0,1=364,2=0.000000
L 0.8381 1.98603356 0.83541654 1.98448287 1 P 0 ;0,1=364,2=0.000000
L 0.83541654 1.98448287 0.82583317 1.98448287 1 P 0 ;0,1=364,2=0.000000
L 0.83541654 1.98448287 0.84116673 1.9695 1 P 0 ;0,1=364,2=0.000000
L 0.8691 1.9695 0.8691 2.0005 1 P 0 ;0,1=364,2=0.000000
L 0.8691 2.0005 0.85491624 1.97828327 1 P 0 ;0,1=364,2=0.000000
L 0.85491624 1.97828327 0.87408366 1.97828327 1 P 0 ;0,1=364,2=0.000000
L 0.89549961 2.0005 0.89243287 1.99946683 1 P 0 ;0,1=364,2=0.000000
L 0.89243287 1.99946683 0.89013337 1.99688307 1 P 0 ;0,1=364,2=0.000000
L 0.89013337 1.99688307 0.8885997 1.99378376 1 P 0 ;0,1=364,2=0.000000
L 0.8885997 1.99378376 0.8874499 1.98964941 1 P 0 ;0,1=364,2=0.000000
L 0.8874499 1.98964941 0.88706663 1.98499951 1 P 0 ;0,1=364,2=0.000000
L 0.88706663 1.98499951 0.8874499 1.98034951 1 P 0 ;0,1=364,2=0.000000
L 0.8874499 1.98034951 0.8885997 1.97621614 1 P 0 ;0,1=364,2=0.000000
L 0.8885997 1.97621614 0.89013337 1.97311585 1 P 0 ;0,1=364,2=0.000000
L 0.89013337 1.97311585 0.89243287 1.97053307 1 P 0 ;0,1=364,2=0.000000
L 0.89243287 1.97053307 0.89549961 1.9695 1 P 0 ;0,1=364,2=0.000000
L 0.89549961 1.9695 0.89856634 1.97053307 1 P 0 ;0,1=364,2=0.000000
L 0.89856634 1.97053307 0.90086654 1.97311585 1 P 0 ;0,1=364,2=0.000000
L 0.90086654 1.97311585 0.9024002 1.97621614 1 P 0 ;0,1=364,2=0.000000
L 0.9024002 1.97621614 0.90355 1.98034951 1 P 0 ;0,1=364,2=0.000000
L 0.90355 1.98034951 0.90393327 1.98499951 1 P 0 ;0,1=364,2=0.000000
L 0.90393327 1.98499951 0.90355 1.98964941 1 P 0 ;0,1=364,2=0.000000
L 0.90355 1.98964941 0.9024002 1.99378376 1 P 0 ;0,1=364,2=0.000000
L 0.9024002 1.99378376 0.90086654 1.99688307 1 P 0 ;0,1=364,2=0.000000
L 0.90086654 1.99688307 0.89856634 1.99946683 1 P 0 ;0,1=364,2=0.000000
L 0.89856634 1.99946683 0.89549961 2.0005 1 P 0 ;0,1=364,2=0.000000
L 0.92649961 1.9695 0.92649961 2.0005 1 P 0 ;0,1=364,2=0.000000
L 0.92649961 2.0005 0.9218999 1.9943003 1 P 0 ;0,1=364,2=0.000000
L 0.9218999 1.9695 0.93109931 1.9695 1 P 0 ;0,1=364,2=0.000000
L 0.81146998 1.952 0.72146998 1.952 1 P 0 
L 0.72146998 1.952 0.72146998 1.908 1 P 0 
L 0.72146998 1.908 0.81146998 1.908 1 P 0 
L 0.81146998 1.908 0.81146998 1.952 1 P 0 
L 0.85083317 1.9245 0.85083317 1.9555 1 P 0 ;0,1=365,2=0.000000
L 0.85083317 1.9555 0.86041654 1.9555 1 P 0 ;0,1=365,2=0.000000
L 0.86041654 1.9555 0.86348327 1.95394931 1 P 0 ;0,1=365,2=0.000000
L 0.86348327 1.95394931 0.8654002 1.95188307 1 P 0 ;0,1=365,2=0.000000
L 0.8654002 1.95188307 0.86616673 1.9477497 1 P 0 ;0,1=365,2=0.000000
L 0.86616673 1.9477497 0.8654002 1.94361634 1 P 0 ;0,1=365,2=0.000000
L 0.8654002 1.94361634 0.8631 1.94103356 1 P 0 ;0,1=365,2=0.000000
L 0.8631 1.94103356 0.86041654 1.93948287 1 P 0 ;0,1=365,2=0.000000
L 0.86041654 1.93948287 0.85083317 1.93948287 1 P 0 ;0,1=365,2=0.000000
L 0.86041654 1.93948287 0.86616673 1.9245 1 P 0 ;0,1=365,2=0.000000
L 0.88106663 1.93069961 0.88336614 1.92708278 1 P 0 ;0,1=365,2=0.000000
L 0.88336614 1.92708278 0.88643287 1.92501654 1 P 0 ;0,1=365,2=0.000000
L 0.88643287 1.92501654 0.88988356 1.9245 1 P 0 ;0,1=365,2=0.000000
L 0.88988356 1.9245 0.8929503 1.92501654 1 P 0 ;0,1=365,2=0.000000
L 0.8929503 1.92501654 0.89601703 1.92759931 1 P 0 ;0,1=365,2=0.000000
L 0.89601703 1.92759931 0.89793327 1.93069961 1 P 0 ;0,1=365,2=0.000000
L 0.89793327 1.93069961 0.89831654 1.9337999 1 P 0 ;0,1=365,2=0.000000
L 0.89831654 1.9337999 0.89755 1.93741575 1 P 0 ;0,1=365,2=0.000000
L 0.89755 1.93741575 0.89486654 1.93999951 1 P 0 ;0,1=365,2=0.000000
L 0.89486654 1.93999951 0.89218307 1.94103356 1 P 0 ;0,1=365,2=0.000000
L 0.89218307 1.94103356 0.88873307 1.94103356 1 P 0 ;0,1=365,2=0.000000
L 0.89218307 1.94103356 0.89448327 1.94258317 1 P 0 ;0,1=365,2=0.000000
L 0.89448327 1.94258317 0.8964002 1.94516594 1 P 0 ;0,1=365,2=0.000000
L 0.8964002 1.94516594 0.89716673 1.94826624 1 P 0 ;0,1=365,2=0.000000
L 0.89716673 1.94826624 0.8964002 1.95136654 1 P 0 ;0,1=365,2=0.000000
L 0.8964002 1.95136654 0.89448327 1.95394931 1 P 0 ;0,1=365,2=0.000000
L 0.89448327 1.95394931 0.89103327 1.9555 1 P 0 ;0,1=365,2=0.000000
L 0.89103327 1.9555 0.88758337 1.95498337 1 P 0 ;0,1=365,2=0.000000
L 0.88758337 1.95498337 0.88413337 1.95291624 1 P 0 ;0,1=365,2=0.000000
L 0.91398287 1.92811585 0.91666634 1.92553307 1 P 0 ;0,1=365,2=0.000000
L 0.91666634 1.92553307 0.91973307 1.9245 1 P 0 ;0,1=365,2=0.000000
L 0.91973307 1.9245 0.9227998 1.92553307 1 P 0 ;0,1=365,2=0.000000
L 0.9227998 1.92553307 0.92548327 1.92863238 1 P 0 ;0,1=365,2=0.000000
L 0.92548327 1.92863238 0.9274002 1.93328327 1 P 0 ;0,1=365,2=0.000000
L 0.9274002 1.93328327 0.92816673 1.93793327 1 P 0 ;0,1=365,2=0.000000
L 0.92816673 1.93793327 0.92816673 1.94361634 1 P 0 ;0,1=365,2=0.000000
L 0.92816673 1.94361634 0.9274002 1.94826624 1 P 0 ;0,1=365,2=0.000000
L 0.9274002 1.94826624 0.92548327 1.9523997 1 P 0 ;0,1=365,2=0.000000
L 0.92548327 1.9523997 0.92318307 1.95446683 1 P 0 ;0,1=365,2=0.000000
L 0.92318307 1.95446683 0.92049961 1.9555 1 P 0 ;0,1=365,2=0.000000
L 0.92049961 1.9555 0.91743287 1.95446683 1 P 0 ;0,1=365,2=0.000000
L 0.91743287 1.95446683 0.91513337 1.9523997 1 P 0 ;0,1=365,2=0.000000
L 0.91513337 1.9523997 0.9135997 1.9493003 1 P 0 ;0,1=365,2=0.000000
L 0.9135997 1.9493003 0.91283317 1.94516594 1 P 0 ;0,1=365,2=0.000000
L 0.91283317 1.94516594 0.9135997 1.9415501 1 P 0 ;0,1=365,2=0.000000
L 0.9135997 1.9415501 0.91551663 1.93793327 1 P 0 ;0,1=365,2=0.000000
L 0.91551663 1.93793327 0.91781683 1.93586604 1 P 0 ;0,1=365,2=0.000000
L 0.91781683 1.93586604 0.92049961 1.93534951 1 P 0 ;0,1=365,2=0.000000
L 0.92049961 1.93534951 0.92356634 1.93638268 1 P 0 ;0,1=365,2=0.000000
L 0.92356634 1.93638268 0.92586654 1.93896634 1 P 0 ;0,1=365,2=0.000000
L 0.92586654 1.93896634 0.92816673 1.94361634 1 P 0 ;0,1=365,2=0.000000
L 0.94306663 1.92914892 0.94536614 1.92656614 1 P 0 ;0,1=365,2=0.000000
L 0.94536614 1.92656614 0.94804961 1.92501654 1 P 0 ;0,1=365,2=0.000000
L 0.94804961 1.92501654 0.95149961 1.9245 1 P 0 ;0,1=365,2=0.000000
L 0.95149961 1.9245 0.9549503 1.92553307 1 P 0 ;0,1=365,2=0.000000
L 0.9549503 1.92553307 0.95763307 1.92759931 1 P 0 ;0,1=365,2=0.000000
L 0.95763307 1.92759931 0.95955 1.93121614 1 P 0 ;0,1=365,2=0.000000
L 0.95955 1.93121614 0.95993327 1.93534951 1 P 0 ;0,1=365,2=0.000000
L 0.95993327 1.93534951 0.95916673 1.93948287 1 P 0 ;0,1=365,2=0.000000
L 0.95916673 1.93948287 0.9572498 1.94206663 1 P 0 ;0,1=365,2=0.000000
L 0.9572498 1.94206663 0.95456634 1.94413287 1 P 0 ;0,1=365,2=0.000000
L 0.95456634 1.94413287 0.95188356 1.94464941 1 P 0 ;0,1=365,2=0.000000
L 0.95188356 1.94464941 0.9492001 1.94413287 1 P 0 ;0,1=365,2=0.000000
L 0.9492001 1.94413287 0.9457501 1.94206663 1 P 0 ;0,1=365,2=0.000000
L 0.9457501 1.94206663 0.9468999 1.9555 1 P 0 ;0,1=365,2=0.000000
L 0.9468999 1.9555 0.9572498 1.9555 1 P 0 ;0,1=365,2=0.000000
L 0.438 1.50298002 0.438 1.59298002 1 P 0 
L 0.438 1.59298002 0.394 1.59298002 1 P 0 
L 0.394 1.59298002 0.394 1.50298002 1 P 0 
L 0.394 1.50298002 0.438 1.50298002 1 P 0 
L 0.4675 1.51666654 0.4425 1.51666654 1 P 0 ;0,1=366,2=270.000000
L 0.4425 1.51666654 0.4425 1.52333327 1 P 0 ;0,1=366,2=270.000000
L 0.4425 1.52333327 0.44375059 1.52546663 1 P 0 ;0,1=366,2=270.000000
L 0.44375059 1.52546663 0.44541683 1.5268001 1 P 0 ;0,1=366,2=270.000000
L 0.44541683 1.5268001 0.4487502 1.52733337 1 P 0 ;0,1=366,2=270.000000
L 0.4487502 1.52733337 0.45208366 1.5268001 1 P 0 ;0,1=366,2=270.000000
L 0.45208366 1.5268001 0.45416654 1.5252 1 P 0 ;0,1=366,2=270.000000
L 0.45416654 1.5252 0.45541703 1.52333327 1 P 0 ;0,1=366,2=270.000000
L 0.45541703 1.52333327 0.45541703 1.51666654 1 P 0 ;0,1=366,2=270.000000
L 0.45541703 1.52333327 0.4675 1.52733337 1 P 0 ;0,1=366,2=270.000000
L 0.46250039 1.53813327 0.46541713 1.53973297 1 P 0 ;0,1=366,2=270.000000
L 0.46541713 1.53973297 0.46708346 1.54186634 1 P 0 ;0,1=366,2=270.000000
L 0.46708346 1.54186634 0.4675 1.54426683 1 P 0 ;0,1=366,2=270.000000
L 0.4675 1.54426683 0.46708346 1.5464002 1 P 0 ;0,1=366,2=270.000000
L 0.46708346 1.5464002 0.46500059 1.54853356 1 P 0 ;0,1=366,2=270.000000
L 0.46500059 1.54853356 0.46250039 1.54986663 1 P 0 ;0,1=366,2=270.000000
L 0.46250039 1.54986663 0.4600001 1.55013317 1 P 0 ;0,1=366,2=270.000000
L 0.4600001 1.55013317 0.45708406 1.5496 1 P 0 ;0,1=366,2=270.000000
L 0.45708406 1.5496 0.45500039 1.54773327 1 P 0 ;0,1=366,2=270.000000
L 0.45500039 1.54773327 0.45416654 1.54586644 1 P 0 ;0,1=366,2=270.000000
L 0.45416654 1.54586644 0.45416654 1.54346654 1 P 0 ;0,1=366,2=270.000000
L 0.45416654 1.54586644 0.45291673 1.54746663 1 P 0 ;0,1=366,2=270.000000
L 0.45291673 1.54746663 0.45083386 1.5488001 1 P 0 ;0,1=366,2=270.000000
L 0.45083386 1.5488001 0.44833366 1.54933337 1 P 0 ;0,1=366,2=270.000000
L 0.44833366 1.54933337 0.44583346 1.5488001 1 P 0 ;0,1=366,2=270.000000
L 0.44583346 1.5488001 0.44375059 1.54746663 1 P 0 ;0,1=366,2=270.000000
L 0.44375059 1.54746663 0.4425 1.54506663 1 P 0 ;0,1=366,2=270.000000
L 0.4425 1.54506663 0.44291663 1.54266663 1 P 0 ;0,1=366,2=270.000000
L 0.44291663 1.54266663 0.44458366 1.54026663 1 P 0 ;0,1=366,2=270.000000
L 0.4675 1.5659997 0.46708346 1.56786644 1 P 0 ;0,1=366,2=270.000000
L 0.46708346 1.56786644 0.46583376 1.5699998 1 P 0 ;0,1=366,2=270.000000
L 0.46583376 1.5699998 0.46375089 1.57133337 1 P 0 ;0,1=366,2=270.000000
L 0.46375089 1.57133337 0.46083327 1.57186663 1 P 0 ;0,1=366,2=270.000000
L 0.46083327 1.57186663 0.45791722 1.57133337 1 P 0 ;0,1=366,2=270.000000
L 0.45791722 1.57133337 0.45541703 1.56973327 1 P 0 ;0,1=366,2=270.000000
L 0.45541703 1.56973327 0.45416654 1.56733327 1 P 0 ;0,1=366,2=270.000000
L 0.45416654 1.56733327 0.45416654 1.56466663 1 P 0 ;0,1=366,2=270.000000
L 0.45416654 1.56466663 0.45333337 1.56306654 1 P 0 ;0,1=366,2=270.000000
L 0.45333337 1.56306654 0.45125049 1.56173297 1 P 0 ;0,1=366,2=270.000000
L 0.45125049 1.56173297 0.44833366 1.5611998 1 P 0 ;0,1=366,2=270.000000
L 0.44833366 1.5611998 0.44541683 1.5620001 1 P 0 ;0,1=366,2=270.000000
L 0.44541683 1.5620001 0.44333317 1.56386634 1 P 0 ;0,1=366,2=270.000000
L 0.44333317 1.56386634 0.4425 1.5659997 1 P 0 ;0,1=366,2=270.000000
L 0.4425 1.5659997 0.44333317 1.56813307 1 P 0 ;0,1=366,2=270.000000
L 0.44333317 1.56813307 0.44541683 1.5699998 1 P 0 ;0,1=366,2=270.000000
L 0.44541683 1.5699998 0.44833366 1.5708001 1 P 0 ;0,1=366,2=270.000000
L 0.44833366 1.5708001 0.45125049 1.57026644 1 P 0 ;0,1=366,2=270.000000
L 0.45125049 1.57026644 0.45333337 1.56893337 1 P 0 ;0,1=366,2=270.000000
L 0.45333337 1.56893337 0.45416654 1.56733327 1 P 0 ;0,1=366,2=270.000000
L 0.45416654 1.56733327 0.45416654 1.56466663 1 P 0 ;0,1=366,2=270.000000
L 0.45416654 1.56466663 0.45541703 1.56226663 1 P 0 ;0,1=366,2=270.000000
L 0.45541703 1.56226663 0.45791722 1.56066654 1 P 0 ;0,1=366,2=270.000000
L 0.45791722 1.56066654 0.46083327 1.56013327 1 P 0 ;0,1=366,2=270.000000
L 0.46083327 1.56013327 0.46375089 1.56066654 1 P 0 ;0,1=366,2=270.000000
L 0.46375089 1.56066654 0.46583376 1.5620001 1 P 0 ;0,1=366,2=270.000000
L 0.46583376 1.5620001 0.46708346 1.56413346 1 P 0 ;0,1=366,2=270.000000
L 0.46708346 1.56413346 0.4675 1.5659997 1 P 0 ;0,1=366,2=270.000000
L 0.45708406 1.58293317 0.45416654 1.5847999 1 P 0 ;0,1=366,2=270.000000
L 0.45416654 1.5847999 0.4525002 1.5864 1 P 0 ;0,1=366,2=270.000000
L 0.4525002 1.5864 0.45166703 1.58853337 1 P 0 ;0,1=366,2=270.000000
L 0.45166703 1.58853337 0.4525002 1.5904002 1 P 0 ;0,1=366,2=270.000000
L 0.4525002 1.5904002 0.45416654 1.59173327 1 P 0 ;0,1=366,2=270.000000
L 0.45416654 1.59173327 0.45666673 1.5928001 1 P 0 ;0,1=366,2=270.000000
L 0.45666673 1.5928001 0.45958356 1.59306673 1 P 0 ;0,1=366,2=270.000000
L 0.45958356 1.59306673 0.46208376 1.5928001 1 P 0 ;0,1=366,2=270.000000
L 0.46208376 1.5928001 0.46458396 1.59173327 1 P 0 ;0,1=366,2=270.000000
L 0.46458396 1.59173327 0.46666693 1.59013307 1 P 0 ;0,1=366,2=270.000000
L 0.46666693 1.59013307 0.4675 1.58826683 1 P 0 ;0,1=366,2=270.000000
L 0.4675 1.58826683 0.46666693 1.58613346 1 P 0 ;0,1=366,2=270.000000
L 0.46666693 1.58613346 0.46416742 1.58426663 1 P 0 ;0,1=366,2=270.000000
L 0.46416742 1.58426663 0.46041673 1.5831998 1 P 0 ;0,1=366,2=270.000000
L 0.46041673 1.5831998 0.4562502 1.58293317 1 P 0 ;0,1=366,2=270.000000
L 0.4562502 1.58293317 0.45083386 1.58346634 1 P 0 ;0,1=366,2=270.000000
L 0.45083386 1.58346634 0.44791634 1.58426663 1 P 0 ;0,1=366,2=270.000000
L 0.44791634 1.58426663 0.4450003 1.5855997 1 P 0 ;0,1=366,2=270.000000
L 0.4450003 1.5855997 0.44291663 1.58746654 1 P 0 ;0,1=366,2=270.000000
L 0.44291663 1.58746654 0.4425 1.58933327 1 P 0 ;0,1=366,2=270.000000
L 0.4425 1.58933327 0.44333317 1.5912 1 P 0 ;0,1=366,2=270.000000
L 0.44333317 1.5912 0.44541683 1.59253356 1 P 0 ;0,1=366,2=270.000000
L 0.393 1.50298002 0.393 1.59298002 1 P 0 
L 0.393 1.59298002 0.349 1.59298002 1 P 0 
L 0.349 1.59298002 0.349 1.50298002 1 P 0 
L 0.349 1.50298002 0.393 1.50298002 1 P 0 
L 0.3755 1.60166654 0.3505 1.60166654 1 P 0 ;0,1=367,2=270.000000
L 0.3505 1.60166654 0.3505 1.60833327 1 P 0 ;0,1=367,2=270.000000
L 0.3505 1.60833327 0.35175059 1.61046663 1 P 0 ;0,1=367,2=270.000000
L 0.35175059 1.61046663 0.35341683 1.6118001 1 P 0 ;0,1=367,2=270.000000
L 0.35341683 1.6118001 0.3567502 1.61233337 1 P 0 ;0,1=367,2=270.000000
L 0.3567502 1.61233337 0.36008366 1.6118001 1 P 0 ;0,1=367,2=270.000000
L 0.36008366 1.6118001 0.36216654 1.6102 1 P 0 ;0,1=367,2=270.000000
L 0.36216654 1.6102 0.36341703 1.60833327 1 P 0 ;0,1=367,2=270.000000
L 0.36341703 1.60833327 0.36341703 1.60166654 1 P 0 ;0,1=367,2=270.000000
L 0.36341703 1.60833327 0.3755 1.61233337 1 P 0 ;0,1=367,2=270.000000
L 0.3755 1.6289997 0.3505 1.6289997 1 P 0 ;0,1=367,2=270.000000
L 0.3505 1.6289997 0.3554997 1.6257999 1 P 0 ;0,1=367,2=270.000000
L 0.3755 1.6257999 0.3755 1.63219951 1 P 0 ;0,1=367,2=270.000000
L 0.35466663 1.64593317 0.35216713 1.64753327 1 P 0 ;0,1=367,2=270.000000
L 0.35216713 1.64753327 0.35091663 1.6494 1 P 0 ;0,1=367,2=270.000000
L 0.35091663 1.6494 0.3505 1.65153337 1 P 0 ;0,1=367,2=270.000000
L 0.3505 1.65153337 0.35133317 1.6542 1 P 0 ;0,1=367,2=270.000000
L 0.35133317 1.6542 0.35341683 1.65606673 1 P 0 ;0,1=367,2=270.000000
L 0.35341683 1.65606673 0.35591634 1.6566 1 P 0 ;0,1=367,2=270.000000
L 0.35591634 1.6566 0.35841732 1.65633337 1 P 0 ;0,1=367,2=270.000000
L 0.35841732 1.65633337 0.3605002 1.65526644 1 P 0 ;0,1=367,2=270.000000
L 0.3605002 1.65526644 0.36466673 1.64993327 1 P 0 ;0,1=367,2=270.000000
L 0.36466673 1.64993327 0.36758356 1.64753327 1 P 0 ;0,1=367,2=270.000000
L 0.36758356 1.64753327 0.37175089 1.64593317 1 P 0 ;0,1=367,2=270.000000
L 0.37175089 1.64593317 0.3755 1.6453999 1 P 0 ;0,1=367,2=270.000000
L 0.3755 1.6453999 0.3755 1.6566 1 P 0 ;0,1=367,2=270.000000
L 0.37175089 1.66713327 0.37383376 1.66873297 1 P 0 ;0,1=367,2=270.000000
L 0.37383376 1.66873297 0.37508346 1.6705997 1 P 0 ;0,1=367,2=270.000000
L 0.37508346 1.6705997 0.3755 1.6729997 1 P 0 ;0,1=367,2=270.000000
L 0.3755 1.6729997 0.37466693 1.6754002 1 P 0 ;0,1=367,2=270.000000
L 0.37466693 1.6754002 0.37300059 1.67726644 1 P 0 ;0,1=367,2=270.000000
L 0.37300059 1.67726644 0.37008376 1.6786 1 P 0 ;0,1=367,2=270.000000
L 0.37008376 1.6786 0.36675039 1.67886663 1 P 0 ;0,1=367,2=270.000000
L 0.36675039 1.67886663 0.36341703 1.67833337 1 P 0 ;0,1=367,2=270.000000
L 0.36341703 1.67833337 0.36133337 1.6769998 1 P 0 ;0,1=367,2=270.000000
L 0.36133337 1.6769998 0.35966703 1.67513307 1 P 0 ;0,1=367,2=270.000000
L 0.35966703 1.67513307 0.35925049 1.67326683 1 P 0 ;0,1=367,2=270.000000
L 0.35925049 1.67326683 0.35966703 1.6714 1 P 0 ;0,1=367,2=270.000000
L 0.35966703 1.6714 0.36133337 1.6690001 1 P 0 ;0,1=367,2=270.000000
L 0.36133337 1.6690001 0.3505 1.6697999 1 P 0 ;0,1=367,2=270.000000
L 0.3505 1.6697999 0.3505 1.6769998 1 P 0 ;0,1=367,2=270.000000
L 0.348 1.50298002 0.348 1.59298002 1 P 0 
L 0.348 1.59298002 0.304 1.59298002 1 P 0 
L 0.304 1.59298002 0.304 1.50298002 1 P 0 
L 0.304 1.50298002 0.348 1.50298002 1 P 0 
L 0.3355 1.60166654 0.3105 1.60166654 1 P 0 ;0,1=368,2=270.000000
L 0.3105 1.60166654 0.3105 1.60833327 1 P 0 ;0,1=368,2=270.000000
L 0.3105 1.60833327 0.31175059 1.61046663 1 P 0 ;0,1=368,2=270.000000
L 0.31175059 1.61046663 0.31341683 1.6118001 1 P 0 ;0,1=368,2=270.000000
L 0.31341683 1.6118001 0.3167502 1.61233337 1 P 0 ;0,1=368,2=270.000000
L 0.3167502 1.61233337 0.32008366 1.6118001 1 P 0 ;0,1=368,2=270.000000
L 0.32008366 1.6118001 0.32216654 1.6102 1 P 0 ;0,1=368,2=270.000000
L 0.32216654 1.6102 0.32341703 1.60833327 1 P 0 ;0,1=368,2=270.000000
L 0.32341703 1.60833327 0.32341703 1.60166654 1 P 0 ;0,1=368,2=270.000000
L 0.32341703 1.60833327 0.3355 1.61233337 1 P 0 ;0,1=368,2=270.000000
L 0.33050039 1.62313327 0.33341713 1.62473297 1 P 0 ;0,1=368,2=270.000000
L 0.33341713 1.62473297 0.33508346 1.62686634 1 P 0 ;0,1=368,2=270.000000
L 0.33508346 1.62686634 0.3355 1.62926683 1 P 0 ;0,1=368,2=270.000000
L 0.3355 1.62926683 0.33508346 1.6314002 1 P 0 ;0,1=368,2=270.000000
L 0.33508346 1.6314002 0.33300059 1.63353356 1 P 0 ;0,1=368,2=270.000000
L 0.33300059 1.63353356 0.33050039 1.63486663 1 P 0 ;0,1=368,2=270.000000
L 0.33050039 1.63486663 0.3280001 1.63513317 1 P 0 ;0,1=368,2=270.000000
L 0.3280001 1.63513317 0.32508406 1.6346 1 P 0 ;0,1=368,2=270.000000
L 0.32508406 1.6346 0.32300039 1.63273327 1 P 0 ;0,1=368,2=270.000000
L 0.32300039 1.63273327 0.32216654 1.63086644 1 P 0 ;0,1=368,2=270.000000
L 0.32216654 1.63086644 0.32216654 1.62846654 1 P 0 ;0,1=368,2=270.000000
L 0.32216654 1.63086644 0.32091673 1.63246663 1 P 0 ;0,1=368,2=270.000000
L 0.32091673 1.63246663 0.31883386 1.6338001 1 P 0 ;0,1=368,2=270.000000
L 0.31883386 1.6338001 0.31633366 1.63433337 1 P 0 ;0,1=368,2=270.000000
L 0.31633366 1.63433337 0.31383346 1.6338001 1 P 0 ;0,1=368,2=270.000000
L 0.31383346 1.6338001 0.31175059 1.63246663 1 P 0 ;0,1=368,2=270.000000
L 0.31175059 1.63246663 0.3105 1.63006663 1 P 0 ;0,1=368,2=270.000000
L 0.3105 1.63006663 0.31091663 1.62766663 1 P 0 ;0,1=368,2=270.000000
L 0.31091663 1.62766663 0.31258366 1.62526663 1 P 0 ;0,1=368,2=270.000000
L 0.3355 1.6509997 0.33508346 1.65286644 1 P 0 ;0,1=368,2=270.000000
L 0.33508346 1.65286644 0.33383376 1.6549998 1 P 0 ;0,1=368,2=270.000000
L 0.33383376 1.6549998 0.33175089 1.65633337 1 P 0 ;0,1=368,2=270.000000
L 0.33175089 1.65633337 0.32883327 1.65686663 1 P 0 ;0,1=368,2=270.000000
L 0.32883327 1.65686663 0.32591722 1.65633337 1 P 0 ;0,1=368,2=270.000000
L 0.32591722 1.65633337 0.32341703 1.65473327 1 P 0 ;0,1=368,2=270.000000
L 0.32341703 1.65473327 0.32216654 1.65233327 1 P 0 ;0,1=368,2=270.000000
L 0.32216654 1.65233327 0.32216654 1.64966663 1 P 0 ;0,1=368,2=270.000000
L 0.32216654 1.64966663 0.32133337 1.64806654 1 P 0 ;0,1=368,2=270.000000
L 0.32133337 1.64806654 0.31925049 1.64673297 1 P 0 ;0,1=368,2=270.000000
L 0.31925049 1.64673297 0.31633366 1.6461998 1 P 0 ;0,1=368,2=270.000000
L 0.31633366 1.6461998 0.31341683 1.6470001 1 P 0 ;0,1=368,2=270.000000
L 0.31341683 1.6470001 0.31133317 1.64886634 1 P 0 ;0,1=368,2=270.000000
L 0.31133317 1.64886634 0.3105 1.6509997 1 P 0 ;0,1=368,2=270.000000
L 0.3105 1.6509997 0.31133317 1.65313307 1 P 0 ;0,1=368,2=270.000000
L 0.31133317 1.65313307 0.31341683 1.6549998 1 P 0 ;0,1=368,2=270.000000
L 0.31341683 1.6549998 0.31633366 1.6558001 1 P 0 ;0,1=368,2=270.000000
L 0.31633366 1.6558001 0.31925049 1.65526644 1 P 0 ;0,1=368,2=270.000000
L 0.31925049 1.65526644 0.32133337 1.65393337 1 P 0 ;0,1=368,2=270.000000
L 0.32133337 1.65393337 0.32216654 1.65233327 1 P 0 ;0,1=368,2=270.000000
L 0.32216654 1.65233327 0.32216654 1.64966663 1 P 0 ;0,1=368,2=270.000000
L 0.32216654 1.64966663 0.32341703 1.64726663 1 P 0 ;0,1=368,2=270.000000
L 0.32341703 1.64726663 0.32591722 1.64566654 1 P 0 ;0,1=368,2=270.000000
L 0.32591722 1.64566654 0.32883327 1.64513327 1 P 0 ;0,1=368,2=270.000000
L 0.32883327 1.64513327 0.33175089 1.64566654 1 P 0 ;0,1=368,2=270.000000
L 0.33175089 1.64566654 0.33383376 1.6470001 1 P 0 ;0,1=368,2=270.000000
L 0.33383376 1.6470001 0.33508346 1.64913346 1 P 0 ;0,1=368,2=270.000000
L 0.33508346 1.64913346 0.3355 1.6509997 1 P 0 ;0,1=368,2=270.000000
L 0.3355 1.67246654 0.33008376 1.6729997 1 P 0 ;0,1=368,2=270.000000
L 0.33008376 1.6729997 0.32550069 1.6738 1 P 0 ;0,1=368,2=270.000000
L 0.32550069 1.6738 0.32133337 1.67486644 1 P 0 ;0,1=368,2=270.000000
L 0.32133337 1.67486644 0.3167502 1.6762 1 P 0 ;0,1=368,2=270.000000
L 0.3167502 1.6762 0.3105 1.67833337 1 P 0 ;0,1=368,2=270.000000
L 0.3105 1.67833337 0.3105 1.66766654 1 P 0 ;0,1=368,2=270.000000
L 0.845 1.322 0.755 1.322 1 P 0 
L 0.755 1.322 0.755 1.278 1 P 0 
L 0.755 1.278 0.845 1.278 1 P 0 
L 0.845 1.278 0.845 1.322 1 P 0 
L 0.85083317 1.2595 0.85083317 1.2905 1 P 0 ;0,1=369,2=0.000000
L 0.85083317 1.2905 0.86041654 1.2905 1 P 0 ;0,1=369,2=0.000000
L 0.86041654 1.2905 0.86348327 1.28894931 1 P 0 ;0,1=369,2=0.000000
L 0.86348327 1.28894931 0.8654002 1.28688307 1 P 0 ;0,1=369,2=0.000000
L 0.8654002 1.28688307 0.86616673 1.2827497 1 P 0 ;0,1=369,2=0.000000
L 0.86616673 1.2827497 0.8654002 1.27861634 1 P 0 ;0,1=369,2=0.000000
L 0.8654002 1.27861634 0.8631 1.27603356 1 P 0 ;0,1=369,2=0.000000
L 0.8631 1.27603356 0.86041654 1.27448287 1 P 0 ;0,1=369,2=0.000000
L 0.86041654 1.27448287 0.85083317 1.27448287 1 P 0 ;0,1=369,2=0.000000
L 0.86041654 1.27448287 0.86616673 1.2595 1 P 0 ;0,1=369,2=0.000000
L 0.88106663 1.26569961 0.88336614 1.26208278 1 P 0 ;0,1=369,2=0.000000
L 0.88336614 1.26208278 0.88643287 1.26001654 1 P 0 ;0,1=369,2=0.000000
L 0.88643287 1.26001654 0.88988356 1.2595 1 P 0 ;0,1=369,2=0.000000
L 0.88988356 1.2595 0.8929503 1.26001654 1 P 0 ;0,1=369,2=0.000000
L 0.8929503 1.26001654 0.89601703 1.26259931 1 P 0 ;0,1=369,2=0.000000
L 0.89601703 1.26259931 0.89793327 1.26569961 1 P 0 ;0,1=369,2=0.000000
L 0.89793327 1.26569961 0.89831654 1.2687999 1 P 0 ;0,1=369,2=0.000000
L 0.89831654 1.2687999 0.89755 1.27241575 1 P 0 ;0,1=369,2=0.000000
L 0.89755 1.27241575 0.89486654 1.27499951 1 P 0 ;0,1=369,2=0.000000
L 0.89486654 1.27499951 0.89218307 1.27603356 1 P 0 ;0,1=369,2=0.000000
L 0.89218307 1.27603356 0.88873307 1.27603356 1 P 0 ;0,1=369,2=0.000000
L 0.89218307 1.27603356 0.89448327 1.27758317 1 P 0 ;0,1=369,2=0.000000
L 0.89448327 1.27758317 0.8964002 1.28016594 1 P 0 ;0,1=369,2=0.000000
L 0.8964002 1.28016594 0.89716673 1.28326624 1 P 0 ;0,1=369,2=0.000000
L 0.89716673 1.28326624 0.8964002 1.28636654 1 P 0 ;0,1=369,2=0.000000
L 0.8964002 1.28636654 0.89448327 1.28894931 1 P 0 ;0,1=369,2=0.000000
L 0.89448327 1.28894931 0.89103327 1.2905 1 P 0 ;0,1=369,2=0.000000
L 0.89103327 1.2905 0.88758337 1.28998337 1 P 0 ;0,1=369,2=0.000000
L 0.88758337 1.28998337 0.88413337 1.28791624 1 P 0 ;0,1=369,2=0.000000
L 0.92049961 1.2595 0.92318307 1.26001654 1 P 0 ;0,1=369,2=0.000000
L 0.92318307 1.26001654 0.9262498 1.26156614 1 P 0 ;0,1=369,2=0.000000
L 0.9262498 1.26156614 0.92816673 1.26414892 1 P 0 ;0,1=369,2=0.000000
L 0.92816673 1.26414892 0.92893327 1.26776673 1 P 0 ;0,1=369,2=0.000000
L 0.92893327 1.26776673 0.92816673 1.27138268 1 P 0 ;0,1=369,2=0.000000
L 0.92816673 1.27138268 0.92586654 1.27448287 1 P 0 ;0,1=369,2=0.000000
L 0.92586654 1.27448287 0.92241654 1.27603356 1 P 0 ;0,1=369,2=0.000000
L 0.92241654 1.27603356 0.91858337 1.27603356 1 P 0 ;0,1=369,2=0.000000
L 0.91858337 1.27603356 0.91628317 1.27706663 1 P 0 ;0,1=369,2=0.000000
L 0.91628317 1.27706663 0.91436614 1.27964941 1 P 0 ;0,1=369,2=0.000000
L 0.91436614 1.27964941 0.9135997 1.28326624 1 P 0 ;0,1=369,2=0.000000
L 0.9135997 1.28326624 0.9147501 1.28688307 1 P 0 ;0,1=369,2=0.000000
L 0.9147501 1.28688307 0.91743287 1.28946683 1 P 0 ;0,1=369,2=0.000000
L 0.91743287 1.28946683 0.92049961 1.2905 1 P 0 ;0,1=369,2=0.000000
L 0.92049961 1.2905 0.92356634 1.28946683 1 P 0 ;0,1=369,2=0.000000
L 0.92356634 1.28946683 0.9262498 1.28688307 1 P 0 ;0,1=369,2=0.000000
L 0.9262498 1.28688307 0.9274002 1.28326624 1 P 0 ;0,1=369,2=0.000000
L 0.9274002 1.28326624 0.92663307 1.27964941 1 P 0 ;0,1=369,2=0.000000
L 0.92663307 1.27964941 0.92471673 1.27706663 1 P 0 ;0,1=369,2=0.000000
L 0.92471673 1.27706663 0.92241654 1.27603356 1 P 0 ;0,1=369,2=0.000000
L 0.92241654 1.27603356 0.91858337 1.27603356 1 P 0 ;0,1=369,2=0.000000
L 0.91858337 1.27603356 0.91513337 1.27448287 1 P 0 ;0,1=369,2=0.000000
L 0.91513337 1.27448287 0.91283317 1.27138268 1 P 0 ;0,1=369,2=0.000000
L 0.91283317 1.27138268 0.91206663 1.26776673 1 P 0 ;0,1=369,2=0.000000
L 0.91206663 1.26776673 0.91283317 1.26414892 1 P 0 ;0,1=369,2=0.000000
L 0.91283317 1.26414892 0.9147501 1.26156614 1 P 0 ;0,1=369,2=0.000000
L 0.9147501 1.26156614 0.91781683 1.26001654 1 P 0 ;0,1=369,2=0.000000
L 0.91781683 1.26001654 0.92049961 1.2595 1 P 0 ;0,1=369,2=0.000000
L 0.94498287 1.26311585 0.94766634 1.26053307 1 P 0 ;0,1=369,2=0.000000
L 0.94766634 1.26053307 0.95073307 1.2595 1 P 0 ;0,1=369,2=0.000000
L 0.95073307 1.2595 0.9537998 1.26053307 1 P 0 ;0,1=369,2=0.000000
L 0.9537998 1.26053307 0.95648327 1.26363238 1 P 0 ;0,1=369,2=0.000000
L 0.95648327 1.26363238 0.9584002 1.26828327 1 P 0 ;0,1=369,2=0.000000
L 0.9584002 1.26828327 0.95916673 1.27293327 1 P 0 ;0,1=369,2=0.000000
L 0.95916673 1.27293327 0.95916673 1.27861634 1 P 0 ;0,1=369,2=0.000000
L 0.95916673 1.27861634 0.9584002 1.28326624 1 P 0 ;0,1=369,2=0.000000
L 0.9584002 1.28326624 0.95648327 1.2873997 1 P 0 ;0,1=369,2=0.000000
L 0.95648327 1.2873997 0.95418307 1.28946683 1 P 0 ;0,1=369,2=0.000000
L 0.95418307 1.28946683 0.95149961 1.2905 1 P 0 ;0,1=369,2=0.000000
L 0.95149961 1.2905 0.94843287 1.28946683 1 P 0 ;0,1=369,2=0.000000
L 0.94843287 1.28946683 0.94613337 1.2873997 1 P 0 ;0,1=369,2=0.000000
L 0.94613337 1.2873997 0.9445997 1.2843003 1 P 0 ;0,1=369,2=0.000000
L 0.9445997 1.2843003 0.94383317 1.28016594 1 P 0 ;0,1=369,2=0.000000
L 0.94383317 1.28016594 0.9445997 1.2765501 1 P 0 ;0,1=369,2=0.000000
L 0.9445997 1.2765501 0.94651663 1.27293327 1 P 0 ;0,1=369,2=0.000000
L 0.94651663 1.27293327 0.94881683 1.27086604 1 P 0 ;0,1=369,2=0.000000
L 0.94881683 1.27086604 0.95149961 1.27034951 1 P 0 ;0,1=369,2=0.000000
L 0.95149961 1.27034951 0.95456634 1.27138268 1 P 0 ;0,1=369,2=0.000000
L 0.95456634 1.27138268 0.95686654 1.27396634 1 P 0 ;0,1=369,2=0.000000
L 0.95686654 1.27396634 0.95916673 1.27861634 1 P 0 ;0,1=369,2=0.000000
L 0.845 1.272 0.755 1.272 1 P 0 
L 0.755 1.272 0.755 1.228 1 P 0 
L 0.755 1.228 0.845 1.228 1 P 0 
L 0.845 1.228 0.845 1.272 1 P 0 
L 0.85583317 1.2095 0.85583317 1.2405 1 P 0 ;0,1=370,2=0.000000
L 0.85583317 1.2405 0.86541654 1.2405 1 P 0 ;0,1=370,2=0.000000
L 0.86541654 1.2405 0.86848327 1.23894931 1 P 0 ;0,1=370,2=0.000000
L 0.86848327 1.23894931 0.8704002 1.23688307 1 P 0 ;0,1=370,2=0.000000
L 0.8704002 1.23688307 0.87116673 1.2327497 1 P 0 ;0,1=370,2=0.000000
L 0.87116673 1.2327497 0.8704002 1.22861634 1 P 0 ;0,1=370,2=0.000000
L 0.8704002 1.22861634 0.8681 1.22603356 1 P 0 ;0,1=370,2=0.000000
L 0.8681 1.22603356 0.86541654 1.22448287 1 P 0 ;0,1=370,2=0.000000
L 0.86541654 1.22448287 0.85583317 1.22448287 1 P 0 ;0,1=370,2=0.000000
L 0.86541654 1.22448287 0.87116673 1.2095 1 P 0 ;0,1=370,2=0.000000
L 0.88721644 1.23533346 0.88951663 1.23843278 1 P 0 ;0,1=370,2=0.000000
L 0.88951663 1.23843278 0.8922001 1.23998337 1 P 0 ;0,1=370,2=0.000000
L 0.8922001 1.23998337 0.89526683 1.2405 1 P 0 ;0,1=370,2=0.000000
L 0.89526683 1.2405 0.8991 1.23946683 1 P 0 ;0,1=370,2=0.000000
L 0.8991 1.23946683 0.90178346 1.23688307 1 P 0 ;0,1=370,2=0.000000
L 0.90178346 1.23688307 0.90255 1.23378376 1 P 0 ;0,1=370,2=0.000000
L 0.90255 1.23378376 0.90216673 1.23068258 1 P 0 ;0,1=370,2=0.000000
L 0.90216673 1.23068258 0.90063307 1.2280998 1 P 0 ;0,1=370,2=0.000000
L 0.90063307 1.2280998 0.89296663 1.22293327 1 P 0 ;0,1=370,2=0.000000
L 0.89296663 1.22293327 0.88951663 1.21931644 1 P 0 ;0,1=370,2=0.000000
L 0.88951663 1.21931644 0.88721644 1.21414892 1 P 0 ;0,1=370,2=0.000000
L 0.88721644 1.21414892 0.8864499 1.2095 1 P 0 ;0,1=370,2=0.000000
L 0.8864499 1.2095 0.90255 1.2095 1 P 0 ;0,1=370,2=0.000000
L 0.92473307 1.2095 0.92549961 1.21621614 1 P 0 ;0,1=370,2=0.000000
L 0.92549961 1.21621614 0.9266501 1.22189921 1 P 0 ;0,1=370,2=0.000000
L 0.9266501 1.22189921 0.92818307 1.22706663 1 P 0 ;0,1=370,2=0.000000
L 0.92818307 1.22706663 0.9301 1.2327497 1 P 0 ;0,1=370,2=0.000000
L 0.9301 1.2327497 0.93316673 1.2405 1 P 0 ;0,1=370,2=0.000000
L 0.93316673 1.2405 0.91783317 1.2405 1 P 0 ;0,1=370,2=0.000000
L 0.9611 1.2095 0.9611 1.2405 1 P 0 ;0,1=370,2=0.000000
L 0.9611 1.2405 0.94691624 1.21828327 1 P 0 ;0,1=370,2=0.000000
L 0.94691624 1.21828327 0.96608366 1.21828327 1 P 0 ;0,1=370,2=0.000000
L 0.845 1.222 0.755 1.222 1 P 0 
L 0.755 1.222 0.755 1.178 1 P 0 
L 0.755 1.178 0.845 1.178 1 P 0 
L 0.845 1.178 0.845 1.222 1 P 0 
L 0.85583317 1.1545 0.85583317 1.1855 1 P 0 ;0,1=371,2=0.000000
L 0.85583317 1.1855 0.86541654 1.1855 1 P 0 ;0,1=371,2=0.000000
L 0.86541654 1.1855 0.86848327 1.18394931 1 P 0 ;0,1=371,2=0.000000
L 0.86848327 1.18394931 0.8704002 1.18188307 1 P 0 ;0,1=371,2=0.000000
L 0.8704002 1.18188307 0.87116673 1.1777497 1 P 0 ;0,1=371,2=0.000000
L 0.87116673 1.1777497 0.8704002 1.17361634 1 P 0 ;0,1=371,2=0.000000
L 0.8704002 1.17361634 0.8681 1.17103356 1 P 0 ;0,1=371,2=0.000000
L 0.8681 1.17103356 0.86541654 1.16948287 1 P 0 ;0,1=371,2=0.000000
L 0.86541654 1.16948287 0.85583317 1.16948287 1 P 0 ;0,1=371,2=0.000000
L 0.86541654 1.16948287 0.87116673 1.1545 1 P 0 ;0,1=371,2=0.000000
L 0.88606663 1.16069961 0.88836614 1.15708278 1 P 0 ;0,1=371,2=0.000000
L 0.88836614 1.15708278 0.89143287 1.15501654 1 P 0 ;0,1=371,2=0.000000
L 0.89143287 1.15501654 0.89488356 1.1545 1 P 0 ;0,1=371,2=0.000000
L 0.89488356 1.1545 0.8979503 1.15501654 1 P 0 ;0,1=371,2=0.000000
L 0.8979503 1.15501654 0.90101703 1.15759931 1 P 0 ;0,1=371,2=0.000000
L 0.90101703 1.15759931 0.90293327 1.16069961 1 P 0 ;0,1=371,2=0.000000
L 0.90293327 1.16069961 0.90331654 1.1637999 1 P 0 ;0,1=371,2=0.000000
L 0.90331654 1.1637999 0.90255 1.16741575 1 P 0 ;0,1=371,2=0.000000
L 0.90255 1.16741575 0.89986654 1.16999951 1 P 0 ;0,1=371,2=0.000000
L 0.89986654 1.16999951 0.89718307 1.17103356 1 P 0 ;0,1=371,2=0.000000
L 0.89718307 1.17103356 0.89373307 1.17103356 1 P 0 ;0,1=371,2=0.000000
L 0.89718307 1.17103356 0.89948327 1.17258317 1 P 0 ;0,1=371,2=0.000000
L 0.89948327 1.17258317 0.9014002 1.17516594 1 P 0 ;0,1=371,2=0.000000
L 0.9014002 1.17516594 0.90216673 1.17826624 1 P 0 ;0,1=371,2=0.000000
L 0.90216673 1.17826624 0.9014002 1.18136654 1 P 0 ;0,1=371,2=0.000000
L 0.9014002 1.18136654 0.89948327 1.18394931 1 P 0 ;0,1=371,2=0.000000
L 0.89948327 1.18394931 0.89603327 1.1855 1 P 0 ;0,1=371,2=0.000000
L 0.89603327 1.1855 0.89258337 1.18498337 1 P 0 ;0,1=371,2=0.000000
L 0.89258337 1.18498337 0.88913337 1.18291624 1 P 0 ;0,1=371,2=0.000000
L 0.91898287 1.15811585 0.92166634 1.15553307 1 P 0 ;0,1=371,2=0.000000
L 0.92166634 1.15553307 0.92473307 1.1545 1 P 0 ;0,1=371,2=0.000000
L 0.92473307 1.1545 0.9277998 1.15553307 1 P 0 ;0,1=371,2=0.000000
L 0.9277998 1.15553307 0.93048327 1.15863238 1 P 0 ;0,1=371,2=0.000000
L 0.93048327 1.15863238 0.9324002 1.16328327 1 P 0 ;0,1=371,2=0.000000
L 0.9324002 1.16328327 0.93316673 1.16793327 1 P 0 ;0,1=371,2=0.000000
L 0.93316673 1.16793327 0.93316673 1.17361634 1 P 0 ;0,1=371,2=0.000000
L 0.93316673 1.17361634 0.9324002 1.17826624 1 P 0 ;0,1=371,2=0.000000
L 0.9324002 1.17826624 0.93048327 1.1823997 1 P 0 ;0,1=371,2=0.000000
L 0.93048327 1.1823997 0.92818307 1.18446683 1 P 0 ;0,1=371,2=0.000000
L 0.92818307 1.18446683 0.92549961 1.1855 1 P 0 ;0,1=371,2=0.000000
L 0.92549961 1.1855 0.92243287 1.18446683 1 P 0 ;0,1=371,2=0.000000
L 0.92243287 1.18446683 0.92013337 1.1823997 1 P 0 ;0,1=371,2=0.000000
L 0.92013337 1.1823997 0.9185997 1.1793003 1 P 0 ;0,1=371,2=0.000000
L 0.9185997 1.1793003 0.91783317 1.17516594 1 P 0 ;0,1=371,2=0.000000
L 0.91783317 1.17516594 0.9185997 1.1715501 1 P 0 ;0,1=371,2=0.000000
L 0.9185997 1.1715501 0.92051663 1.16793327 1 P 0 ;0,1=371,2=0.000000
L 0.92051663 1.16793327 0.92281683 1.16586604 1 P 0 ;0,1=371,2=0.000000
L 0.92281683 1.16586604 0.92549961 1.16534951 1 P 0 ;0,1=371,2=0.000000
L 0.92549961 1.16534951 0.92856634 1.16638268 1 P 0 ;0,1=371,2=0.000000
L 0.92856634 1.16638268 0.93086654 1.16896634 1 P 0 ;0,1=371,2=0.000000
L 0.93086654 1.16896634 0.93316673 1.17361634 1 P 0 ;0,1=371,2=0.000000
L 0.95649961 1.1855 0.95343287 1.18446683 1 P 0 ;0,1=371,2=0.000000
L 0.95343287 1.18446683 0.95113337 1.18188307 1 P 0 ;0,1=371,2=0.000000
L 0.95113337 1.18188307 0.9495997 1.17878376 1 P 0 ;0,1=371,2=0.000000
L 0.9495997 1.17878376 0.9484499 1.17464941 1 P 0 ;0,1=371,2=0.000000
L 0.9484499 1.17464941 0.94806663 1.16999951 1 P 0 ;0,1=371,2=0.000000
L 0.94806663 1.16999951 0.9484499 1.16534951 1 P 0 ;0,1=371,2=0.000000
L 0.9484499 1.16534951 0.9495997 1.16121614 1 P 0 ;0,1=371,2=0.000000
L 0.9495997 1.16121614 0.95113337 1.15811585 1 P 0 ;0,1=371,2=0.000000
L 0.95113337 1.15811585 0.95343287 1.15553307 1 P 0 ;0,1=371,2=0.000000
L 0.95343287 1.15553307 0.95649961 1.1545 1 P 0 ;0,1=371,2=0.000000
L 0.95649961 1.1545 0.95956634 1.15553307 1 P 0 ;0,1=371,2=0.000000
L 0.95956634 1.15553307 0.96186654 1.15811585 1 P 0 ;0,1=371,2=0.000000
L 0.96186654 1.15811585 0.9634002 1.16121614 1 P 0 ;0,1=371,2=0.000000
L 0.9634002 1.16121614 0.96455 1.16534951 1 P 0 ;0,1=371,2=0.000000
L 0.96455 1.16534951 0.96493327 1.16999951 1 P 0 ;0,1=371,2=0.000000
L 0.96493327 1.16999951 0.96455 1.17464941 1 P 0 ;0,1=371,2=0.000000
L 0.96455 1.17464941 0.9634002 1.17878376 1 P 0 ;0,1=371,2=0.000000
L 0.9634002 1.17878376 0.96186654 1.18188307 1 P 0 ;0,1=371,2=0.000000
L 0.96186654 1.18188307 0.95956634 1.18446683 1 P 0 ;0,1=371,2=0.000000
L 0.95956634 1.18446683 0.95649961 1.1855 1 P 0 ;0,1=371,2=0.000000
L 5.786 3.595 5.786 3.639 1 P 0 
L 5.786 3.639 5.696 3.639 1 P 0 
L 5.696 3.639 5.696 3.595 1 P 0 
L 5.696 3.595 5.786 3.595 1 P 0 
L 5.70683317 3.2695 5.70683317 3.3005 1 P 0 ;0,1=372,2=0.000000
L 5.70683317 3.3005 5.71641654 3.3005 1 P 0 ;0,1=372,2=0.000000
L 5.71641654 3.3005 5.71948327 3.29894931 1 P 0 ;0,1=372,2=0.000000
L 5.71948327 3.29894931 5.7214002 3.29688307 1 P 0 ;0,1=372,2=0.000000
L 5.7214002 3.29688307 5.72216673 3.2927497 1 P 0 ;0,1=372,2=0.000000
L 5.72216673 3.2927497 5.7214002 3.28861634 1 P 0 ;0,1=372,2=0.000000
L 5.7214002 3.28861634 5.7191 3.28603356 1 P 0 ;0,1=372,2=0.000000
L 5.7191 3.28603356 5.71641654 3.28448287 1 P 0 ;0,1=372,2=0.000000
L 5.71641654 3.28448287 5.70683317 3.28448287 1 P 0 ;0,1=372,2=0.000000
L 5.71641654 3.28448287 5.72216673 3.2695 1 P 0 ;0,1=372,2=0.000000
L 5.74473307 3.2695 5.74549961 3.27621614 1 P 0 ;0,1=372,2=0.000000
L 5.74549961 3.27621614 5.7466501 3.28189921 1 P 0 ;0,1=372,2=0.000000
L 5.7466501 3.28189921 5.74818307 3.28706663 1 P 0 ;0,1=372,2=0.000000
L 5.74818307 3.28706663 5.7501 3.2927497 1 P 0 ;0,1=372,2=0.000000
L 5.7501 3.2927497 5.75316673 3.3005 1 P 0 ;0,1=372,2=0.000000
L 5.75316673 3.3005 5.73783317 3.3005 1 P 0 ;0,1=372,2=0.000000
L 5.786 3.645 5.786 3.689 1 P 0 
L 5.786 3.689 5.696 3.689 1 P 0 
L 5.696 3.689 5.696 3.645 1 P 0 
L 5.696 3.645 5.786 3.645 1 P 0 
L 5.70683317 3.3095 5.70683317 3.3405 1 P 0 ;0,1=373,2=0.000000
L 5.70683317 3.3405 5.71641654 3.3405 1 P 0 ;0,1=373,2=0.000000
L 5.71641654 3.3405 5.71948327 3.33894931 1 P 0 ;0,1=373,2=0.000000
L 5.71948327 3.33894931 5.7214002 3.33688307 1 P 0 ;0,1=373,2=0.000000
L 5.7214002 3.33688307 5.72216673 3.3327497 1 P 0 ;0,1=373,2=0.000000
L 5.72216673 3.3327497 5.7214002 3.32861634 1 P 0 ;0,1=373,2=0.000000
L 5.7214002 3.32861634 5.7191 3.32603356 1 P 0 ;0,1=373,2=0.000000
L 5.7191 3.32603356 5.71641654 3.32448287 1 P 0 ;0,1=373,2=0.000000
L 5.71641654 3.32448287 5.70683317 3.32448287 1 P 0 ;0,1=373,2=0.000000
L 5.71641654 3.32448287 5.72216673 3.3095 1 P 0 ;0,1=373,2=0.000000
L 5.74549961 3.3095 5.74818307 3.31001654 1 P 0 ;0,1=373,2=0.000000
L 5.74818307 3.31001654 5.7512498 3.31156614 1 P 0 ;0,1=373,2=0.000000
L 5.7512498 3.31156614 5.75316673 3.31414892 1 P 0 ;0,1=373,2=0.000000
L 5.75316673 3.31414892 5.75393327 3.31776673 1 P 0 ;0,1=373,2=0.000000
L 5.75393327 3.31776673 5.75316673 3.32138268 1 P 0 ;0,1=373,2=0.000000
L 5.75316673 3.32138268 5.75086654 3.32448287 1 P 0 ;0,1=373,2=0.000000
L 5.75086654 3.32448287 5.74741654 3.32603356 1 P 0 ;0,1=373,2=0.000000
L 5.74741654 3.32603356 5.74358337 3.32603356 1 P 0 ;0,1=373,2=0.000000
L 5.74358337 3.32603356 5.74128317 3.32706663 1 P 0 ;0,1=373,2=0.000000
L 5.74128317 3.32706663 5.73936614 3.32964941 1 P 0 ;0,1=373,2=0.000000
L 5.73936614 3.32964941 5.7385997 3.33326624 1 P 0 ;0,1=373,2=0.000000
L 5.7385997 3.33326624 5.7397501 3.33688307 1 P 0 ;0,1=373,2=0.000000
L 5.7397501 3.33688307 5.74243287 3.33946683 1 P 0 ;0,1=373,2=0.000000
L 5.74243287 3.33946683 5.74549961 3.3405 1 P 0 ;0,1=373,2=0.000000
L 5.74549961 3.3405 5.74856634 3.33946683 1 P 0 ;0,1=373,2=0.000000
L 5.74856634 3.33946683 5.7512498 3.33688307 1 P 0 ;0,1=373,2=0.000000
L 5.7512498 3.33688307 5.7524002 3.33326624 1 P 0 ;0,1=373,2=0.000000
L 5.7524002 3.33326624 5.75163307 3.32964941 1 P 0 ;0,1=373,2=0.000000
L 5.75163307 3.32964941 5.74971673 3.32706663 1 P 0 ;0,1=373,2=0.000000
L 5.74971673 3.32706663 5.74741654 3.32603356 1 P 0 ;0,1=373,2=0.000000
L 5.74741654 3.32603356 5.74358337 3.32603356 1 P 0 ;0,1=373,2=0.000000
L 5.74358337 3.32603356 5.74013337 3.32448287 1 P 0 ;0,1=373,2=0.000000
L 5.74013337 3.32448287 5.73783317 3.32138268 1 P 0 ;0,1=373,2=0.000000
L 5.73783317 3.32138268 5.73706663 3.31776673 1 P 0 ;0,1=373,2=0.000000
L 5.73706663 3.31776673 5.73783317 3.31414892 1 P 0 ;0,1=373,2=0.000000
L 5.73783317 3.31414892 5.7397501 3.31156614 1 P 0 ;0,1=373,2=0.000000
L 5.7397501 3.31156614 5.74281683 3.31001654 1 P 0 ;0,1=373,2=0.000000
L 5.74281683 3.31001654 5.74549961 3.3095 1 P 0 ;0,1=373,2=0.000000
L 5.786 3.445 5.786 3.489 1 P 0 
L 5.786 3.489 5.696 3.489 1 P 0 
L 5.696 3.489 5.696 3.445 1 P 0 
L 5.696 3.445 5.786 3.445 1 P 0 
L 5.70683317 3.1495 5.70683317 3.1805 1 P 0 ;0,1=374,2=0.000000
L 5.70683317 3.1805 5.71641654 3.1805 1 P 0 ;0,1=374,2=0.000000
L 5.71641654 3.1805 5.71948327 3.17894931 1 P 0 ;0,1=374,2=0.000000
L 5.71948327 3.17894931 5.7214002 3.17688307 1 P 0 ;0,1=374,2=0.000000
L 5.7214002 3.17688307 5.72216673 3.1727497 1 P 0 ;0,1=374,2=0.000000
L 5.72216673 3.1727497 5.7214002 3.16861634 1 P 0 ;0,1=374,2=0.000000
L 5.7214002 3.16861634 5.7191 3.16603356 1 P 0 ;0,1=374,2=0.000000
L 5.7191 3.16603356 5.71641654 3.16448287 1 P 0 ;0,1=374,2=0.000000
L 5.71641654 3.16448287 5.70683317 3.16448287 1 P 0 ;0,1=374,2=0.000000
L 5.71641654 3.16448287 5.72216673 3.1495 1 P 0 ;0,1=374,2=0.000000
L 5.7501 3.1495 5.7501 3.1805 1 P 0 ;0,1=374,2=0.000000
L 5.7501 3.1805 5.73591624 3.15828327 1 P 0 ;0,1=374,2=0.000000
L 5.73591624 3.15828327 5.75508366 3.15828327 1 P 0 ;0,1=374,2=0.000000
L 1.3747 0.731 1.3747 0.775 1 P 0 
L 1.3747 0.775 1.2847 0.775 1 P 0 
L 1.2847 0.775 1.2847 0.731 1 P 0 
L 1.2847 0.731 1.3747 0.731 1 P 0 
L 1.39583317 0.7095 1.39583317 0.7405 1 P 0 ;0,1=375,2=0.000000
L 1.39583317 0.7405 1.40541654 0.7405 1 P 0 ;0,1=375,2=0.000000
L 1.40541654 0.7405 1.40848327 0.73894931 1 P 0 ;0,1=375,2=0.000000
L 1.40848327 0.73894931 1.4104002 0.73688307 1 P 0 ;0,1=375,2=0.000000
L 1.4104002 0.73688307 1.41116673 0.7327497 1 P 0 ;0,1=375,2=0.000000
L 1.41116673 0.7327497 1.4104002 0.72861634 1 P 0 ;0,1=375,2=0.000000
L 1.4104002 0.72861634 1.4081 0.72603356 1 P 0 ;0,1=375,2=0.000000
L 1.4081 0.72603356 1.40541654 0.72448287 1 P 0 ;0,1=375,2=0.000000
L 1.40541654 0.72448287 1.39583317 0.72448287 1 P 0 ;0,1=375,2=0.000000
L 1.40541654 0.72448287 1.41116673 0.7095 1 P 0 ;0,1=375,2=0.000000
L 1.42606663 0.71569961 1.42836614 0.71208278 1 P 0 ;0,1=375,2=0.000000
L 1.42836614 0.71208278 1.43143287 0.71001654 1 P 0 ;0,1=375,2=0.000000
L 1.43143287 0.71001654 1.43488356 0.7095 1 P 0 ;0,1=375,2=0.000000
L 1.43488356 0.7095 1.4379503 0.71001654 1 P 0 ;0,1=375,2=0.000000
L 1.4379503 0.71001654 1.44101703 0.71259931 1 P 0 ;0,1=375,2=0.000000
L 1.44101703 0.71259931 1.44293327 0.71569961 1 P 0 ;0,1=375,2=0.000000
L 1.44293327 0.71569961 1.44331654 0.7187999 1 P 0 ;0,1=375,2=0.000000
L 1.44331654 0.7187999 1.44255 0.72241575 1 P 0 ;0,1=375,2=0.000000
L 1.44255 0.72241575 1.43986654 0.72499951 1 P 0 ;0,1=375,2=0.000000
L 1.43986654 0.72499951 1.43718307 0.72603356 1 P 0 ;0,1=375,2=0.000000
L 1.43718307 0.72603356 1.43373307 0.72603356 1 P 0 ;0,1=375,2=0.000000
L 1.43718307 0.72603356 1.43948327 0.72758317 1 P 0 ;0,1=375,2=0.000000
L 1.43948327 0.72758317 1.4414002 0.73016594 1 P 0 ;0,1=375,2=0.000000
L 1.4414002 0.73016594 1.44216673 0.73326624 1 P 0 ;0,1=375,2=0.000000
L 1.44216673 0.73326624 1.4414002 0.73636654 1 P 0 ;0,1=375,2=0.000000
L 1.4414002 0.73636654 1.43948327 0.73894931 1 P 0 ;0,1=375,2=0.000000
L 1.43948327 0.73894931 1.43603327 0.7405 1 P 0 ;0,1=375,2=0.000000
L 1.43603327 0.7405 1.43258337 0.73998337 1 P 0 ;0,1=375,2=0.000000
L 1.43258337 0.73998337 1.42913337 0.73791624 1 P 0 ;0,1=375,2=0.000000
L 1.46549961 0.7095 1.46549961 0.7405 1 P 0 ;0,1=375,2=0.000000
L 1.46549961 0.7405 1.4608999 0.7343003 1 P 0 ;0,1=375,2=0.000000
L 1.4608999 0.7095 1.47009931 0.7095 1 P 0 ;0,1=375,2=0.000000
L 1.48806663 0.71569961 1.49036614 0.71208278 1 P 0 ;0,1=375,2=0.000000
L 1.49036614 0.71208278 1.49343287 0.71001654 1 P 0 ;0,1=375,2=0.000000
L 1.49343287 0.71001654 1.49688356 0.7095 1 P 0 ;0,1=375,2=0.000000
L 1.49688356 0.7095 1.4999503 0.71001654 1 P 0 ;0,1=375,2=0.000000
L 1.4999503 0.71001654 1.50301703 0.71259931 1 P 0 ;0,1=375,2=0.000000
L 1.50301703 0.71259931 1.50493327 0.71569961 1 P 0 ;0,1=375,2=0.000000
L 1.50493327 0.71569961 1.50531654 0.7187999 1 P 0 ;0,1=375,2=0.000000
L 1.50531654 0.7187999 1.50455 0.72241575 1 P 0 ;0,1=375,2=0.000000
L 1.50455 0.72241575 1.50186654 0.72499951 1 P 0 ;0,1=375,2=0.000000
L 1.50186654 0.72499951 1.49918307 0.72603356 1 P 0 ;0,1=375,2=0.000000
L 1.49918307 0.72603356 1.49573307 0.72603356 1 P 0 ;0,1=375,2=0.000000
L 1.49918307 0.72603356 1.50148327 0.72758317 1 P 0 ;0,1=375,2=0.000000
L 1.50148327 0.72758317 1.5034002 0.73016594 1 P 0 ;0,1=375,2=0.000000
L 1.5034002 0.73016594 1.50416673 0.73326624 1 P 0 ;0,1=375,2=0.000000
L 1.50416673 0.73326624 1.5034002 0.73636654 1 P 0 ;0,1=375,2=0.000000
L 1.5034002 0.73636654 1.50148327 0.73894931 1 P 0 ;0,1=375,2=0.000000
L 1.50148327 0.73894931 1.49803327 0.7405 1 P 0 ;0,1=375,2=0.000000
L 1.49803327 0.7405 1.49458337 0.73998337 1 P 0 ;0,1=375,2=0.000000
L 1.49458337 0.73998337 1.49113337 0.73791624 1 P 0 ;0,1=375,2=0.000000
L 1.3747 0.686 1.3747 0.73 1 P 0 
L 1.3747 0.73 1.2847 0.73 1 P 0 
L 1.2847 0.73 1.2847 0.686 1 P 0 
L 1.2847 0.686 1.3747 0.686 1 P 0 
L 1.38583317 0.6395 1.38583317 0.6705 1 P 0 ;0,1=376,2=0.000000
L 1.38583317 0.6705 1.39541654 0.6705 1 P 0 ;0,1=376,2=0.000000
L 1.39541654 0.6705 1.39848327 0.66894931 1 P 0 ;0,1=376,2=0.000000
L 1.39848327 0.66894931 1.4004002 0.66688307 1 P 0 ;0,1=376,2=0.000000
L 1.4004002 0.66688307 1.40116673 0.6627497 1 P 0 ;0,1=376,2=0.000000
L 1.40116673 0.6627497 1.4004002 0.65861634 1 P 0 ;0,1=376,2=0.000000
L 1.4004002 0.65861634 1.3981 0.65603356 1 P 0 ;0,1=376,2=0.000000
L 1.3981 0.65603356 1.39541654 0.65448287 1 P 0 ;0,1=376,2=0.000000
L 1.39541654 0.65448287 1.38583317 0.65448287 1 P 0 ;0,1=376,2=0.000000
L 1.39541654 0.65448287 1.40116673 0.6395 1 P 0 ;0,1=376,2=0.000000
L 1.42449961 0.6395 1.42449961 0.6705 1 P 0 ;0,1=376,2=0.000000
L 1.42449961 0.6705 1.4198999 0.6643003 1 P 0 ;0,1=376,2=0.000000
L 1.4198999 0.6395 1.42909931 0.6395 1 P 0 ;0,1=376,2=0.000000
L 1.45549961 0.6395 1.45818307 0.64001654 1 P 0 ;0,1=376,2=0.000000
L 1.45818307 0.64001654 1.4612498 0.64156614 1 P 0 ;0,1=376,2=0.000000
L 1.4612498 0.64156614 1.46316673 0.64414892 1 P 0 ;0,1=376,2=0.000000
L 1.46316673 0.64414892 1.46393327 0.64776673 1 P 0 ;0,1=376,2=0.000000
L 1.46393327 0.64776673 1.46316673 0.65138268 1 P 0 ;0,1=376,2=0.000000
L 1.46316673 0.65138268 1.46086654 0.65448287 1 P 0 ;0,1=376,2=0.000000
L 1.46086654 0.65448287 1.45741654 0.65603356 1 P 0 ;0,1=376,2=0.000000
L 1.45741654 0.65603356 1.45358337 0.65603356 1 P 0 ;0,1=376,2=0.000000
L 1.45358337 0.65603356 1.45128317 0.65706663 1 P 0 ;0,1=376,2=0.000000
L 1.45128317 0.65706663 1.44936614 0.65964941 1 P 0 ;0,1=376,2=0.000000
L 1.44936614 0.65964941 1.4485997 0.66326624 1 P 0 ;0,1=376,2=0.000000
L 1.4485997 0.66326624 1.4497501 0.66688307 1 P 0 ;0,1=376,2=0.000000
L 1.4497501 0.66688307 1.45243287 0.66946683 1 P 0 ;0,1=376,2=0.000000
L 1.45243287 0.66946683 1.45549961 0.6705 1 P 0 ;0,1=376,2=0.000000
L 1.45549961 0.6705 1.45856634 0.66946683 1 P 0 ;0,1=376,2=0.000000
L 1.45856634 0.66946683 1.4612498 0.66688307 1 P 0 ;0,1=376,2=0.000000
L 1.4612498 0.66688307 1.4624002 0.66326624 1 P 0 ;0,1=376,2=0.000000
L 1.4624002 0.66326624 1.46163307 0.65964941 1 P 0 ;0,1=376,2=0.000000
L 1.46163307 0.65964941 1.45971673 0.65706663 1 P 0 ;0,1=376,2=0.000000
L 1.45971673 0.65706663 1.45741654 0.65603356 1 P 0 ;0,1=376,2=0.000000
L 1.45741654 0.65603356 1.45358337 0.65603356 1 P 0 ;0,1=376,2=0.000000
L 1.45358337 0.65603356 1.45013337 0.65448287 1 P 0 ;0,1=376,2=0.000000
L 1.45013337 0.65448287 1.44783317 0.65138268 1 P 0 ;0,1=376,2=0.000000
L 1.44783317 0.65138268 1.44706663 0.64776673 1 P 0 ;0,1=376,2=0.000000
L 1.44706663 0.64776673 1.44783317 0.64414892 1 P 0 ;0,1=376,2=0.000000
L 1.44783317 0.64414892 1.4497501 0.64156614 1 P 0 ;0,1=376,2=0.000000
L 1.4497501 0.64156614 1.45281683 0.64001654 1 P 0 ;0,1=376,2=0.000000
L 1.45281683 0.64001654 1.45549961 0.6395 1 P 0 ;0,1=376,2=0.000000
L 1.4911 0.6395 1.4911 0.6705 1 P 0 ;0,1=376,2=0.000000
L 1.4911 0.6705 1.47691624 0.64828327 1 P 0 ;0,1=376,2=0.000000
L 1.47691624 0.64828327 1.49608366 0.64828327 1 P 0 ;0,1=376,2=0.000000
L 1.3745 0.591 1.3745 0.635 1 P 0 
L 1.3745 0.635 1.2845 0.635 1 P 0 
L 1.2845 0.635 1.2845 0.591 1 P 0 
L 1.2845 0.591 1.3745 0.591 1 P 0 
L 1.37983317 0.5175 1.37983317 0.5485 1 P 0 ;0,1=377,2=0.000000
L 1.37983317 0.5485 1.38941654 0.5485 1 P 0 ;0,1=377,2=0.000000
L 1.38941654 0.5485 1.39248327 0.54694931 1 P 0 ;0,1=377,2=0.000000
L 1.39248327 0.54694931 1.3944002 0.54488307 1 P 0 ;0,1=377,2=0.000000
L 1.3944002 0.54488307 1.39516673 0.5407497 1 P 0 ;0,1=377,2=0.000000
L 1.39516673 0.5407497 1.3944002 0.53661634 1 P 0 ;0,1=377,2=0.000000
L 1.3944002 0.53661634 1.3921 0.53403356 1 P 0 ;0,1=377,2=0.000000
L 1.3921 0.53403356 1.38941654 0.53248287 1 P 0 ;0,1=377,2=0.000000
L 1.38941654 0.53248287 1.37983317 0.53248287 1 P 0 ;0,1=377,2=0.000000
L 1.38941654 0.53248287 1.39516673 0.5175 1 P 0 ;0,1=377,2=0.000000
L 1.41849961 0.5175 1.41849961 0.5485 1 P 0 ;0,1=377,2=0.000000
L 1.41849961 0.5485 1.4138999 0.5423003 1 P 0 ;0,1=377,2=0.000000
L 1.4138999 0.5175 1.42309931 0.5175 1 P 0 ;0,1=377,2=0.000000
L 1.44949961 0.5175 1.45218307 0.51801654 1 P 0 ;0,1=377,2=0.000000
L 1.45218307 0.51801654 1.4552498 0.51956614 1 P 0 ;0,1=377,2=0.000000
L 1.4552498 0.51956614 1.45716673 0.52214892 1 P 0 ;0,1=377,2=0.000000
L 1.45716673 0.52214892 1.45793327 0.52576673 1 P 0 ;0,1=377,2=0.000000
L 1.45793327 0.52576673 1.45716673 0.52938268 1 P 0 ;0,1=377,2=0.000000
L 1.45716673 0.52938268 1.45486654 0.53248287 1 P 0 ;0,1=377,2=0.000000
L 1.45486654 0.53248287 1.45141654 0.53403356 1 P 0 ;0,1=377,2=0.000000
L 1.45141654 0.53403356 1.44758337 0.53403356 1 P 0 ;0,1=377,2=0.000000
L 1.44758337 0.53403356 1.44528317 0.53506663 1 P 0 ;0,1=377,2=0.000000
L 1.44528317 0.53506663 1.44336614 0.53764941 1 P 0 ;0,1=377,2=0.000000
L 1.44336614 0.53764941 1.4425997 0.54126624 1 P 0 ;0,1=377,2=0.000000
L 1.4425997 0.54126624 1.4437501 0.54488307 1 P 0 ;0,1=377,2=0.000000
L 1.4437501 0.54488307 1.44643287 0.54746683 1 P 0 ;0,1=377,2=0.000000
L 1.44643287 0.54746683 1.44949961 0.5485 1 P 0 ;0,1=377,2=0.000000
L 1.44949961 0.5485 1.45256634 0.54746683 1 P 0 ;0,1=377,2=0.000000
L 1.45256634 0.54746683 1.4552498 0.54488307 1 P 0 ;0,1=377,2=0.000000
L 1.4552498 0.54488307 1.4564002 0.54126624 1 P 0 ;0,1=377,2=0.000000
L 1.4564002 0.54126624 1.45563307 0.53764941 1 P 0 ;0,1=377,2=0.000000
L 1.45563307 0.53764941 1.45371673 0.53506663 1 P 0 ;0,1=377,2=0.000000
L 1.45371673 0.53506663 1.45141654 0.53403356 1 P 0 ;0,1=377,2=0.000000
L 1.45141654 0.53403356 1.44758337 0.53403356 1 P 0 ;0,1=377,2=0.000000
L 1.44758337 0.53403356 1.44413337 0.53248287 1 P 0 ;0,1=377,2=0.000000
L 1.44413337 0.53248287 1.44183317 0.52938268 1 P 0 ;0,1=377,2=0.000000
L 1.44183317 0.52938268 1.44106663 0.52576673 1 P 0 ;0,1=377,2=0.000000
L 1.44106663 0.52576673 1.44183317 0.52214892 1 P 0 ;0,1=377,2=0.000000
L 1.44183317 0.52214892 1.4437501 0.51956614 1 P 0 ;0,1=377,2=0.000000
L 1.4437501 0.51956614 1.44681683 0.51801654 1 P 0 ;0,1=377,2=0.000000
L 1.44681683 0.51801654 1.44949961 0.5175 1 P 0 ;0,1=377,2=0.000000
L 1.47206663 0.52369961 1.47436614 0.52008278 1 P 0 ;0,1=377,2=0.000000
L 1.47436614 0.52008278 1.47743287 0.51801654 1 P 0 ;0,1=377,2=0.000000
L 1.47743287 0.51801654 1.48088356 0.5175 1 P 0 ;0,1=377,2=0.000000
L 1.48088356 0.5175 1.4839503 0.51801654 1 P 0 ;0,1=377,2=0.000000
L 1.4839503 0.51801654 1.48701703 0.52059931 1 P 0 ;0,1=377,2=0.000000
L 1.48701703 0.52059931 1.48893327 0.52369961 1 P 0 ;0,1=377,2=0.000000
L 1.48893327 0.52369961 1.48931654 0.5267999 1 P 0 ;0,1=377,2=0.000000
L 1.48931654 0.5267999 1.48855 0.53041575 1 P 0 ;0,1=377,2=0.000000
L 1.48855 0.53041575 1.48586654 0.53299951 1 P 0 ;0,1=377,2=0.000000
L 1.48586654 0.53299951 1.48318307 0.53403356 1 P 0 ;0,1=377,2=0.000000
L 1.48318307 0.53403356 1.47973307 0.53403356 1 P 0 ;0,1=377,2=0.000000
L 1.48318307 0.53403356 1.48548327 0.53558317 1 P 0 ;0,1=377,2=0.000000
L 1.48548327 0.53558317 1.4874002 0.53816594 1 P 0 ;0,1=377,2=0.000000
L 1.4874002 0.53816594 1.48816673 0.54126624 1 P 0 ;0,1=377,2=0.000000
L 1.48816673 0.54126624 1.4874002 0.54436654 1 P 0 ;0,1=377,2=0.000000
L 1.4874002 0.54436654 1.48548327 0.54694931 1 P 0 ;0,1=377,2=0.000000
L 1.48548327 0.54694931 1.48203327 0.5485 1 P 0 ;0,1=377,2=0.000000
L 1.48203327 0.5485 1.47858337 0.54798337 1 P 0 ;0,1=377,2=0.000000
L 1.47858337 0.54798337 1.47513337 0.54591624 1 P 0 ;0,1=377,2=0.000000
L 1.3745 0.636 1.3745 0.68 1 P 0 
L 1.2845 0.636 1.3745 0.636 1 P 0 
L 1.2845 0.68 1.2845 0.636 1 P 0 
L 1.3745 0.68 1.2845 0.68 1 P 0 
L 1.37983317 0.5625 1.37983317 0.5935 1 P 0 ;0,1=378,2=0.000000
L 1.37983317 0.5935 1.38941654 0.5935 1 P 0 ;0,1=378,2=0.000000
L 1.38941654 0.5935 1.39248327 0.59194931 1 P 0 ;0,1=378,2=0.000000
L 1.39248327 0.59194931 1.3944002 0.58988307 1 P 0 ;0,1=378,2=0.000000
L 1.3944002 0.58988307 1.39516673 0.5857497 1 P 0 ;0,1=378,2=0.000000
L 1.39516673 0.5857497 1.3944002 0.58161634 1 P 0 ;0,1=378,2=0.000000
L 1.3944002 0.58161634 1.3921 0.57903356 1 P 0 ;0,1=378,2=0.000000
L 1.3921 0.57903356 1.38941654 0.57748287 1 P 0 ;0,1=378,2=0.000000
L 1.38941654 0.57748287 1.37983317 0.57748287 1 P 0 ;0,1=378,2=0.000000
L 1.38941654 0.57748287 1.39516673 0.5625 1 P 0 ;0,1=378,2=0.000000
L 1.41006663 0.56869961 1.41236614 0.56508278 1 P 0 ;0,1=378,2=0.000000
L 1.41236614 0.56508278 1.41543287 0.56301654 1 P 0 ;0,1=378,2=0.000000
L 1.41543287 0.56301654 1.41888356 0.5625 1 P 0 ;0,1=378,2=0.000000
L 1.41888356 0.5625 1.4219503 0.56301654 1 P 0 ;0,1=378,2=0.000000
L 1.4219503 0.56301654 1.42501703 0.56559931 1 P 0 ;0,1=378,2=0.000000
L 1.42501703 0.56559931 1.42693327 0.56869961 1 P 0 ;0,1=378,2=0.000000
L 1.42693327 0.56869961 1.42731654 0.5717999 1 P 0 ;0,1=378,2=0.000000
L 1.42731654 0.5717999 1.42655 0.57541575 1 P 0 ;0,1=378,2=0.000000
L 1.42655 0.57541575 1.42386654 0.57799951 1 P 0 ;0,1=378,2=0.000000
L 1.42386654 0.57799951 1.42118307 0.57903356 1 P 0 ;0,1=378,2=0.000000
L 1.42118307 0.57903356 1.41773307 0.57903356 1 P 0 ;0,1=378,2=0.000000
L 1.42118307 0.57903356 1.42348327 0.58058317 1 P 0 ;0,1=378,2=0.000000
L 1.42348327 0.58058317 1.4254002 0.58316594 1 P 0 ;0,1=378,2=0.000000
L 1.4254002 0.58316594 1.42616673 0.58626624 1 P 0 ;0,1=378,2=0.000000
L 1.42616673 0.58626624 1.4254002 0.58936654 1 P 0 ;0,1=378,2=0.000000
L 1.4254002 0.58936654 1.42348327 0.59194931 1 P 0 ;0,1=378,2=0.000000
L 1.42348327 0.59194931 1.42003327 0.5935 1 P 0 ;0,1=378,2=0.000000
L 1.42003327 0.5935 1.41658337 0.59298337 1 P 0 ;0,1=378,2=0.000000
L 1.41658337 0.59298337 1.41313337 0.59091624 1 P 0 ;0,1=378,2=0.000000
L 1.44949961 0.5625 1.44949961 0.5935 1 P 0 ;0,1=378,2=0.000000
L 1.44949961 0.5935 1.4448999 0.5873003 1 P 0 ;0,1=378,2=0.000000
L 1.4448999 0.5625 1.45409931 0.5625 1 P 0 ;0,1=378,2=0.000000
L 1.47321644 0.58833346 1.47551663 0.59143278 1 P 0 ;0,1=378,2=0.000000
L 1.47551663 0.59143278 1.4782001 0.59298337 1 P 0 ;0,1=378,2=0.000000
L 1.4782001 0.59298337 1.48126683 0.5935 1 P 0 ;0,1=378,2=0.000000
L 1.48126683 0.5935 1.4851 0.59246683 1 P 0 ;0,1=378,2=0.000000
L 1.4851 0.59246683 1.48778346 0.58988307 1 P 0 ;0,1=378,2=0.000000
L 1.48778346 0.58988307 1.48855 0.58678376 1 P 0 ;0,1=378,2=0.000000
L 1.48855 0.58678376 1.48816673 0.58368258 1 P 0 ;0,1=378,2=0.000000
L 1.48816673 0.58368258 1.48663307 0.5810998 1 P 0 ;0,1=378,2=0.000000
L 1.48663307 0.5810998 1.47896663 0.57593327 1 P 0 ;0,1=378,2=0.000000
L 1.47896663 0.57593327 1.47551663 0.57231644 1 P 0 ;0,1=378,2=0.000000
L 1.47551663 0.57231644 1.47321644 0.56714892 1 P 0 ;0,1=378,2=0.000000
L 1.47321644 0.56714892 1.4724499 0.5625 1 P 0 ;0,1=378,2=0.000000
L 1.4724499 0.5625 1.48855 0.5625 1 P 0 ;0,1=378,2=0.000000
L 5.786 3.735 5.786 3.779 1 P 0 
L 5.786 3.779 5.696 3.779 1 P 0 
L 5.696 3.779 5.696 3.735 1 P 0 
L 5.696 3.735 5.786 3.735 1 P 0 
L 5.70733317 3.3915 5.70733317 3.4225 1 P 0 ;0,1=379,2=0.000000
L 5.70733317 3.4225 5.71691654 3.4225 1 P 0 ;0,1=379,2=0.000000
L 5.71691654 3.4225 5.71998327 3.42094931 1 P 0 ;0,1=379,2=0.000000
L 5.71998327 3.42094931 5.7219002 3.41888307 1 P 0 ;0,1=379,2=0.000000
L 5.7219002 3.41888307 5.72266673 3.4147497 1 P 0 ;0,1=379,2=0.000000
L 5.72266673 3.4147497 5.7219002 3.41061634 1 P 0 ;0,1=379,2=0.000000
L 5.7219002 3.41061634 5.7196 3.40803356 1 P 0 ;0,1=379,2=0.000000
L 5.7196 3.40803356 5.71691654 3.40648287 1 P 0 ;0,1=379,2=0.000000
L 5.71691654 3.40648287 5.70733317 3.40648287 1 P 0 ;0,1=379,2=0.000000
L 5.71691654 3.40648287 5.72266673 3.3915 1 P 0 ;0,1=379,2=0.000000
L 5.7506 3.3915 5.7506 3.4225 1 P 0 ;0,1=379,2=0.000000
L 5.7506 3.4225 5.73641624 3.40028327 1 P 0 ;0,1=379,2=0.000000
L 5.73641624 3.40028327 5.75558366 3.40028327 1 P 0 ;0,1=379,2=0.000000
L 5.76971644 3.40441575 5.7723999 3.40803356 1 P 0 ;0,1=379,2=0.000000
L 5.7723999 3.40803356 5.7747001 3.4100998 1 P 0 ;0,1=379,2=0.000000
L 5.7747001 3.4100998 5.77776683 3.41113287 1 P 0 ;0,1=379,2=0.000000
L 5.77776683 3.41113287 5.7804503 3.4100998 1 P 0 ;0,1=379,2=0.000000
L 5.7804503 3.4100998 5.78236654 3.40803356 1 P 0 ;0,1=379,2=0.000000
L 5.78236654 3.40803356 5.7839002 3.40493327 1 P 0 ;0,1=379,2=0.000000
L 5.7839002 3.40493327 5.78428346 3.40131644 1 P 0 ;0,1=379,2=0.000000
L 5.78428346 3.40131644 5.7839002 3.39821614 1 P 0 ;0,1=379,2=0.000000
L 5.7839002 3.39821614 5.78236654 3.39511585 1 P 0 ;0,1=379,2=0.000000
L 5.78236654 3.39511585 5.78006634 3.39253307 1 P 0 ;0,1=379,2=0.000000
L 5.78006634 3.39253307 5.77738356 3.3915 1 P 0 ;0,1=379,2=0.000000
L 5.77738356 3.3915 5.77431683 3.39253307 1 P 0 ;0,1=379,2=0.000000
L 5.77431683 3.39253307 5.77163337 3.39563238 1 P 0 ;0,1=379,2=0.000000
L 5.77163337 3.39563238 5.7700997 3.40028327 1 P 0 ;0,1=379,2=0.000000
L 5.7700997 3.40028327 5.76971644 3.4054498 1 P 0 ;0,1=379,2=0.000000
L 5.76971644 3.4054498 5.77048287 3.41216594 1 P 0 ;0,1=379,2=0.000000
L 5.77048287 3.41216594 5.77163337 3.41578376 1 P 0 ;0,1=379,2=0.000000
L 5.77163337 3.41578376 5.77354961 3.4193997 1 P 0 ;0,1=379,2=0.000000
L 5.77354961 3.4193997 5.77623307 3.42198337 1 P 0 ;0,1=379,2=0.000000
L 5.77623307 3.42198337 5.77891654 3.4225 1 P 0 ;0,1=379,2=0.000000
L 5.77891654 3.4225 5.7816 3.42146683 1 P 0 ;0,1=379,2=0.000000
L 5.7816 3.42146683 5.78351703 3.41888307 1 P 0 ;0,1=379,2=0.000000
L 5.786 3.885 5.786 3.929 1 P 0 
L 5.786 3.929 5.696 3.929 1 P 0 
L 5.696 3.929 5.696 3.885 1 P 0 
L 5.696 3.885 5.786 3.885 1 P 0 
L 5.82133317 3.8995 5.82133317 3.9305 1 P 0 ;0,1=380,2=0.000000
L 5.82133317 3.9305 5.83091654 3.9305 1 P 0 ;0,1=380,2=0.000000
L 5.83091654 3.9305 5.83398327 3.92894931 1 P 0 ;0,1=380,2=0.000000
L 5.83398327 3.92894931 5.8359002 3.92688307 1 P 0 ;0,1=380,2=0.000000
L 5.8359002 3.92688307 5.83666673 3.9227497 1 P 0 ;0,1=380,2=0.000000
L 5.83666673 3.9227497 5.8359002 3.91861634 1 P 0 ;0,1=380,2=0.000000
L 5.8359002 3.91861634 5.8336 3.91603356 1 P 0 ;0,1=380,2=0.000000
L 5.8336 3.91603356 5.83091654 3.91448287 1 P 0 ;0,1=380,2=0.000000
L 5.83091654 3.91448287 5.82133317 3.91448287 1 P 0 ;0,1=380,2=0.000000
L 5.83091654 3.91448287 5.83666673 3.8995 1 P 0 ;0,1=380,2=0.000000
L 5.85999961 3.8995 5.85999961 3.9305 1 P 0 ;0,1=380,2=0.000000
L 5.85999961 3.9305 5.8553999 3.9243003 1 P 0 ;0,1=380,2=0.000000
L 5.8553999 3.8995 5.86459931 3.8995 1 P 0 ;0,1=380,2=0.000000
L 5.88256663 3.90414892 5.88486614 3.90156614 1 P 0 ;0,1=380,2=0.000000
L 5.88486614 3.90156614 5.88754961 3.90001654 1 P 0 ;0,1=380,2=0.000000
L 5.88754961 3.90001654 5.89099961 3.8995 1 P 0 ;0,1=380,2=0.000000
L 5.89099961 3.8995 5.8944503 3.90053307 1 P 0 ;0,1=380,2=0.000000
L 5.8944503 3.90053307 5.89713307 3.90259931 1 P 0 ;0,1=380,2=0.000000
L 5.89713307 3.90259931 5.89905 3.90621614 1 P 0 ;0,1=380,2=0.000000
L 5.89905 3.90621614 5.89943327 3.91034951 1 P 0 ;0,1=380,2=0.000000
L 5.89943327 3.91034951 5.89866673 3.91448287 1 P 0 ;0,1=380,2=0.000000
L 5.89866673 3.91448287 5.8967498 3.91706663 1 P 0 ;0,1=380,2=0.000000
L 5.8967498 3.91706663 5.89406634 3.91913287 1 P 0 ;0,1=380,2=0.000000
L 5.89406634 3.91913287 5.89138356 3.91964941 1 P 0 ;0,1=380,2=0.000000
L 5.89138356 3.91964941 5.8887001 3.91913287 1 P 0 ;0,1=380,2=0.000000
L 5.8887001 3.91913287 5.8852501 3.91706663 1 P 0 ;0,1=380,2=0.000000
L 5.8852501 3.91706663 5.8863999 3.9305 1 P 0 ;0,1=380,2=0.000000
L 5.8863999 3.9305 5.8967498 3.9305 1 P 0 ;0,1=380,2=0.000000
L 1.2397 0.6866 1.2397 0.7306 1 P 0 
L 1.2397 0.7306 1.1497 0.7306 1 P 0 
L 1.1497 0.7306 1.1497 0.6866 1 P 0 
L 1.1497 0.6866 1.2397 0.6866 1 P 0 
L 1.10603317 0.8931 1.10603317 0.9241 1 P 0 ;0,1=381,2=0.000000
L 1.10603317 0.9241 1.11561654 0.9241 1 P 0 ;0,1=381,2=0.000000
L 1.11561654 0.9241 1.11868327 0.92254931 1 P 0 ;0,1=381,2=0.000000
L 1.11868327 0.92254931 1.1206002 0.92048307 1 P 0 ;0,1=381,2=0.000000
L 1.1206002 0.92048307 1.12136673 0.9163497 1 P 0 ;0,1=381,2=0.000000
L 1.12136673 0.9163497 1.1206002 0.91221634 1 P 0 ;0,1=381,2=0.000000
L 1.1206002 0.91221634 1.1183 0.90963356 1 P 0 ;0,1=381,2=0.000000
L 1.1183 0.90963356 1.11561654 0.90808287 1 P 0 ;0,1=381,2=0.000000
L 1.11561654 0.90808287 1.10603317 0.90808287 1 P 0 ;0,1=381,2=0.000000
L 1.11561654 0.90808287 1.12136673 0.8931 1 P 0 ;0,1=381,2=0.000000
L 1.14469961 0.8931 1.14469961 0.9241 1 P 0 ;0,1=381,2=0.000000
L 1.14469961 0.9241 1.1400999 0.9179003 1 P 0 ;0,1=381,2=0.000000
L 1.1400999 0.8931 1.14929931 0.8931 1 P 0 ;0,1=381,2=0.000000
L 1.16918287 0.89671585 1.17186634 0.89413307 1 P 0 ;0,1=381,2=0.000000
L 1.17186634 0.89413307 1.17493307 0.8931 1 P 0 ;0,1=381,2=0.000000
L 1.17493307 0.8931 1.1779998 0.89413307 1 P 0 ;0,1=381,2=0.000000
L 1.1779998 0.89413307 1.18068327 0.89723238 1 P 0 ;0,1=381,2=0.000000
L 1.18068327 0.89723238 1.1826002 0.90188327 1 P 0 ;0,1=381,2=0.000000
L 1.1826002 0.90188327 1.18336673 0.90653327 1 P 0 ;0,1=381,2=0.000000
L 1.18336673 0.90653327 1.18336673 0.91221634 1 P 0 ;0,1=381,2=0.000000
L 1.18336673 0.91221634 1.1826002 0.91686624 1 P 0 ;0,1=381,2=0.000000
L 1.1826002 0.91686624 1.18068327 0.9209997 1 P 0 ;0,1=381,2=0.000000
L 1.18068327 0.9209997 1.17838307 0.92306683 1 P 0 ;0,1=381,2=0.000000
L 1.17838307 0.92306683 1.17569961 0.9241 1 P 0 ;0,1=381,2=0.000000
L 1.17569961 0.9241 1.17263287 0.92306683 1 P 0 ;0,1=381,2=0.000000
L 1.17263287 0.92306683 1.17033337 0.9209997 1 P 0 ;0,1=381,2=0.000000
L 1.17033337 0.9209997 1.1687997 0.9179003 1 P 0 ;0,1=381,2=0.000000
L 1.1687997 0.9179003 1.16803317 0.91376594 1 P 0 ;0,1=381,2=0.000000
L 1.16803317 0.91376594 1.1687997 0.9101501 1 P 0 ;0,1=381,2=0.000000
L 1.1687997 0.9101501 1.17071663 0.90653327 1 P 0 ;0,1=381,2=0.000000
L 1.17071663 0.90653327 1.17301683 0.90446604 1 P 0 ;0,1=381,2=0.000000
L 1.17301683 0.90446604 1.17569961 0.90394951 1 P 0 ;0,1=381,2=0.000000
L 1.17569961 0.90394951 1.17876634 0.90498268 1 P 0 ;0,1=381,2=0.000000
L 1.17876634 0.90498268 1.18106654 0.90756634 1 P 0 ;0,1=381,2=0.000000
L 1.18106654 0.90756634 1.18336673 0.91221634 1 P 0 ;0,1=381,2=0.000000
L 1.2397 0.7316 1.2397 0.7756 1 P 0 
L 1.2397 0.7756 1.1497 0.7756 1 P 0 
L 1.1497 0.7756 1.1497 0.7316 1 P 0 
L 1.1497 0.7316 1.2397 0.7316 1 P 0 
L 1.10503317 0.9331 1.10503317 0.9641 1 P 0 ;0,1=382,2=0.000000
L 1.10503317 0.9641 1.11461654 0.9641 1 P 0 ;0,1=382,2=0.000000
L 1.11461654 0.9641 1.11768327 0.96254931 1 P 0 ;0,1=382,2=0.000000
L 1.11768327 0.96254931 1.1196002 0.96048307 1 P 0 ;0,1=382,2=0.000000
L 1.1196002 0.96048307 1.12036673 0.9563497 1 P 0 ;0,1=382,2=0.000000
L 1.12036673 0.9563497 1.1196002 0.95221634 1 P 0 ;0,1=382,2=0.000000
L 1.1196002 0.95221634 1.1173 0.94963356 1 P 0 ;0,1=382,2=0.000000
L 1.1173 0.94963356 1.11461654 0.94808287 1 P 0 ;0,1=382,2=0.000000
L 1.11461654 0.94808287 1.10503317 0.94808287 1 P 0 ;0,1=382,2=0.000000
L 1.11461654 0.94808287 1.12036673 0.9331 1 P 0 ;0,1=382,2=0.000000
L 1.14369961 0.9331 1.14369961 0.9641 1 P 0 ;0,1=382,2=0.000000
L 1.14369961 0.9641 1.1390999 0.9579003 1 P 0 ;0,1=382,2=0.000000
L 1.1390999 0.9331 1.14829931 0.9331 1 P 0 ;0,1=382,2=0.000000
L 1.16818287 0.93671585 1.17086634 0.93413307 1 P 0 ;0,1=382,2=0.000000
L 1.17086634 0.93413307 1.17393307 0.9331 1 P 0 ;0,1=382,2=0.000000
L 1.17393307 0.9331 1.1769998 0.93413307 1 P 0 ;0,1=382,2=0.000000
L 1.1769998 0.93413307 1.17968327 0.93723238 1 P 0 ;0,1=382,2=0.000000
L 1.17968327 0.93723238 1.1816002 0.94188327 1 P 0 ;0,1=382,2=0.000000
L 1.1816002 0.94188327 1.18236673 0.94653327 1 P 0 ;0,1=382,2=0.000000
L 1.18236673 0.94653327 1.18236673 0.95221634 1 P 0 ;0,1=382,2=0.000000
L 1.18236673 0.95221634 1.1816002 0.95686624 1 P 0 ;0,1=382,2=0.000000
L 1.1816002 0.95686624 1.17968327 0.9609997 1 P 0 ;0,1=382,2=0.000000
L 1.17968327 0.9609997 1.17738307 0.96306683 1 P 0 ;0,1=382,2=0.000000
L 1.17738307 0.96306683 1.17469961 0.9641 1 P 0 ;0,1=382,2=0.000000
L 1.17469961 0.9641 1.17163287 0.96306683 1 P 0 ;0,1=382,2=0.000000
L 1.17163287 0.96306683 1.16933337 0.9609997 1 P 0 ;0,1=382,2=0.000000
L 1.16933337 0.9609997 1.1677997 0.9579003 1 P 0 ;0,1=382,2=0.000000
L 1.1677997 0.9579003 1.16703317 0.95376594 1 P 0 ;0,1=382,2=0.000000
L 1.16703317 0.95376594 1.1677997 0.9501501 1 P 0 ;0,1=382,2=0.000000
L 1.1677997 0.9501501 1.16971663 0.94653327 1 P 0 ;0,1=382,2=0.000000
L 1.16971663 0.94653327 1.17201683 0.94446604 1 P 0 ;0,1=382,2=0.000000
L 1.17201683 0.94446604 1.17469961 0.94394951 1 P 0 ;0,1=382,2=0.000000
L 1.17469961 0.94394951 1.17776634 0.94498268 1 P 0 ;0,1=382,2=0.000000
L 1.17776634 0.94498268 1.18006654 0.94756634 1 P 0 ;0,1=382,2=0.000000
L 1.18006654 0.94756634 1.18236673 0.95221634 1 P 0 ;0,1=382,2=0.000000
L 1.19918287 0.93671585 1.20186634 0.93413307 1 P 0 ;0,1=382,2=0.000000
L 1.20186634 0.93413307 1.20493307 0.9331 1 P 0 ;0,1=382,2=0.000000
L 1.20493307 0.9331 1.2079998 0.93413307 1 P 0 ;0,1=382,2=0.000000
L 1.2079998 0.93413307 1.21068327 0.93723238 1 P 0 ;0,1=382,2=0.000000
L 1.21068327 0.93723238 1.2126002 0.94188327 1 P 0 ;0,1=382,2=0.000000
L 1.2126002 0.94188327 1.21336673 0.94653327 1 P 0 ;0,1=382,2=0.000000
L 1.21336673 0.94653327 1.21336673 0.95221634 1 P 0 ;0,1=382,2=0.000000
L 1.21336673 0.95221634 1.2126002 0.95686624 1 P 0 ;0,1=382,2=0.000000
L 1.2126002 0.95686624 1.21068327 0.9609997 1 P 0 ;0,1=382,2=0.000000
L 1.21068327 0.9609997 1.20838307 0.96306683 1 P 0 ;0,1=382,2=0.000000
L 1.20838307 0.96306683 1.20569961 0.9641 1 P 0 ;0,1=382,2=0.000000
L 1.20569961 0.9641 1.20263287 0.96306683 1 P 0 ;0,1=382,2=0.000000
L 1.20263287 0.96306683 1.20033337 0.9609997 1 P 0 ;0,1=382,2=0.000000
L 1.20033337 0.9609997 1.1987997 0.9579003 1 P 0 ;0,1=382,2=0.000000
L 1.1987997 0.9579003 1.19803317 0.95376594 1 P 0 ;0,1=382,2=0.000000
L 1.19803317 0.95376594 1.1987997 0.9501501 1 P 0 ;0,1=382,2=0.000000
L 1.1987997 0.9501501 1.20071663 0.94653327 1 P 0 ;0,1=382,2=0.000000
L 1.20071663 0.94653327 1.20301683 0.94446604 1 P 0 ;0,1=382,2=0.000000
L 1.20301683 0.94446604 1.20569961 0.94394951 1 P 0 ;0,1=382,2=0.000000
L 1.20569961 0.94394951 1.20876634 0.94498268 1 P 0 ;0,1=382,2=0.000000
L 1.20876634 0.94498268 1.21106654 0.94756634 1 P 0 ;0,1=382,2=0.000000
L 1.21106654 0.94756634 1.21336673 0.95221634 1 P 0 ;0,1=382,2=0.000000
L 1.22941644 0.95893346 1.23171663 0.96203278 1 P 0 ;0,1=382,2=0.000000
L 1.23171663 0.96203278 1.2344001 0.96358337 1 P 0 ;0,1=382,2=0.000000
L 1.2344001 0.96358337 1.23746683 0.9641 1 P 0 ;0,1=382,2=0.000000
L 1.23746683 0.9641 1.2413 0.96306683 1 P 0 ;0,1=382,2=0.000000
L 1.2413 0.96306683 1.24398346 0.96048307 1 P 0 ;0,1=382,2=0.000000
L 1.24398346 0.96048307 1.24475 0.95738376 1 P 0 ;0,1=382,2=0.000000
L 1.24475 0.95738376 1.24436673 0.95428258 1 P 0 ;0,1=382,2=0.000000
L 1.24436673 0.95428258 1.24283307 0.9516998 1 P 0 ;0,1=382,2=0.000000
L 1.24283307 0.9516998 1.23516663 0.94653327 1 P 0 ;0,1=382,2=0.000000
L 1.23516663 0.94653327 1.23171663 0.94291644 1 P 0 ;0,1=382,2=0.000000
L 1.23171663 0.94291644 1.22941644 0.93774892 1 P 0 ;0,1=382,2=0.000000
L 1.22941644 0.93774892 1.2286499 0.9331 1 P 0 ;0,1=382,2=0.000000
L 1.2286499 0.9331 1.24475 0.9331 1 P 0 ;0,1=382,2=0.000000
L 1.2397 0.6366 1.2397 0.6806 1 P 0 
L 1.2397 0.6806 1.1497 0.6806 1 P 0 
L 1.1497 0.6806 1.1497 0.6366 1 P 0 
L 1.1497 0.6366 1.2397 0.6366 1 P 0 
L 1.10553317 0.8481 1.10553317 0.8791 1 P 0 ;0,1=383,2=0.000000
L 1.10553317 0.8791 1.11511654 0.8791 1 P 0 ;0,1=383,2=0.000000
L 1.11511654 0.8791 1.11818327 0.87754931 1 P 0 ;0,1=383,2=0.000000
L 1.11818327 0.87754931 1.1201002 0.87548307 1 P 0 ;0,1=383,2=0.000000
L 1.1201002 0.87548307 1.12086673 0.8713497 1 P 0 ;0,1=383,2=0.000000
L 1.12086673 0.8713497 1.1201002 0.86721634 1 P 0 ;0,1=383,2=0.000000
L 1.1201002 0.86721634 1.1178 0.86463356 1 P 0 ;0,1=383,2=0.000000
L 1.1178 0.86463356 1.11511654 0.86308287 1 P 0 ;0,1=383,2=0.000000
L 1.11511654 0.86308287 1.10553317 0.86308287 1 P 0 ;0,1=383,2=0.000000
L 1.11511654 0.86308287 1.12086673 0.8481 1 P 0 ;0,1=383,2=0.000000
L 1.13576663 0.85429961 1.13806614 0.85068278 1 P 0 ;0,1=383,2=0.000000
L 1.13806614 0.85068278 1.14113287 0.84861654 1 P 0 ;0,1=383,2=0.000000
L 1.14113287 0.84861654 1.14458356 0.8481 1 P 0 ;0,1=383,2=0.000000
L 1.14458356 0.8481 1.1476503 0.84861654 1 P 0 ;0,1=383,2=0.000000
L 1.1476503 0.84861654 1.15071703 0.85119931 1 P 0 ;0,1=383,2=0.000000
L 1.15071703 0.85119931 1.15263327 0.85429961 1 P 0 ;0,1=383,2=0.000000
L 1.15263327 0.85429961 1.15301654 0.8573999 1 P 0 ;0,1=383,2=0.000000
L 1.15301654 0.8573999 1.15225 0.86101575 1 P 0 ;0,1=383,2=0.000000
L 1.15225 0.86101575 1.14956654 0.86359951 1 P 0 ;0,1=383,2=0.000000
L 1.14956654 0.86359951 1.14688307 0.86463356 1 P 0 ;0,1=383,2=0.000000
L 1.14688307 0.86463356 1.14343307 0.86463356 1 P 0 ;0,1=383,2=0.000000
L 1.14688307 0.86463356 1.14918327 0.86618317 1 P 0 ;0,1=383,2=0.000000
L 1.14918327 0.86618317 1.1511002 0.86876594 1 P 0 ;0,1=383,2=0.000000
L 1.1511002 0.86876594 1.15186673 0.87186624 1 P 0 ;0,1=383,2=0.000000
L 1.15186673 0.87186624 1.1511002 0.87496654 1 P 0 ;0,1=383,2=0.000000
L 1.1511002 0.87496654 1.14918327 0.87754931 1 P 0 ;0,1=383,2=0.000000
L 1.14918327 0.87754931 1.14573327 0.8791 1 P 0 ;0,1=383,2=0.000000
L 1.14573327 0.8791 1.14228337 0.87858337 1 P 0 ;0,1=383,2=0.000000
L 1.14228337 0.87858337 1.13883337 0.87651624 1 P 0 ;0,1=383,2=0.000000
L 1.1798 0.8481 1.1798 0.8791 1 P 0 ;0,1=383,2=0.000000
L 1.1798 0.8791 1.16561624 0.85688327 1 P 0 ;0,1=383,2=0.000000
L 1.16561624 0.85688327 1.18478366 0.85688327 1 P 0 ;0,1=383,2=0.000000
L 1.19776663 0.85274892 1.20006614 0.85016614 1 P 0 ;0,1=383,2=0.000000
L 1.20006614 0.85016614 1.20274961 0.84861654 1 P 0 ;0,1=383,2=0.000000
L 1.20274961 0.84861654 1.20619961 0.8481 1 P 0 ;0,1=383,2=0.000000
L 1.20619961 0.8481 1.2096503 0.84913307 1 P 0 ;0,1=383,2=0.000000
L 1.2096503 0.84913307 1.21233307 0.85119931 1 P 0 ;0,1=383,2=0.000000
L 1.21233307 0.85119931 1.21425 0.85481614 1 P 0 ;0,1=383,2=0.000000
L 1.21425 0.85481614 1.21463327 0.85894951 1 P 0 ;0,1=383,2=0.000000
L 1.21463327 0.85894951 1.21386673 0.86308287 1 P 0 ;0,1=383,2=0.000000
L 1.21386673 0.86308287 1.2119498 0.86566663 1 P 0 ;0,1=383,2=0.000000
L 1.2119498 0.86566663 1.20926634 0.86773287 1 P 0 ;0,1=383,2=0.000000
L 1.20926634 0.86773287 1.20658356 0.86824941 1 P 0 ;0,1=383,2=0.000000
L 1.20658356 0.86824941 1.2039001 0.86773287 1 P 0 ;0,1=383,2=0.000000
L 1.2039001 0.86773287 1.2004501 0.86566663 1 P 0 ;0,1=383,2=0.000000
L 1.2004501 0.86566663 1.2015999 0.8791 1 P 0 ;0,1=383,2=0.000000
L 1.2015999 0.8791 1.2119498 0.8791 1 P 0 ;0,1=383,2=0.000000
L 5.625 3.938 5.625 3.982 1 P 0 
L 5.625 3.982 5.535 3.982 1 P 0 
L 5.535 3.982 5.535 3.938 1 P 0 
L 5.535 3.938 5.625 3.938 1 P 0 
L 5.63266654 3.9225 5.63266654 3.9475 1 P 0 ;0,1=384,2=0.000000
L 5.63266654 3.9475 5.63933327 3.9475 1 P 0 ;0,1=384,2=0.000000
L 5.63933327 3.9475 5.64146663 3.94624941 1 P 0 ;0,1=384,2=0.000000
L 5.64146663 3.94624941 5.6428001 3.94458317 1 P 0 ;0,1=384,2=0.000000
L 5.6428001 3.94458317 5.64333337 3.9412498 1 P 0 ;0,1=384,2=0.000000
L 5.64333337 3.9412498 5.6428001 3.93791634 1 P 0 ;0,1=384,2=0.000000
L 5.6428001 3.93791634 5.6412 3.93583346 1 P 0 ;0,1=384,2=0.000000
L 5.6412 3.93583346 5.63933327 3.93458297 1 P 0 ;0,1=384,2=0.000000
L 5.63933327 3.93458297 5.63266654 3.93458297 1 P 0 ;0,1=384,2=0.000000
L 5.63933327 3.93458297 5.64333337 3.9225 1 P 0 ;0,1=384,2=0.000000
L 5.6599997 3.9225 5.6599997 3.9475 1 P 0 ;0,1=384,2=0.000000
L 5.6599997 3.9475 5.6567999 3.9425003 1 P 0 ;0,1=384,2=0.000000
L 5.6567999 3.9225 5.66319951 3.9225 1 P 0 ;0,1=384,2=0.000000
L 5.67613327 3.92749961 5.67773297 3.92458287 1 P 0 ;0,1=384,2=0.000000
L 5.67773297 3.92458287 5.67986634 3.92291654 1 P 0 ;0,1=384,2=0.000000
L 5.67986634 3.92291654 5.68226683 3.9225 1 P 0 ;0,1=384,2=0.000000
L 5.68226683 3.9225 5.6844002 3.92291654 1 P 0 ;0,1=384,2=0.000000
L 5.6844002 3.92291654 5.68653356 3.92499941 1 P 0 ;0,1=384,2=0.000000
L 5.68653356 3.92499941 5.68786663 3.92749961 1 P 0 ;0,1=384,2=0.000000
L 5.68786663 3.92749961 5.68813317 3.9299999 1 P 0 ;0,1=384,2=0.000000
L 5.68813317 3.9299999 5.6876 3.93291594 1 P 0 ;0,1=384,2=0.000000
L 5.6876 3.93291594 5.68573327 3.93499961 1 P 0 ;0,1=384,2=0.000000
L 5.68573327 3.93499961 5.68386644 3.93583346 1 P 0 ;0,1=384,2=0.000000
L 5.68386644 3.93583346 5.68146654 3.93583346 1 P 0 ;0,1=384,2=0.000000
L 5.68386644 3.93583346 5.68546663 3.93708327 1 P 0 ;0,1=384,2=0.000000
L 5.68546663 3.93708327 5.6868001 3.93916614 1 P 0 ;0,1=384,2=0.000000
L 5.6868001 3.93916614 5.68733337 3.94166634 1 P 0 ;0,1=384,2=0.000000
L 5.68733337 3.94166634 5.6868001 3.94416654 1 P 0 ;0,1=384,2=0.000000
L 5.6868001 3.94416654 5.68546663 3.94624941 1 P 0 ;0,1=384,2=0.000000
L 5.68546663 3.94624941 5.68306663 3.9475 1 P 0 ;0,1=384,2=0.000000
L 5.68306663 3.9475 5.68066663 3.94708337 1 P 0 ;0,1=384,2=0.000000
L 5.68066663 3.94708337 5.67826663 3.94541634 1 P 0 ;0,1=384,2=0.000000
L 5.296 3.935 5.386 3.935 1 P 0 
L 5.386 3.935 5.386 3.979 1 P 0 
L 5.386 3.979 5.296 3.979 1 P 0 
L 5.296 3.979 5.296 3.935 1 P 0 
L 5.22133317 3.9545 5.22133317 3.9855 1 P 0 ;0,1=385,2=0.000000
L 5.22133317 3.9855 5.23091654 3.9855 1 P 0 ;0,1=385,2=0.000000
L 5.23091654 3.9855 5.23398327 3.98394931 1 P 0 ;0,1=385,2=0.000000
L 5.23398327 3.98394931 5.2359002 3.98188307 1 P 0 ;0,1=385,2=0.000000
L 5.2359002 3.98188307 5.23666673 3.9777497 1 P 0 ;0,1=385,2=0.000000
L 5.23666673 3.9777497 5.2359002 3.97361634 1 P 0 ;0,1=385,2=0.000000
L 5.2359002 3.97361634 5.2336 3.97103356 1 P 0 ;0,1=385,2=0.000000
L 5.2336 3.97103356 5.23091654 3.96948287 1 P 0 ;0,1=385,2=0.000000
L 5.23091654 3.96948287 5.22133317 3.96948287 1 P 0 ;0,1=385,2=0.000000
L 5.23091654 3.96948287 5.23666673 3.9545 1 P 0 ;0,1=385,2=0.000000
L 5.25999961 3.9545 5.25999961 3.9855 1 P 0 ;0,1=385,2=0.000000
L 5.25999961 3.9855 5.2553999 3.9793003 1 P 0 ;0,1=385,2=0.000000
L 5.2553999 3.9545 5.26459931 3.9545 1 P 0 ;0,1=385,2=0.000000
L 5.29099961 3.9545 5.29099961 3.9855 1 P 0 ;0,1=385,2=0.000000
L 5.29099961 3.9855 5.2863999 3.9793003 1 P 0 ;0,1=385,2=0.000000
L 5.2863999 3.9545 5.29559931 3.9545 1 P 0 ;0,1=385,2=0.000000
L 5.53043002 3.989 5.44043002 3.989 1 P 0 
L 5.44043002 3.989 5.44043002 3.945 1 P 0 
L 5.44043002 3.945 5.53043002 3.945 1 P 0 
L 5.53043002 3.945 5.53043002 3.989 1 P 0 
L 5.40133317 3.9945 5.40133317 4.0255 1 P 0 ;0,1=386,2=0.000000
L 5.40133317 4.0255 5.41091654 4.0255 1 P 0 ;0,1=386,2=0.000000
L 5.41091654 4.0255 5.41398327 4.02394931 1 P 0 ;0,1=386,2=0.000000
L 5.41398327 4.02394931 5.4159002 4.02188307 1 P 0 ;0,1=386,2=0.000000
L 5.4159002 4.02188307 5.41666673 4.0177497 1 P 0 ;0,1=386,2=0.000000
L 5.41666673 4.0177497 5.4159002 4.01361634 1 P 0 ;0,1=386,2=0.000000
L 5.4159002 4.01361634 5.4136 4.01103356 1 P 0 ;0,1=386,2=0.000000
L 5.4136 4.01103356 5.41091654 4.00948287 1 P 0 ;0,1=386,2=0.000000
L 5.41091654 4.00948287 5.40133317 4.00948287 1 P 0 ;0,1=386,2=0.000000
L 5.41091654 4.00948287 5.41666673 3.9945 1 P 0 ;0,1=386,2=0.000000
L 5.43999961 3.9945 5.43999961 4.0255 1 P 0 ;0,1=386,2=0.000000
L 5.43999961 4.0255 5.4353999 4.0193003 1 P 0 ;0,1=386,2=0.000000
L 5.4353999 3.9945 5.44459931 3.9945 1 P 0 ;0,1=386,2=0.000000
L 5.46371644 4.02033346 5.46601663 4.02343278 1 P 0 ;0,1=386,2=0.000000
L 5.46601663 4.02343278 5.4687001 4.02498337 1 P 0 ;0,1=386,2=0.000000
L 5.4687001 4.02498337 5.47176683 4.0255 1 P 0 ;0,1=386,2=0.000000
L 5.47176683 4.0255 5.4756 4.02446683 1 P 0 ;0,1=386,2=0.000000
L 5.4756 4.02446683 5.47828346 4.02188307 1 P 0 ;0,1=386,2=0.000000
L 5.47828346 4.02188307 5.47905 4.01878376 1 P 0 ;0,1=386,2=0.000000
L 5.47905 4.01878376 5.47866673 4.01568258 1 P 0 ;0,1=386,2=0.000000
L 5.47866673 4.01568258 5.47713307 4.0130998 1 P 0 ;0,1=386,2=0.000000
L 5.47713307 4.0130998 5.46946663 4.00793327 1 P 0 ;0,1=386,2=0.000000
L 5.46946663 4.00793327 5.46601663 4.00431644 1 P 0 ;0,1=386,2=0.000000
L 5.46601663 4.00431644 5.46371644 3.99914892 1 P 0 ;0,1=386,2=0.000000
L 5.46371644 3.99914892 5.4629499 3.9945 1 P 0 ;0,1=386,2=0.000000
L 5.4629499 3.9945 5.47905 3.9945 1 P 0 ;0,1=386,2=0.000000
L 0.82848002 2.855 0.78448002 2.855 1 P 0 
L 0.82848002 2.765 0.82848002 2.855 1 P 0 
L 0.78448002 2.855 0.78448002 2.765 1 P 0 
L 0.78448002 2.765 0.82848002 2.765 1 P 0 
L 0.8655 2.78133317 0.8345 2.78133317 1 P 0 ;0,1=387,2=270.000000
L 0.8345 2.78133317 0.8345 2.79091654 1 P 0 ;0,1=387,2=270.000000
L 0.8345 2.79091654 0.83605069 2.79398327 1 P 0 ;0,1=387,2=270.000000
L 0.83605069 2.79398327 0.83811693 2.7959002 1 P 0 ;0,1=387,2=270.000000
L 0.83811693 2.7959002 0.8422503 2.79666673 1 P 0 ;0,1=387,2=270.000000
L 0.8422503 2.79666673 0.84638366 2.7959002 1 P 0 ;0,1=387,2=270.000000
L 0.84638366 2.7959002 0.84896644 2.7936 1 P 0 ;0,1=387,2=270.000000
L 0.84896644 2.7936 0.85051713 2.79091654 1 P 0 ;0,1=387,2=270.000000
L 0.85051713 2.79091654 0.85051713 2.78133317 1 P 0 ;0,1=387,2=270.000000
L 0.85051713 2.79091654 0.8655 2.79666673 1 P 0 ;0,1=387,2=270.000000
L 0.8655 2.81923307 0.85878386 2.81999961 1 P 0 ;0,1=387,2=270.000000
L 0.85878386 2.81999961 0.85310079 2.8211501 1 P 0 ;0,1=387,2=270.000000
L 0.85310079 2.8211501 0.84793337 2.82268307 1 P 0 ;0,1=387,2=270.000000
L 0.84793337 2.82268307 0.8422503 2.8246 1 P 0 ;0,1=387,2=270.000000
L 0.8422503 2.8246 0.8345 2.82766673 1 P 0 ;0,1=387,2=270.000000
L 0.8345 2.82766673 0.8345 2.81233317 1 P 0 ;0,1=387,2=270.000000
L 0.8655 2.85099961 0.8345 2.85099961 1 P 0 ;0,1=387,2=270.000000
L 0.8345 2.85099961 0.8406997 2.8463999 1 P 0 ;0,1=387,2=270.000000
L 0.8655 2.8463999 0.8655 2.85559931 1 P 0 ;0,1=387,2=270.000000
L 0.78 2.812 0.69 2.812 1 P 0 
L 0.69 2.812 0.69 2.768 1 P 0 
L 0.69 2.768 0.78 2.768 1 P 0 
L 0.78 2.768 0.78 2.812 1 P 0 
L 0.72133317 2.8645 0.72133317 2.8955 1 P 0 ;0,1=388,2=0.000000
L 0.72133317 2.8955 0.73091654 2.8955 1 P 0 ;0,1=388,2=0.000000
L 0.73091654 2.8955 0.73398327 2.89394931 1 P 0 ;0,1=388,2=0.000000
L 0.73398327 2.89394931 0.7359002 2.89188307 1 P 0 ;0,1=388,2=0.000000
L 0.7359002 2.89188307 0.73666673 2.8877497 1 P 0 ;0,1=388,2=0.000000
L 0.73666673 2.8877497 0.7359002 2.88361634 1 P 0 ;0,1=388,2=0.000000
L 0.7359002 2.88361634 0.7336 2.88103356 1 P 0 ;0,1=388,2=0.000000
L 0.7336 2.88103356 0.73091654 2.87948287 1 P 0 ;0,1=388,2=0.000000
L 0.73091654 2.87948287 0.72133317 2.87948287 1 P 0 ;0,1=388,2=0.000000
L 0.73091654 2.87948287 0.73666673 2.8645 1 P 0 ;0,1=388,2=0.000000
L 0.75923307 2.8645 0.75999961 2.87121614 1 P 0 ;0,1=388,2=0.000000
L 0.75999961 2.87121614 0.7611501 2.87689921 1 P 0 ;0,1=388,2=0.000000
L 0.7611501 2.87689921 0.76268307 2.88206663 1 P 0 ;0,1=388,2=0.000000
L 0.76268307 2.88206663 0.7646 2.8877497 1 P 0 ;0,1=388,2=0.000000
L 0.7646 2.8877497 0.76766673 2.8955 1 P 0 ;0,1=388,2=0.000000
L 0.76766673 2.8955 0.75233317 2.8955 1 P 0 ;0,1=388,2=0.000000
L 0.78256663 2.87069961 0.78486614 2.86708278 1 P 0 ;0,1=388,2=0.000000
L 0.78486614 2.86708278 0.78793287 2.86501654 1 P 0 ;0,1=388,2=0.000000
L 0.78793287 2.86501654 0.79138356 2.8645 1 P 0 ;0,1=388,2=0.000000
L 0.79138356 2.8645 0.7944503 2.86501654 1 P 0 ;0,1=388,2=0.000000
L 0.7944503 2.86501654 0.79751703 2.86759931 1 P 0 ;0,1=388,2=0.000000
L 0.79751703 2.86759931 0.79943327 2.87069961 1 P 0 ;0,1=388,2=0.000000
L 0.79943327 2.87069961 0.79981654 2.8737999 1 P 0 ;0,1=388,2=0.000000
L 0.79981654 2.8737999 0.79905 2.87741575 1 P 0 ;0,1=388,2=0.000000
L 0.79905 2.87741575 0.79636654 2.87999951 1 P 0 ;0,1=388,2=0.000000
L 0.79636654 2.87999951 0.79368307 2.88103356 1 P 0 ;0,1=388,2=0.000000
L 0.79368307 2.88103356 0.79023307 2.88103356 1 P 0 ;0,1=388,2=0.000000
L 0.79368307 2.88103356 0.79598327 2.88258317 1 P 0 ;0,1=388,2=0.000000
L 0.79598327 2.88258317 0.7979002 2.88516594 1 P 0 ;0,1=388,2=0.000000
L 0.7979002 2.88516594 0.79866673 2.88826624 1 P 0 ;0,1=388,2=0.000000
L 0.79866673 2.88826624 0.7979002 2.89136654 1 P 0 ;0,1=388,2=0.000000
L 0.7979002 2.89136654 0.79598327 2.89394931 1 P 0 ;0,1=388,2=0.000000
L 0.79598327 2.89394931 0.79253327 2.8955 1 P 0 ;0,1=388,2=0.000000
L 0.79253327 2.8955 0.78908337 2.89498337 1 P 0 ;0,1=388,2=0.000000
L 0.78908337 2.89498337 0.78563337 2.89291624 1 P 0 ;0,1=388,2=0.000000
L 0.556 2.635 0.556 2.545 1 P 0 
L 0.556 2.545 0.6 2.545 1 P 0 
L 0.6 2.545 0.6 2.635 1 P 0 
L 0.6 2.635 0.556 2.635 1 P 0 
L 0.5755 2.74583317 0.5445 2.74583317 1 P 0 ;0,1=389,2=270.000000
L 0.5445 2.74583317 0.5445 2.75541654 1 P 0 ;0,1=389,2=270.000000
L 0.5445 2.75541654 0.54605069 2.75848327 1 P 0 ;0,1=389,2=270.000000
L 0.54605069 2.75848327 0.54811693 2.7604002 1 P 0 ;0,1=389,2=270.000000
L 0.54811693 2.7604002 0.5522503 2.76116673 1 P 0 ;0,1=389,2=270.000000
L 0.5522503 2.76116673 0.55638366 2.7604002 1 P 0 ;0,1=389,2=270.000000
L 0.55638366 2.7604002 0.55896644 2.7581 1 P 0 ;0,1=389,2=270.000000
L 0.55896644 2.7581 0.56051713 2.75541654 1 P 0 ;0,1=389,2=270.000000
L 0.56051713 2.75541654 0.56051713 2.74583317 1 P 0 ;0,1=389,2=270.000000
L 0.56051713 2.75541654 0.5755 2.76116673 1 P 0 ;0,1=389,2=270.000000
L 0.56930039 2.77606663 0.57291722 2.77836614 1 P 0 ;0,1=389,2=270.000000
L 0.57291722 2.77836614 0.57498346 2.78143287 1 P 0 ;0,1=389,2=270.000000
L 0.57498346 2.78143287 0.5755 2.78488356 1 P 0 ;0,1=389,2=270.000000
L 0.5755 2.78488356 0.57498346 2.7879503 1 P 0 ;0,1=389,2=270.000000
L 0.57498346 2.7879503 0.57240069 2.79101703 1 P 0 ;0,1=389,2=270.000000
L 0.57240069 2.79101703 0.56930039 2.79293327 1 P 0 ;0,1=389,2=270.000000
L 0.56930039 2.79293327 0.5662001 2.79331654 1 P 0 ;0,1=389,2=270.000000
L 0.5662001 2.79331654 0.56258425 2.79255 1 P 0 ;0,1=389,2=270.000000
L 0.56258425 2.79255 0.56000049 2.78986654 1 P 0 ;0,1=389,2=270.000000
L 0.56000049 2.78986654 0.55896644 2.78718307 1 P 0 ;0,1=389,2=270.000000
L 0.55896644 2.78718307 0.55896644 2.78373307 1 P 0 ;0,1=389,2=270.000000
L 0.55896644 2.78718307 0.55741683 2.78948327 1 P 0 ;0,1=389,2=270.000000
L 0.55741683 2.78948327 0.55483406 2.7914002 1 P 0 ;0,1=389,2=270.000000
L 0.55483406 2.7914002 0.55173376 2.79216673 1 P 0 ;0,1=389,2=270.000000
L 0.55173376 2.79216673 0.54863346 2.7914002 1 P 0 ;0,1=389,2=270.000000
L 0.54863346 2.7914002 0.54605069 2.78948327 1 P 0 ;0,1=389,2=270.000000
L 0.54605069 2.78948327 0.5445 2.78603327 1 P 0 ;0,1=389,2=270.000000
L 0.5445 2.78603327 0.54501663 2.78258337 1 P 0 ;0,1=389,2=270.000000
L 0.54501663 2.78258337 0.54708376 2.77913337 1 P 0 ;0,1=389,2=270.000000
L 0.56258425 2.80821644 0.55896644 2.8108999 1 P 0 ;0,1=389,2=270.000000
L 0.55896644 2.8108999 0.5569002 2.8132001 1 P 0 ;0,1=389,2=270.000000
L 0.5569002 2.8132001 0.55586713 2.81626683 1 P 0 ;0,1=389,2=270.000000
L 0.55586713 2.81626683 0.5569002 2.8189503 1 P 0 ;0,1=389,2=270.000000
L 0.5569002 2.8189503 0.55896644 2.82086654 1 P 0 ;0,1=389,2=270.000000
L 0.55896644 2.82086654 0.56206673 2.8224002 1 P 0 ;0,1=389,2=270.000000
L 0.56206673 2.8224002 0.56568356 2.82278346 1 P 0 ;0,1=389,2=270.000000
L 0.56568356 2.82278346 0.56878386 2.8224002 1 P 0 ;0,1=389,2=270.000000
L 0.56878386 2.8224002 0.57188415 2.82086654 1 P 0 ;0,1=389,2=270.000000
L 0.57188415 2.82086654 0.57446693 2.81856634 1 P 0 ;0,1=389,2=270.000000
L 0.57446693 2.81856634 0.5755 2.81588356 1 P 0 ;0,1=389,2=270.000000
L 0.5755 2.81588356 0.57446693 2.81281683 1 P 0 ;0,1=389,2=270.000000
L 0.57446693 2.81281683 0.57136762 2.81013337 1 P 0 ;0,1=389,2=270.000000
L 0.57136762 2.81013337 0.56671673 2.8085997 1 P 0 ;0,1=389,2=270.000000
L 0.56671673 2.8085997 0.5615502 2.80821644 1 P 0 ;0,1=389,2=270.000000
L 0.5615502 2.80821644 0.55483406 2.80898287 1 P 0 ;0,1=389,2=270.000000
L 0.55483406 2.80898287 0.55121624 2.81013337 1 P 0 ;0,1=389,2=270.000000
L 0.55121624 2.81013337 0.5476003 2.81204961 1 P 0 ;0,1=389,2=270.000000
L 0.5476003 2.81204961 0.54501663 2.81473307 1 P 0 ;0,1=389,2=270.000000
L 0.54501663 2.81473307 0.5445 2.81741654 1 P 0 ;0,1=389,2=270.000000
L 0.5445 2.81741654 0.54553317 2.8201 1 P 0 ;0,1=389,2=270.000000
L 0.54553317 2.8201 0.54811693 2.82201703 1 P 0 ;0,1=389,2=270.000000
L 0.5755 2.84649961 0.5445 2.84649961 1 P 0 ;0,1=389,2=270.000000
L 0.5445 2.84649961 0.5506997 2.8418999 1 P 0 ;0,1=389,2=270.000000
L 0.5755 2.8418999 0.5755 2.85109931 1 P 0 ;0,1=389,2=270.000000
L 2.105 2.907 2.105 2.997 1 P 0 
L 2.105 2.997 2.061 2.997 1 P 0 
L 2.061 2.997 2.061 2.907 1 P 0 
L 2.061 2.907 2.105 2.907 1 P 0 
L 2.2755 2.87583317 2.2445 2.87583317 1 P 0 ;0,1=390,2=270.000000
L 2.2445 2.87583317 2.2445 2.88541654 1 P 0 ;0,1=390,2=270.000000
L 2.2445 2.88541654 2.24605069 2.88848327 1 P 0 ;0,1=390,2=270.000000
L 2.24605069 2.88848327 2.24811693 2.8904002 1 P 0 ;0,1=390,2=270.000000
L 2.24811693 2.8904002 2.2522503 2.89116673 1 P 0 ;0,1=390,2=270.000000
L 2.2522503 2.89116673 2.25638366 2.8904002 1 P 0 ;0,1=390,2=270.000000
L 2.25638366 2.8904002 2.25896644 2.8881 1 P 0 ;0,1=390,2=270.000000
L 2.25896644 2.8881 2.26051713 2.88541654 1 P 0 ;0,1=390,2=270.000000
L 2.26051713 2.88541654 2.26051713 2.87583317 1 P 0 ;0,1=390,2=270.000000
L 2.26051713 2.88541654 2.2755 2.89116673 1 P 0 ;0,1=390,2=270.000000
L 2.2755 2.9191 2.2445 2.9191 1 P 0 ;0,1=390,2=270.000000
L 2.2445 2.9191 2.26671673 2.90491624 1 P 0 ;0,1=390,2=270.000000
L 2.26671673 2.90491624 2.26671673 2.92408366 1 P 0 ;0,1=390,2=270.000000
L 2.2445 2.94549961 2.24553317 2.94243287 1 P 0 ;0,1=390,2=270.000000
L 2.24553317 2.94243287 2.24811693 2.94013337 1 P 0 ;0,1=390,2=270.000000
L 2.24811693 2.94013337 2.25121624 2.9385997 1 P 0 ;0,1=390,2=270.000000
L 2.25121624 2.9385997 2.25535059 2.9374499 1 P 0 ;0,1=390,2=270.000000
L 2.25535059 2.9374499 2.26000049 2.93706663 1 P 0 ;0,1=390,2=270.000000
L 2.26000049 2.93706663 2.26465049 2.9374499 1 P 0 ;0,1=390,2=270.000000
L 2.26465049 2.9374499 2.26878386 2.9385997 1 P 0 ;0,1=390,2=270.000000
L 2.26878386 2.9385997 2.27188415 2.94013337 1 P 0 ;0,1=390,2=270.000000
L 2.27188415 2.94013337 2.27446693 2.94243287 1 P 0 ;0,1=390,2=270.000000
L 2.27446693 2.94243287 2.2755 2.94549961 1 P 0 ;0,1=390,2=270.000000
L 2.2755 2.94549961 2.27446693 2.94856634 1 P 0 ;0,1=390,2=270.000000
L 2.27446693 2.94856634 2.27188415 2.95086654 1 P 0 ;0,1=390,2=270.000000
L 2.27188415 2.95086654 2.26878386 2.9524002 1 P 0 ;0,1=390,2=270.000000
L 2.26878386 2.9524002 2.26465049 2.95355 1 P 0 ;0,1=390,2=270.000000
L 2.26465049 2.95355 2.26000049 2.95393327 1 P 0 ;0,1=390,2=270.000000
L 2.26000049 2.95393327 2.25535059 2.95355 1 P 0 ;0,1=390,2=270.000000
L 2.25535059 2.95355 2.25121624 2.9524002 1 P 0 ;0,1=390,2=270.000000
L 2.25121624 2.9524002 2.24811693 2.95086654 1 P 0 ;0,1=390,2=270.000000
L 2.24811693 2.95086654 2.24553317 2.94856634 1 P 0 ;0,1=390,2=270.000000
L 2.24553317 2.94856634 2.2445 2.94549961 1 P 0 ;0,1=390,2=270.000000
L 2.2755 2.97649961 2.27498346 2.97918307 1 P 0 ;0,1=390,2=270.000000
L 2.27498346 2.97918307 2.27343386 2.9822498 1 P 0 ;0,1=390,2=270.000000
L 2.27343386 2.9822498 2.27085108 2.98416673 1 P 0 ;0,1=390,2=270.000000
L 2.27085108 2.98416673 2.26723327 2.98493327 1 P 0 ;0,1=390,2=270.000000
L 2.26723327 2.98493327 2.26361732 2.98416673 1 P 0 ;0,1=390,2=270.000000
L 2.26361732 2.98416673 2.26051713 2.98186654 1 P 0 ;0,1=390,2=270.000000
L 2.26051713 2.98186654 2.25896644 2.97841654 1 P 0 ;0,1=390,2=270.000000
L 2.25896644 2.97841654 2.25896644 2.97458337 1 P 0 ;0,1=390,2=270.000000
L 2.25896644 2.97458337 2.25793337 2.97228317 1 P 0 ;0,1=390,2=270.000000
L 2.25793337 2.97228317 2.25535059 2.97036614 1 P 0 ;0,1=390,2=270.000000
L 2.25535059 2.97036614 2.25173376 2.9695997 1 P 0 ;0,1=390,2=270.000000
L 2.25173376 2.9695997 2.24811693 2.9707501 1 P 0 ;0,1=390,2=270.000000
L 2.24811693 2.9707501 2.24553317 2.97343287 1 P 0 ;0,1=390,2=270.000000
L 2.24553317 2.97343287 2.2445 2.97649961 1 P 0 ;0,1=390,2=270.000000
L 2.2445 2.97649961 2.24553317 2.97956634 1 P 0 ;0,1=390,2=270.000000
L 2.24553317 2.97956634 2.24811693 2.9822498 1 P 0 ;0,1=390,2=270.000000
L 2.24811693 2.9822498 2.25173376 2.9834002 1 P 0 ;0,1=390,2=270.000000
L 2.25173376 2.9834002 2.25535059 2.98263307 1 P 0 ;0,1=390,2=270.000000
L 2.25535059 2.98263307 2.25793337 2.98071673 1 P 0 ;0,1=390,2=270.000000
L 2.25793337 2.98071673 2.25896644 2.97841654 1 P 0 ;0,1=390,2=270.000000
L 2.25896644 2.97841654 2.25896644 2.97458337 1 P 0 ;0,1=390,2=270.000000
L 2.25896644 2.97458337 2.26051713 2.97113337 1 P 0 ;0,1=390,2=270.000000
L 2.26051713 2.97113337 2.26361732 2.96883317 1 P 0 ;0,1=390,2=270.000000
L 2.26361732 2.96883317 2.26723327 2.96806663 1 P 0 ;0,1=390,2=270.000000
L 2.26723327 2.96806663 2.27085108 2.96883317 1 P 0 ;0,1=390,2=270.000000
L 2.27085108 2.96883317 2.27343386 2.9707501 1 P 0 ;0,1=390,2=270.000000
L 2.27343386 2.9707501 2.27498346 2.97381683 1 P 0 ;0,1=390,2=270.000000
L 2.27498346 2.97381683 2.2755 2.97649961 1 P 0 ;0,1=390,2=270.000000
L 2.15 2.907 2.15 2.997 1 P 0 
L 2.15 2.997 2.106 2.997 1 P 0 
L 2.106 2.997 2.106 2.907 1 P 0 
L 2.106 2.907 2.15 2.907 1 P 0 
L 2.3155 2.87583317 2.2845 2.87583317 1 P 0 ;0,1=391,2=270.000000
L 2.2845 2.87583317 2.2845 2.88541654 1 P 0 ;0,1=391,2=270.000000
L 2.2845 2.88541654 2.28605069 2.88848327 1 P 0 ;0,1=391,2=270.000000
L 2.28605069 2.88848327 2.28811693 2.8904002 1 P 0 ;0,1=391,2=270.000000
L 2.28811693 2.8904002 2.2922503 2.89116673 1 P 0 ;0,1=391,2=270.000000
L 2.2922503 2.89116673 2.29638366 2.8904002 1 P 0 ;0,1=391,2=270.000000
L 2.29638366 2.8904002 2.29896644 2.8881 1 P 0 ;0,1=391,2=270.000000
L 2.29896644 2.8881 2.30051713 2.88541654 1 P 0 ;0,1=391,2=270.000000
L 2.30051713 2.88541654 2.30051713 2.87583317 1 P 0 ;0,1=391,2=270.000000
L 2.30051713 2.88541654 2.3155 2.89116673 1 P 0 ;0,1=391,2=270.000000
L 2.3155 2.9191 2.2845 2.9191 1 P 0 ;0,1=391,2=270.000000
L 2.2845 2.9191 2.30671673 2.90491624 1 P 0 ;0,1=391,2=270.000000
L 2.30671673 2.90491624 2.30671673 2.92408366 1 P 0 ;0,1=391,2=270.000000
L 2.3155 2.94549961 2.2845 2.94549961 1 P 0 ;0,1=391,2=270.000000
L 2.2845 2.94549961 2.2906997 2.9408999 1 P 0 ;0,1=391,2=270.000000
L 2.3155 2.9408999 2.3155 2.95009931 1 P 0 ;0,1=391,2=270.000000
L 2.28966654 2.96921644 2.28656722 2.97151663 1 P 0 ;0,1=391,2=270.000000
L 2.28656722 2.97151663 2.28501663 2.9742001 1 P 0 ;0,1=391,2=270.000000
L 2.28501663 2.9742001 2.2845 2.97726683 1 P 0 ;0,1=391,2=270.000000
L 2.2845 2.97726683 2.28553317 2.9811 1 P 0 ;0,1=391,2=270.000000
L 2.28553317 2.9811 2.28811693 2.98378346 1 P 0 ;0,1=391,2=270.000000
L 2.28811693 2.98378346 2.29121624 2.98455 1 P 0 ;0,1=391,2=270.000000
L 2.29121624 2.98455 2.29431742 2.98416673 1 P 0 ;0,1=391,2=270.000000
L 2.29431742 2.98416673 2.2969002 2.98263307 1 P 0 ;0,1=391,2=270.000000
L 2.2969002 2.98263307 2.30206673 2.97496663 1 P 0 ;0,1=391,2=270.000000
L 2.30206673 2.97496663 2.30568356 2.97151663 1 P 0 ;0,1=391,2=270.000000
L 2.30568356 2.97151663 2.31085108 2.96921644 1 P 0 ;0,1=391,2=270.000000
L 2.31085108 2.96921644 2.3155 2.9684499 1 P 0 ;0,1=391,2=270.000000
L 2.3155 2.9684499 2.3155 2.98455 1 P 0 ;0,1=391,2=270.000000
L 2.195 2.907 2.195 2.997 1 P 0 
L 2.195 2.997 2.151 2.997 1 P 0 
L 2.151 2.997 2.151 2.907 1 P 0 
L 2.151 2.907 2.195 2.907 1 P 0 
L 2.3555 2.87583317 2.3245 2.87583317 1 P 0 ;0,1=392,2=270.000000
L 2.3245 2.87583317 2.3245 2.88541654 1 P 0 ;0,1=392,2=270.000000
L 2.3245 2.88541654 2.32605069 2.88848327 1 P 0 ;0,1=392,2=270.000000
L 2.32605069 2.88848327 2.32811693 2.8904002 1 P 0 ;0,1=392,2=270.000000
L 2.32811693 2.8904002 2.3322503 2.89116673 1 P 0 ;0,1=392,2=270.000000
L 2.3322503 2.89116673 2.33638366 2.8904002 1 P 0 ;0,1=392,2=270.000000
L 2.33638366 2.8904002 2.33896644 2.8881 1 P 0 ;0,1=392,2=270.000000
L 2.33896644 2.8881 2.34051713 2.88541654 1 P 0 ;0,1=392,2=270.000000
L 2.34051713 2.88541654 2.34051713 2.87583317 1 P 0 ;0,1=392,2=270.000000
L 2.34051713 2.88541654 2.3555 2.89116673 1 P 0 ;0,1=392,2=270.000000
L 2.3555 2.9191 2.3245 2.9191 1 P 0 ;0,1=392,2=270.000000
L 2.3245 2.9191 2.34671673 2.90491624 1 P 0 ;0,1=392,2=270.000000
L 2.34671673 2.90491624 2.34671673 2.92408366 1 P 0 ;0,1=392,2=270.000000
L 2.3555 2.94549961 2.3245 2.94549961 1 P 0 ;0,1=392,2=270.000000
L 2.3245 2.94549961 2.3306997 2.9408999 1 P 0 ;0,1=392,2=270.000000
L 2.3555 2.9408999 2.3555 2.95009931 1 P 0 ;0,1=392,2=270.000000
L 2.3555 2.97649961 2.35498346 2.97918307 1 P 0 ;0,1=392,2=270.000000
L 2.35498346 2.97918307 2.35343386 2.9822498 1 P 0 ;0,1=392,2=270.000000
L 2.35343386 2.9822498 2.35085108 2.98416673 1 P 0 ;0,1=392,2=270.000000
L 2.35085108 2.98416673 2.34723327 2.98493327 1 P 0 ;0,1=392,2=270.000000
L 2.34723327 2.98493327 2.34361732 2.98416673 1 P 0 ;0,1=392,2=270.000000
L 2.34361732 2.98416673 2.34051713 2.98186654 1 P 0 ;0,1=392,2=270.000000
L 2.34051713 2.98186654 2.33896644 2.97841654 1 P 0 ;0,1=392,2=270.000000
L 2.33896644 2.97841654 2.33896644 2.97458337 1 P 0 ;0,1=392,2=270.000000
L 2.33896644 2.97458337 2.33793337 2.97228317 1 P 0 ;0,1=392,2=270.000000
L 2.33793337 2.97228317 2.33535059 2.97036614 1 P 0 ;0,1=392,2=270.000000
L 2.33535059 2.97036614 2.33173376 2.9695997 1 P 0 ;0,1=392,2=270.000000
L 2.33173376 2.9695997 2.32811693 2.9707501 1 P 0 ;0,1=392,2=270.000000
L 2.32811693 2.9707501 2.32553317 2.97343287 1 P 0 ;0,1=392,2=270.000000
L 2.32553317 2.97343287 2.3245 2.97649961 1 P 0 ;0,1=392,2=270.000000
L 2.3245 2.97649961 2.32553317 2.97956634 1 P 0 ;0,1=392,2=270.000000
L 2.32553317 2.97956634 2.32811693 2.9822498 1 P 0 ;0,1=392,2=270.000000
L 2.32811693 2.9822498 2.33173376 2.9834002 1 P 0 ;0,1=392,2=270.000000
L 2.33173376 2.9834002 2.33535059 2.98263307 1 P 0 ;0,1=392,2=270.000000
L 2.33535059 2.98263307 2.33793337 2.98071673 1 P 0 ;0,1=392,2=270.000000
L 2.33793337 2.98071673 2.33896644 2.97841654 1 P 0 ;0,1=392,2=270.000000
L 2.33896644 2.97841654 2.33896644 2.97458337 1 P 0 ;0,1=392,2=270.000000
L 2.33896644 2.97458337 2.34051713 2.97113337 1 P 0 ;0,1=392,2=270.000000
L 2.34051713 2.97113337 2.34361732 2.96883317 1 P 0 ;0,1=392,2=270.000000
L 2.34361732 2.96883317 2.34723327 2.96806663 1 P 0 ;0,1=392,2=270.000000
L 2.34723327 2.96806663 2.35085108 2.96883317 1 P 0 ;0,1=392,2=270.000000
L 2.35085108 2.96883317 2.35343386 2.9707501 1 P 0 ;0,1=392,2=270.000000
L 2.35343386 2.9707501 2.35498346 2.97381683 1 P 0 ;0,1=392,2=270.000000
L 2.35498346 2.97381683 2.3555 2.97649961 1 P 0 ;0,1=392,2=270.000000
L 1.578 4.096 1.578 4.186 1 P 0 
L 1.578 4.186 1.534 4.186 1 P 0 
L 1.534 4.186 1.534 4.096 1 P 0 
L 1.534 4.096 1.578 4.096 1 P 0 
L 1.45633317 4.1895 1.45633317 4.2205 1 P 0 ;0,1=393,2=0.000000
L 1.45633317 4.2205 1.46591654 4.2205 1 P 0 ;0,1=393,2=0.000000
L 1.46591654 4.2205 1.46898327 4.21894931 1 P 0 ;0,1=393,2=0.000000
L 1.46898327 4.21894931 1.4709002 4.21688307 1 P 0 ;0,1=393,2=0.000000
L 1.4709002 4.21688307 1.47166673 4.2127497 1 P 0 ;0,1=393,2=0.000000
L 1.47166673 4.2127497 1.4709002 4.20861634 1 P 0 ;0,1=393,2=0.000000
L 1.4709002 4.20861634 1.4686 4.20603356 1 P 0 ;0,1=393,2=0.000000
L 1.4686 4.20603356 1.46591654 4.20448287 1 P 0 ;0,1=393,2=0.000000
L 1.46591654 4.20448287 1.45633317 4.20448287 1 P 0 ;0,1=393,2=0.000000
L 1.46591654 4.20448287 1.47166673 4.1895 1 P 0 ;0,1=393,2=0.000000
L 1.48771644 4.21533346 1.49001663 4.21843278 1 P 0 ;0,1=393,2=0.000000
L 1.49001663 4.21843278 1.4927001 4.21998337 1 P 0 ;0,1=393,2=0.000000
L 1.4927001 4.21998337 1.49576683 4.2205 1 P 0 ;0,1=393,2=0.000000
L 1.49576683 4.2205 1.4996 4.21946683 1 P 0 ;0,1=393,2=0.000000
L 1.4996 4.21946683 1.50228346 4.21688307 1 P 0 ;0,1=393,2=0.000000
L 1.50228346 4.21688307 1.50305 4.21378376 1 P 0 ;0,1=393,2=0.000000
L 1.50305 4.21378376 1.50266673 4.21068258 1 P 0 ;0,1=393,2=0.000000
L 1.50266673 4.21068258 1.50113307 4.2080998 1 P 0 ;0,1=393,2=0.000000
L 1.50113307 4.2080998 1.49346663 4.20293327 1 P 0 ;0,1=393,2=0.000000
L 1.49346663 4.20293327 1.49001663 4.19931644 1 P 0 ;0,1=393,2=0.000000
L 1.49001663 4.19931644 1.48771644 4.19414892 1 P 0 ;0,1=393,2=0.000000
L 1.48771644 4.19414892 1.4869499 4.1895 1 P 0 ;0,1=393,2=0.000000
L 1.4869499 4.1895 1.50305 4.1895 1 P 0 ;0,1=393,2=0.000000
L 1.51948287 4.19311585 1.52216634 4.19053307 1 P 0 ;0,1=393,2=0.000000
L 1.52216634 4.19053307 1.52523307 4.1895 1 P 0 ;0,1=393,2=0.000000
L 1.52523307 4.1895 1.5282998 4.19053307 1 P 0 ;0,1=393,2=0.000000
L 1.5282998 4.19053307 1.53098327 4.19363238 1 P 0 ;0,1=393,2=0.000000
L 1.53098327 4.19363238 1.5329002 4.19828327 1 P 0 ;0,1=393,2=0.000000
L 1.5329002 4.19828327 1.53366673 4.20293327 1 P 0 ;0,1=393,2=0.000000
L 1.53366673 4.20293327 1.53366673 4.20861634 1 P 0 ;0,1=393,2=0.000000
L 1.53366673 4.20861634 1.5329002 4.21326624 1 P 0 ;0,1=393,2=0.000000
L 1.5329002 4.21326624 1.53098327 4.2173997 1 P 0 ;0,1=393,2=0.000000
L 1.53098327 4.2173997 1.52868307 4.21946683 1 P 0 ;0,1=393,2=0.000000
L 1.52868307 4.21946683 1.52599961 4.2205 1 P 0 ;0,1=393,2=0.000000
L 1.52599961 4.2205 1.52293287 4.21946683 1 P 0 ;0,1=393,2=0.000000
L 1.52293287 4.21946683 1.52063337 4.2173997 1 P 0 ;0,1=393,2=0.000000
L 1.52063337 4.2173997 1.5190997 4.2143003 1 P 0 ;0,1=393,2=0.000000
L 1.5190997 4.2143003 1.51833317 4.21016594 1 P 0 ;0,1=393,2=0.000000
L 1.51833317 4.21016594 1.5190997 4.2065501 1 P 0 ;0,1=393,2=0.000000
L 1.5190997 4.2065501 1.52101663 4.20293327 1 P 0 ;0,1=393,2=0.000000
L 1.52101663 4.20293327 1.52331683 4.20086604 1 P 0 ;0,1=393,2=0.000000
L 1.52331683 4.20086604 1.52599961 4.20034951 1 P 0 ;0,1=393,2=0.000000
L 1.52599961 4.20034951 1.52906634 4.20138268 1 P 0 ;0,1=393,2=0.000000
L 1.52906634 4.20138268 1.53136654 4.20396634 1 P 0 ;0,1=393,2=0.000000
L 1.53136654 4.20396634 1.53366673 4.20861634 1 P 0 ;0,1=393,2=0.000000
L 2.2848 3.221 2.2848 3.311 1 P 0 
L 2.2848 3.311 2.2408 3.311 1 P 0 
L 2.2408 3.311 2.2408 3.221 1 P 0 
L 2.2408 3.221 2.2848 3.221 1 P 0 
L 2.3205 3.22083317 2.2895 3.22083317 1 P 0 ;0,1=394,2=270.000000
L 2.2895 3.22083317 2.2895 3.23041654 1 P 0 ;0,1=394,2=270.000000
L 2.2895 3.23041654 2.29105069 3.23348327 1 P 0 ;0,1=394,2=270.000000
L 2.29105069 3.23348327 2.29311693 3.2354002 1 P 0 ;0,1=394,2=270.000000
L 2.29311693 3.2354002 2.2972503 3.23616673 1 P 0 ;0,1=394,2=270.000000
L 2.2972503 3.23616673 2.30138366 3.2354002 1 P 0 ;0,1=394,2=270.000000
L 2.30138366 3.2354002 2.30396644 3.2331 1 P 0 ;0,1=394,2=270.000000
L 2.30396644 3.2331 2.30551713 3.23041654 1 P 0 ;0,1=394,2=270.000000
L 2.30551713 3.23041654 2.30551713 3.22083317 1 P 0 ;0,1=394,2=270.000000
L 2.30551713 3.23041654 2.3205 3.23616673 1 P 0 ;0,1=394,2=270.000000
L 2.3205 3.2641 2.2895 3.2641 1 P 0 ;0,1=394,2=270.000000
L 2.2895 3.2641 2.31171673 3.24991624 1 P 0 ;0,1=394,2=270.000000
L 2.31171673 3.24991624 2.31171673 3.26908366 1 P 0 ;0,1=394,2=270.000000
L 2.2895 3.29049961 2.29053317 3.28743287 1 P 0 ;0,1=394,2=270.000000
L 2.29053317 3.28743287 2.29311693 3.28513337 1 P 0 ;0,1=394,2=270.000000
L 2.29311693 3.28513337 2.29621624 3.2835997 1 P 0 ;0,1=394,2=270.000000
L 2.29621624 3.2835997 2.30035059 3.2824499 1 P 0 ;0,1=394,2=270.000000
L 2.30035059 3.2824499 2.30500049 3.28206663 1 P 0 ;0,1=394,2=270.000000
L 2.30500049 3.28206663 2.30965049 3.2824499 1 P 0 ;0,1=394,2=270.000000
L 2.30965049 3.2824499 2.31378386 3.2835997 1 P 0 ;0,1=394,2=270.000000
L 2.31378386 3.2835997 2.31688415 3.28513337 1 P 0 ;0,1=394,2=270.000000
L 2.31688415 3.28513337 2.31946693 3.28743287 1 P 0 ;0,1=394,2=270.000000
L 2.31946693 3.28743287 2.3205 3.29049961 1 P 0 ;0,1=394,2=270.000000
L 2.3205 3.29049961 2.31946693 3.29356634 1 P 0 ;0,1=394,2=270.000000
L 2.31946693 3.29356634 2.31688415 3.29586654 1 P 0 ;0,1=394,2=270.000000
L 2.31688415 3.29586654 2.31378386 3.2974002 1 P 0 ;0,1=394,2=270.000000
L 2.31378386 3.2974002 2.30965049 3.29855 1 P 0 ;0,1=394,2=270.000000
L 2.30965049 3.29855 2.30500049 3.29893327 1 P 0 ;0,1=394,2=270.000000
L 2.30500049 3.29893327 2.30035059 3.29855 1 P 0 ;0,1=394,2=270.000000
L 2.30035059 3.29855 2.29621624 3.2974002 1 P 0 ;0,1=394,2=270.000000
L 2.29621624 3.2974002 2.29311693 3.29586654 1 P 0 ;0,1=394,2=270.000000
L 2.29311693 3.29586654 2.29053317 3.29356634 1 P 0 ;0,1=394,2=270.000000
L 2.29053317 3.29356634 2.2895 3.29049961 1 P 0 ;0,1=394,2=270.000000
L 2.30758425 3.31421644 2.30396644 3.3168999 1 P 0 ;0,1=394,2=270.000000
L 2.30396644 3.3168999 2.3019002 3.3192001 1 P 0 ;0,1=394,2=270.000000
L 2.3019002 3.3192001 2.30086713 3.32226683 1 P 0 ;0,1=394,2=270.000000
L 2.30086713 3.32226683 2.3019002 3.3249503 1 P 0 ;0,1=394,2=270.000000
L 2.3019002 3.3249503 2.30396644 3.32686654 1 P 0 ;0,1=394,2=270.000000
L 2.30396644 3.32686654 2.30706673 3.3284002 1 P 0 ;0,1=394,2=270.000000
L 2.30706673 3.3284002 2.31068356 3.32878346 1 P 0 ;0,1=394,2=270.000000
L 2.31068356 3.32878346 2.31378386 3.3284002 1 P 0 ;0,1=394,2=270.000000
L 2.31378386 3.3284002 2.31688415 3.32686654 1 P 0 ;0,1=394,2=270.000000
L 2.31688415 3.32686654 2.31946693 3.32456634 1 P 0 ;0,1=394,2=270.000000
L 2.31946693 3.32456634 2.3205 3.32188356 1 P 0 ;0,1=394,2=270.000000
L 2.3205 3.32188356 2.31946693 3.31881683 1 P 0 ;0,1=394,2=270.000000
L 2.31946693 3.31881683 2.31636762 3.31613337 1 P 0 ;0,1=394,2=270.000000
L 2.31636762 3.31613337 2.31171673 3.3145997 1 P 0 ;0,1=394,2=270.000000
L 2.31171673 3.3145997 2.3065502 3.31421644 1 P 0 ;0,1=394,2=270.000000
L 2.3065502 3.31421644 2.29983406 3.31498287 1 P 0 ;0,1=394,2=270.000000
L 2.29983406 3.31498287 2.29621624 3.31613337 1 P 0 ;0,1=394,2=270.000000
L 2.29621624 3.31613337 2.2926003 3.31804961 1 P 0 ;0,1=394,2=270.000000
L 2.2926003 3.31804961 2.29001663 3.32073307 1 P 0 ;0,1=394,2=270.000000
L 2.29001663 3.32073307 2.2895 3.32341654 1 P 0 ;0,1=394,2=270.000000
L 2.2895 3.32341654 2.29053317 3.3261 1 P 0 ;0,1=394,2=270.000000
L 2.29053317 3.3261 2.29311693 3.32801703 1 P 0 ;0,1=394,2=270.000000
L 1.937 3.313 1.937 3.223 1 P 0 
L 1.937 3.223 1.981 3.223 1 P 0 
L 1.981 3.223 1.981 3.313 1 P 0 
L 1.981 3.313 1.937 3.313 1 P 0 
L 1.9805 3.34583317 1.9495 3.34583317 1 P 0 ;0,1=395,2=270.000000
L 1.9495 3.34583317 1.9495 3.35541654 1 P 0 ;0,1=395,2=270.000000
L 1.9495 3.35541654 1.95105069 3.35848327 1 P 0 ;0,1=395,2=270.000000
L 1.95105069 3.35848327 1.95311693 3.3604002 1 P 0 ;0,1=395,2=270.000000
L 1.95311693 3.3604002 1.9572503 3.36116673 1 P 0 ;0,1=395,2=270.000000
L 1.9572503 3.36116673 1.96138366 3.3604002 1 P 0 ;0,1=395,2=270.000000
L 1.96138366 3.3604002 1.96396644 3.3581 1 P 0 ;0,1=395,2=270.000000
L 1.96396644 3.3581 1.96551713 3.35541654 1 P 0 ;0,1=395,2=270.000000
L 1.96551713 3.35541654 1.96551713 3.34583317 1 P 0 ;0,1=395,2=270.000000
L 1.96551713 3.35541654 1.9805 3.36116673 1 P 0 ;0,1=395,2=270.000000
L 1.9805 3.3891 1.9495 3.3891 1 P 0 ;0,1=395,2=270.000000
L 1.9495 3.3891 1.97171673 3.37491624 1 P 0 ;0,1=395,2=270.000000
L 1.97171673 3.37491624 1.97171673 3.39408366 1 P 0 ;0,1=395,2=270.000000
L 1.95466654 3.40821644 1.95156722 3.41051663 1 P 0 ;0,1=395,2=270.000000
L 1.95156722 3.41051663 1.95001663 3.4132001 1 P 0 ;0,1=395,2=270.000000
L 1.95001663 3.4132001 1.9495 3.41626683 1 P 0 ;0,1=395,2=270.000000
L 1.9495 3.41626683 1.95053317 3.4201 1 P 0 ;0,1=395,2=270.000000
L 1.95053317 3.4201 1.95311693 3.42278346 1 P 0 ;0,1=395,2=270.000000
L 1.95311693 3.42278346 1.95621624 3.42355 1 P 0 ;0,1=395,2=270.000000
L 1.95621624 3.42355 1.95931742 3.42316673 1 P 0 ;0,1=395,2=270.000000
L 1.95931742 3.42316673 1.9619002 3.42163307 1 P 0 ;0,1=395,2=270.000000
L 1.9619002 3.42163307 1.96706673 3.41396663 1 P 0 ;0,1=395,2=270.000000
L 1.96706673 3.41396663 1.97068356 3.41051663 1 P 0 ;0,1=395,2=270.000000
L 1.97068356 3.41051663 1.97585108 3.40821644 1 P 0 ;0,1=395,2=270.000000
L 1.97585108 3.40821644 1.9805 3.4074499 1 P 0 ;0,1=395,2=270.000000
L 1.9805 3.4074499 1.9805 3.42355 1 P 0 ;0,1=395,2=270.000000
L 1.95466654 3.43921644 1.95156722 3.44151663 1 P 0 ;0,1=395,2=270.000000
L 1.95156722 3.44151663 1.95001663 3.4442001 1 P 0 ;0,1=395,2=270.000000
L 1.95001663 3.4442001 1.9495 3.44726683 1 P 0 ;0,1=395,2=270.000000
L 1.9495 3.44726683 1.95053317 3.4511 1 P 0 ;0,1=395,2=270.000000
L 1.95053317 3.4511 1.95311693 3.45378346 1 P 0 ;0,1=395,2=270.000000
L 1.95311693 3.45378346 1.95621624 3.45455 1 P 0 ;0,1=395,2=270.000000
L 1.95621624 3.45455 1.95931742 3.45416673 1 P 0 ;0,1=395,2=270.000000
L 1.95931742 3.45416673 1.9619002 3.45263307 1 P 0 ;0,1=395,2=270.000000
L 1.9619002 3.45263307 1.96706673 3.44496663 1 P 0 ;0,1=395,2=270.000000
L 1.96706673 3.44496663 1.97068356 3.44151663 1 P 0 ;0,1=395,2=270.000000
L 1.97068356 3.44151663 1.97585108 3.43921644 1 P 0 ;0,1=395,2=270.000000
L 1.97585108 3.43921644 1.9805 3.4384499 1 P 0 ;0,1=395,2=270.000000
L 1.9805 3.4384499 1.9805 3.45455 1 P 0 ;0,1=395,2=270.000000
L 1.407 4.06 1.407 4.15 1 P 0 
L 1.407 4.15 1.363 4.15 1 P 0 
L 1.363 4.15 1.363 4.06 1 P 0 
L 1.363 4.06 1.407 4.06 1 P 0 
L 1.2405 4.13683317 1.2095 4.13683317 1 P 0 ;0,1=396,2=270.000000
L 1.2095 4.13683317 1.2095 4.14641654 1 P 0 ;0,1=396,2=270.000000
L 1.2095 4.14641654 1.21105069 4.14948327 1 P 0 ;0,1=396,2=270.000000
L 1.21105069 4.14948327 1.21311693 4.1514002 1 P 0 ;0,1=396,2=270.000000
L 1.21311693 4.1514002 1.2172503 4.15216673 1 P 0 ;0,1=396,2=270.000000
L 1.2172503 4.15216673 1.22138366 4.1514002 1 P 0 ;0,1=396,2=270.000000
L 1.22138366 4.1514002 1.22396644 4.1491 1 P 0 ;0,1=396,2=270.000000
L 1.22396644 4.1491 1.22551713 4.14641654 1 P 0 ;0,1=396,2=270.000000
L 1.22551713 4.14641654 1.22551713 4.13683317 1 P 0 ;0,1=396,2=270.000000
L 1.22551713 4.14641654 1.2405 4.15216673 1 P 0 ;0,1=396,2=270.000000
L 1.22758425 4.16821644 1.22396644 4.1708999 1 P 0 ;0,1=396,2=270.000000
L 1.22396644 4.1708999 1.2219002 4.1732001 1 P 0 ;0,1=396,2=270.000000
L 1.2219002 4.1732001 1.22086713 4.17626683 1 P 0 ;0,1=396,2=270.000000
L 1.22086713 4.17626683 1.2219002 4.1789503 1 P 0 ;0,1=396,2=270.000000
L 1.2219002 4.1789503 1.22396644 4.18086654 1 P 0 ;0,1=396,2=270.000000
L 1.22396644 4.18086654 1.22706673 4.1824002 1 P 0 ;0,1=396,2=270.000000
L 1.22706673 4.1824002 1.23068356 4.18278346 1 P 0 ;0,1=396,2=270.000000
L 1.23068356 4.18278346 1.23378386 4.1824002 1 P 0 ;0,1=396,2=270.000000
L 1.23378386 4.1824002 1.23688415 4.18086654 1 P 0 ;0,1=396,2=270.000000
L 1.23688415 4.18086654 1.23946693 4.17856634 1 P 0 ;0,1=396,2=270.000000
L 1.23946693 4.17856634 1.2405 4.17588356 1 P 0 ;0,1=396,2=270.000000
L 1.2405 4.17588356 1.23946693 4.17281683 1 P 0 ;0,1=396,2=270.000000
L 1.23946693 4.17281683 1.23636762 4.17013337 1 P 0 ;0,1=396,2=270.000000
L 1.23636762 4.17013337 1.23171673 4.1685997 1 P 0 ;0,1=396,2=270.000000
L 1.23171673 4.1685997 1.2265502 4.16821644 1 P 0 ;0,1=396,2=270.000000
L 1.2265502 4.16821644 1.21983406 4.16898287 1 P 0 ;0,1=396,2=270.000000
L 1.21983406 4.16898287 1.21621624 4.17013337 1 P 0 ;0,1=396,2=270.000000
L 1.21621624 4.17013337 1.2126003 4.17204961 1 P 0 ;0,1=396,2=270.000000
L 1.2126003 4.17204961 1.21001663 4.17473307 1 P 0 ;0,1=396,2=270.000000
L 1.21001663 4.17473307 1.2095 4.17741654 1 P 0 ;0,1=396,2=270.000000
L 1.2095 4.17741654 1.21053317 4.1801 1 P 0 ;0,1=396,2=270.000000
L 1.21053317 4.1801 1.21311693 4.18201703 1 P 0 ;0,1=396,2=270.000000
L 1.491 3.873 1.401 3.873 1 P 0 
L 1.401 3.873 1.401 3.829 1 P 0 
L 1.401 3.829 1.491 3.829 1 P 0 
L 1.491 3.829 1.491 3.873 1 P 0 
L 1.48773317 3.6033 1.48773317 3.6343 1 P 0 ;0,1=397,2=0.000000
L 1.48773317 3.6343 1.49731654 3.6343 1 P 0 ;0,1=397,2=0.000000
L 1.49731654 3.6343 1.50038327 3.63274931 1 P 0 ;0,1=397,2=0.000000
L 1.50038327 3.63274931 1.5023002 3.63068307 1 P 0 ;0,1=397,2=0.000000
L 1.5023002 3.63068307 1.50306673 3.6265497 1 P 0 ;0,1=397,2=0.000000
L 1.50306673 3.6265497 1.5023002 3.62241634 1 P 0 ;0,1=397,2=0.000000
L 1.5023002 3.62241634 1.5 3.61983356 1 P 0 ;0,1=397,2=0.000000
L 1.5 3.61983356 1.49731654 3.61828287 1 P 0 ;0,1=397,2=0.000000
L 1.49731654 3.61828287 1.48773317 3.61828287 1 P 0 ;0,1=397,2=0.000000
L 1.49731654 3.61828287 1.50306673 3.6033 1 P 0 ;0,1=397,2=0.000000
L 1.51911644 3.62913346 1.52141663 3.63223278 1 P 0 ;0,1=397,2=0.000000
L 1.52141663 3.63223278 1.5241001 3.63378337 1 P 0 ;0,1=397,2=0.000000
L 1.5241001 3.63378337 1.52716683 3.6343 1 P 0 ;0,1=397,2=0.000000
L 1.52716683 3.6343 1.531 3.63326683 1 P 0 ;0,1=397,2=0.000000
L 1.531 3.63326683 1.53368346 3.63068307 1 P 0 ;0,1=397,2=0.000000
L 1.53368346 3.63068307 1.53445 3.62758376 1 P 0 ;0,1=397,2=0.000000
L 1.53445 3.62758376 1.53406673 3.62448258 1 P 0 ;0,1=397,2=0.000000
L 1.53406673 3.62448258 1.53253307 3.6218998 1 P 0 ;0,1=397,2=0.000000
L 1.53253307 3.6218998 1.52486663 3.61673327 1 P 0 ;0,1=397,2=0.000000
L 1.52486663 3.61673327 1.52141663 3.61311644 1 P 0 ;0,1=397,2=0.000000
L 1.52141663 3.61311644 1.51911644 3.60794892 1 P 0 ;0,1=397,2=0.000000
L 1.51911644 3.60794892 1.5183499 3.6033 1 P 0 ;0,1=397,2=0.000000
L 1.5183499 3.6033 1.53445 3.6033 1 P 0 ;0,1=397,2=0.000000
L 1.55088287 3.60691585 1.55356634 3.60433307 1 P 0 ;0,1=397,2=0.000000
L 1.55356634 3.60433307 1.55663307 3.6033 1 P 0 ;0,1=397,2=0.000000
L 1.55663307 3.6033 1.5596998 3.60433307 1 P 0 ;0,1=397,2=0.000000
L 1.5596998 3.60433307 1.56238327 3.60743238 1 P 0 ;0,1=397,2=0.000000
L 1.56238327 3.60743238 1.5643002 3.61208327 1 P 0 ;0,1=397,2=0.000000
L 1.5643002 3.61208327 1.56506673 3.61673327 1 P 0 ;0,1=397,2=0.000000
L 1.56506673 3.61673327 1.56506673 3.62241634 1 P 0 ;0,1=397,2=0.000000
L 1.56506673 3.62241634 1.5643002 3.62706624 1 P 0 ;0,1=397,2=0.000000
L 1.5643002 3.62706624 1.56238327 3.6311997 1 P 0 ;0,1=397,2=0.000000
L 1.56238327 3.6311997 1.56008307 3.63326683 1 P 0 ;0,1=397,2=0.000000
L 1.56008307 3.63326683 1.55739961 3.6343 1 P 0 ;0,1=397,2=0.000000
L 1.55739961 3.6343 1.55433287 3.63326683 1 P 0 ;0,1=397,2=0.000000
L 1.55433287 3.63326683 1.55203337 3.6311997 1 P 0 ;0,1=397,2=0.000000
L 1.55203337 3.6311997 1.5504997 3.6281003 1 P 0 ;0,1=397,2=0.000000
L 1.5504997 3.6281003 1.54973317 3.62396594 1 P 0 ;0,1=397,2=0.000000
L 1.54973317 3.62396594 1.5504997 3.6203501 1 P 0 ;0,1=397,2=0.000000
L 1.5504997 3.6203501 1.55241663 3.61673327 1 P 0 ;0,1=397,2=0.000000
L 1.55241663 3.61673327 1.55471683 3.61466604 1 P 0 ;0,1=397,2=0.000000
L 1.55471683 3.61466604 1.55739961 3.61414951 1 P 0 ;0,1=397,2=0.000000
L 1.55739961 3.61414951 1.56046634 3.61518268 1 P 0 ;0,1=397,2=0.000000
L 1.56046634 3.61518268 1.56276654 3.61776634 1 P 0 ;0,1=397,2=0.000000
L 1.56276654 3.61776634 1.56506673 3.62241634 1 P 0 ;0,1=397,2=0.000000
L 1.593 3.6033 1.593 3.6343 1 P 0 ;0,1=397,2=0.000000
L 1.593 3.6343 1.57881624 3.61208327 1 P 0 ;0,1=397,2=0.000000
L 1.57881624 3.61208327 1.59798366 3.61208327 1 P 0 ;0,1=397,2=0.000000
L 5.786 3.495 5.786 3.539 1 P 0 
L 5.696 3.495 5.786 3.495 1 P 0 
L 5.786 3.539 5.696 3.539 1 P 0 
L 5.696 3.539 5.696 3.495 1 P 0 
L 5.70683317 3.1895 5.70683317 3.2205 1 P 0 ;0,1=398,2=0.000000
L 5.70683317 3.2205 5.71641654 3.2205 1 P 0 ;0,1=398,2=0.000000
L 5.71641654 3.2205 5.71948327 3.21894931 1 P 0 ;0,1=398,2=0.000000
L 5.71948327 3.21894931 5.7214002 3.21688307 1 P 0 ;0,1=398,2=0.000000
L 5.7214002 3.21688307 5.72216673 3.2127497 1 P 0 ;0,1=398,2=0.000000
L 5.72216673 3.2127497 5.7214002 3.20861634 1 P 0 ;0,1=398,2=0.000000
L 5.7214002 3.20861634 5.7191 3.20603356 1 P 0 ;0,1=398,2=0.000000
L 5.7191 3.20603356 5.71641654 3.20448287 1 P 0 ;0,1=398,2=0.000000
L 5.71641654 3.20448287 5.70683317 3.20448287 1 P 0 ;0,1=398,2=0.000000
L 5.71641654 3.20448287 5.72216673 3.1895 1 P 0 ;0,1=398,2=0.000000
L 5.73706663 3.19414892 5.73936614 3.19156614 1 P 0 ;0,1=398,2=0.000000
L 5.73936614 3.19156614 5.74204961 3.19001654 1 P 0 ;0,1=398,2=0.000000
L 5.74204961 3.19001654 5.74549961 3.1895 1 P 0 ;0,1=398,2=0.000000
L 5.74549961 3.1895 5.7489503 3.19053307 1 P 0 ;0,1=398,2=0.000000
L 5.7489503 3.19053307 5.75163307 3.19259931 1 P 0 ;0,1=398,2=0.000000
L 5.75163307 3.19259931 5.75355 3.19621614 1 P 0 ;0,1=398,2=0.000000
L 5.75355 3.19621614 5.75393327 3.20034951 1 P 0 ;0,1=398,2=0.000000
L 5.75393327 3.20034951 5.75316673 3.20448287 1 P 0 ;0,1=398,2=0.000000
L 5.75316673 3.20448287 5.7512498 3.20706663 1 P 0 ;0,1=398,2=0.000000
L 5.7512498 3.20706663 5.74856634 3.20913287 1 P 0 ;0,1=398,2=0.000000
L 5.74856634 3.20913287 5.74588356 3.20964941 1 P 0 ;0,1=398,2=0.000000
L 5.74588356 3.20964941 5.7432001 3.20913287 1 P 0 ;0,1=398,2=0.000000
L 5.7432001 3.20913287 5.7397501 3.20706663 1 P 0 ;0,1=398,2=0.000000
L 5.7397501 3.20706663 5.7408999 3.2205 1 P 0 ;0,1=398,2=0.000000
L 5.7408999 3.2205 5.7512498 3.2205 1 P 0 ;0,1=398,2=0.000000
L 3.135 2.412 3.225 2.412 1 P 0 
L 3.225 2.412 3.225 2.456 1 P 0 
L 3.225 2.456 3.135 2.456 1 P 0 
L 3.135 2.456 3.135 2.412 1 P 0 
L 2.72083317 3.1885 2.72083317 3.2195 1 P 0 ;0,1=399,2=0.000000
L 2.72083317 3.2195 2.73041654 3.2195 1 P 0 ;0,1=399,2=0.000000
L 2.73041654 3.2195 2.73348327 3.21794931 1 P 0 ;0,1=399,2=0.000000
L 2.73348327 3.21794931 2.7354002 3.21588307 1 P 0 ;0,1=399,2=0.000000
L 2.7354002 3.21588307 2.73616673 3.2117497 1 P 0 ;0,1=399,2=0.000000
L 2.73616673 3.2117497 2.7354002 3.20761634 1 P 0 ;0,1=399,2=0.000000
L 2.7354002 3.20761634 2.7331 3.20503356 1 P 0 ;0,1=399,2=0.000000
L 2.7331 3.20503356 2.73041654 3.20348287 1 P 0 ;0,1=399,2=0.000000
L 2.73041654 3.20348287 2.72083317 3.20348287 1 P 0 ;0,1=399,2=0.000000
L 2.73041654 3.20348287 2.73616673 3.1885 1 P 0 ;0,1=399,2=0.000000
L 2.75106663 3.19469961 2.75336614 3.19108278 1 P 0 ;0,1=399,2=0.000000
L 2.75336614 3.19108278 2.75643287 3.18901654 1 P 0 ;0,1=399,2=0.000000
L 2.75643287 3.18901654 2.75988356 3.1885 1 P 0 ;0,1=399,2=0.000000
L 2.75988356 3.1885 2.7629503 3.18901654 1 P 0 ;0,1=399,2=0.000000
L 2.7629503 3.18901654 2.76601703 3.19159931 1 P 0 ;0,1=399,2=0.000000
L 2.76601703 3.19159931 2.76793327 3.19469961 1 P 0 ;0,1=399,2=0.000000
L 2.76793327 3.19469961 2.76831654 3.1977999 1 P 0 ;0,1=399,2=0.000000
L 2.76831654 3.1977999 2.76755 3.20141575 1 P 0 ;0,1=399,2=0.000000
L 2.76755 3.20141575 2.76486654 3.20399951 1 P 0 ;0,1=399,2=0.000000
L 2.76486654 3.20399951 2.76218307 3.20503356 1 P 0 ;0,1=399,2=0.000000
L 2.76218307 3.20503356 2.75873307 3.20503356 1 P 0 ;0,1=399,2=0.000000
L 2.76218307 3.20503356 2.76448327 3.20658317 1 P 0 ;0,1=399,2=0.000000
L 2.76448327 3.20658317 2.7664002 3.20916594 1 P 0 ;0,1=399,2=0.000000
L 2.7664002 3.20916594 2.76716673 3.21226624 1 P 0 ;0,1=399,2=0.000000
L 2.76716673 3.21226624 2.7664002 3.21536654 1 P 0 ;0,1=399,2=0.000000
L 2.7664002 3.21536654 2.76448327 3.21794931 1 P 0 ;0,1=399,2=0.000000
L 2.76448327 3.21794931 2.76103327 3.2195 1 P 0 ;0,1=399,2=0.000000
L 2.76103327 3.2195 2.75758337 3.21898337 1 P 0 ;0,1=399,2=0.000000
L 2.75758337 3.21898337 2.75413337 3.21691624 1 P 0 ;0,1=399,2=0.000000
L 2.79049961 3.2195 2.78743287 3.21846683 1 P 0 ;0,1=399,2=0.000000
L 2.78743287 3.21846683 2.78513337 3.21588307 1 P 0 ;0,1=399,2=0.000000
L 2.78513337 3.21588307 2.7835997 3.21278376 1 P 0 ;0,1=399,2=0.000000
L 2.7835997 3.21278376 2.7824499 3.20864941 1 P 0 ;0,1=399,2=0.000000
L 2.7824499 3.20864941 2.78206663 3.20399951 1 P 0 ;0,1=399,2=0.000000
L 2.78206663 3.20399951 2.7824499 3.19934951 1 P 0 ;0,1=399,2=0.000000
L 2.7824499 3.19934951 2.7835997 3.19521614 1 P 0 ;0,1=399,2=0.000000
L 2.7835997 3.19521614 2.78513337 3.19211585 1 P 0 ;0,1=399,2=0.000000
L 2.78513337 3.19211585 2.78743287 3.18953307 1 P 0 ;0,1=399,2=0.000000
L 2.78743287 3.18953307 2.79049961 3.1885 1 P 0 ;0,1=399,2=0.000000
L 2.79049961 3.1885 2.79356634 3.18953307 1 P 0 ;0,1=399,2=0.000000
L 2.79356634 3.18953307 2.79586654 3.19211585 1 P 0 ;0,1=399,2=0.000000
L 2.79586654 3.19211585 2.7974002 3.19521614 1 P 0 ;0,1=399,2=0.000000
L 2.7974002 3.19521614 2.79855 3.19934951 1 P 0 ;0,1=399,2=0.000000
L 2.79855 3.19934951 2.79893327 3.20399951 1 P 0 ;0,1=399,2=0.000000
L 2.79893327 3.20399951 2.79855 3.20864941 1 P 0 ;0,1=399,2=0.000000
L 2.79855 3.20864941 2.7974002 3.21278376 1 P 0 ;0,1=399,2=0.000000
L 2.7974002 3.21278376 2.79586654 3.21588307 1 P 0 ;0,1=399,2=0.000000
L 2.79586654 3.21588307 2.79356634 3.21846683 1 P 0 ;0,1=399,2=0.000000
L 2.79356634 3.21846683 2.79049961 3.2195 1 P 0 ;0,1=399,2=0.000000
L 2.81421644 3.20141575 2.8168999 3.20503356 1 P 0 ;0,1=399,2=0.000000
L 2.8168999 3.20503356 2.8192001 3.2070998 1 P 0 ;0,1=399,2=0.000000
L 2.8192001 3.2070998 2.82226683 3.20813287 1 P 0 ;0,1=399,2=0.000000
L 2.82226683 3.20813287 2.8249503 3.2070998 1 P 0 ;0,1=399,2=0.000000
L 2.8249503 3.2070998 2.82686654 3.20503356 1 P 0 ;0,1=399,2=0.000000
L 2.82686654 3.20503356 2.8284002 3.20193327 1 P 0 ;0,1=399,2=0.000000
L 2.8284002 3.20193327 2.82878346 3.19831644 1 P 0 ;0,1=399,2=0.000000
L 2.82878346 3.19831644 2.8284002 3.19521614 1 P 0 ;0,1=399,2=0.000000
L 2.8284002 3.19521614 2.82686654 3.19211585 1 P 0 ;0,1=399,2=0.000000
L 2.82686654 3.19211585 2.82456634 3.18953307 1 P 0 ;0,1=399,2=0.000000
L 2.82456634 3.18953307 2.82188356 3.1885 1 P 0 ;0,1=399,2=0.000000
L 2.82188356 3.1885 2.81881683 3.18953307 1 P 0 ;0,1=399,2=0.000000
L 2.81881683 3.18953307 2.81613337 3.19263238 1 P 0 ;0,1=399,2=0.000000
L 2.81613337 3.19263238 2.8145997 3.19728327 1 P 0 ;0,1=399,2=0.000000
L 2.8145997 3.19728327 2.81421644 3.2024498 1 P 0 ;0,1=399,2=0.000000
L 2.81421644 3.2024498 2.81498287 3.20916594 1 P 0 ;0,1=399,2=0.000000
L 2.81498287 3.20916594 2.81613337 3.21278376 1 P 0 ;0,1=399,2=0.000000
L 2.81613337 3.21278376 2.81804961 3.2163997 1 P 0 ;0,1=399,2=0.000000
L 2.81804961 3.2163997 2.82073307 3.21898337 1 P 0 ;0,1=399,2=0.000000
L 2.82073307 3.21898337 2.82341654 3.2195 1 P 0 ;0,1=399,2=0.000000
L 2.82341654 3.2195 2.8261 3.21846683 1 P 0 ;0,1=399,2=0.000000
L 2.8261 3.21846683 2.82801703 3.21588307 1 P 0 ;0,1=399,2=0.000000
L 3.135 2.367 3.225 2.367 1 P 0 
L 3.225 2.367 3.225 2.411 1 P 0 
L 3.225 2.411 3.135 2.411 1 P 0 
L 3.135 2.411 3.135 2.367 1 P 0 
L 2.72083317 3.1435 2.72083317 3.1745 1 P 0 ;0,1=400,2=0.000000
L 2.72083317 3.1745 2.73041654 3.1745 1 P 0 ;0,1=400,2=0.000000
L 2.73041654 3.1745 2.73348327 3.17294931 1 P 0 ;0,1=400,2=0.000000
L 2.73348327 3.17294931 2.7354002 3.17088307 1 P 0 ;0,1=400,2=0.000000
L 2.7354002 3.17088307 2.73616673 3.1667497 1 P 0 ;0,1=400,2=0.000000
L 2.73616673 3.1667497 2.7354002 3.16261634 1 P 0 ;0,1=400,2=0.000000
L 2.7354002 3.16261634 2.7331 3.16003356 1 P 0 ;0,1=400,2=0.000000
L 2.7331 3.16003356 2.73041654 3.15848287 1 P 0 ;0,1=400,2=0.000000
L 2.73041654 3.15848287 2.72083317 3.15848287 1 P 0 ;0,1=400,2=0.000000
L 2.73041654 3.15848287 2.73616673 3.1435 1 P 0 ;0,1=400,2=0.000000
L 2.75221644 3.16933346 2.75451663 3.17243278 1 P 0 ;0,1=400,2=0.000000
L 2.75451663 3.17243278 2.7572001 3.17398337 1 P 0 ;0,1=400,2=0.000000
L 2.7572001 3.17398337 2.76026683 3.1745 1 P 0 ;0,1=400,2=0.000000
L 2.76026683 3.1745 2.7641 3.17346683 1 P 0 ;0,1=400,2=0.000000
L 2.7641 3.17346683 2.76678346 3.17088307 1 P 0 ;0,1=400,2=0.000000
L 2.76678346 3.17088307 2.76755 3.16778376 1 P 0 ;0,1=400,2=0.000000
L 2.76755 3.16778376 2.76716673 3.16468258 1 P 0 ;0,1=400,2=0.000000
L 2.76716673 3.16468258 2.76563307 3.1620998 1 P 0 ;0,1=400,2=0.000000
L 2.76563307 3.1620998 2.75796663 3.15693327 1 P 0 ;0,1=400,2=0.000000
L 2.75796663 3.15693327 2.75451663 3.15331644 1 P 0 ;0,1=400,2=0.000000
L 2.75451663 3.15331644 2.75221644 3.14814892 1 P 0 ;0,1=400,2=0.000000
L 2.75221644 3.14814892 2.7514499 3.1435 1 P 0 ;0,1=400,2=0.000000
L 2.7514499 3.1435 2.76755 3.1435 1 P 0 ;0,1=400,2=0.000000
L 2.78398287 3.14711585 2.78666634 3.14453307 1 P 0 ;0,1=400,2=0.000000
L 2.78666634 3.14453307 2.78973307 3.1435 1 P 0 ;0,1=400,2=0.000000
L 2.78973307 3.1435 2.7927998 3.14453307 1 P 0 ;0,1=400,2=0.000000
L 2.7927998 3.14453307 2.79548327 3.14763238 1 P 0 ;0,1=400,2=0.000000
L 2.79548327 3.14763238 2.7974002 3.15228327 1 P 0 ;0,1=400,2=0.000000
L 2.7974002 3.15228327 2.79816673 3.15693327 1 P 0 ;0,1=400,2=0.000000
L 2.79816673 3.15693327 2.79816673 3.16261634 1 P 0 ;0,1=400,2=0.000000
L 2.79816673 3.16261634 2.7974002 3.16726624 1 P 0 ;0,1=400,2=0.000000
L 2.7974002 3.16726624 2.79548327 3.1713997 1 P 0 ;0,1=400,2=0.000000
L 2.79548327 3.1713997 2.79318307 3.17346683 1 P 0 ;0,1=400,2=0.000000
L 2.79318307 3.17346683 2.79049961 3.1745 1 P 0 ;0,1=400,2=0.000000
L 2.79049961 3.1745 2.78743287 3.17346683 1 P 0 ;0,1=400,2=0.000000
L 2.78743287 3.17346683 2.78513337 3.1713997 1 P 0 ;0,1=400,2=0.000000
L 2.78513337 3.1713997 2.7835997 3.1683003 1 P 0 ;0,1=400,2=0.000000
L 2.7835997 3.1683003 2.78283317 3.16416594 1 P 0 ;0,1=400,2=0.000000
L 2.78283317 3.16416594 2.7835997 3.1605501 1 P 0 ;0,1=400,2=0.000000
L 2.7835997 3.1605501 2.78551663 3.15693327 1 P 0 ;0,1=400,2=0.000000
L 2.78551663 3.15693327 2.78781683 3.15486604 1 P 0 ;0,1=400,2=0.000000
L 2.78781683 3.15486604 2.79049961 3.15434951 1 P 0 ;0,1=400,2=0.000000
L 2.79049961 3.15434951 2.79356634 3.15538268 1 P 0 ;0,1=400,2=0.000000
L 2.79356634 3.15538268 2.79586654 3.15796634 1 P 0 ;0,1=400,2=0.000000
L 2.79586654 3.15796634 2.79816673 3.16261634 1 P 0 ;0,1=400,2=0.000000
L 2.82149961 3.1435 2.82149961 3.1745 1 P 0 ;0,1=400,2=0.000000
L 2.82149961 3.1745 2.8168999 3.1683003 1 P 0 ;0,1=400,2=0.000000
L 2.8168999 3.1435 2.82609931 3.1435 1 P 0 ;0,1=400,2=0.000000
L 3.135 2.232 3.225 2.232 1 P 0 
L 3.225 2.232 3.225 2.276 1 P 0 
L 3.225 2.276 3.135 2.276 1 P 0 
L 3.135 2.276 3.135 2.232 1 P 0 
L 2.72133317 3.0035 2.72133317 3.0345 1 P 0 ;0,1=401,2=0.000000
L 2.72133317 3.0345 2.73091654 3.0345 1 P 0 ;0,1=401,2=0.000000
L 2.73091654 3.0345 2.73398327 3.03294931 1 P 0 ;0,1=401,2=0.000000
L 2.73398327 3.03294931 2.7359002 3.03088307 1 P 0 ;0,1=401,2=0.000000
L 2.7359002 3.03088307 2.73666673 3.0267497 1 P 0 ;0,1=401,2=0.000000
L 2.73666673 3.0267497 2.7359002 3.02261634 1 P 0 ;0,1=401,2=0.000000
L 2.7359002 3.02261634 2.7336 3.02003356 1 P 0 ;0,1=401,2=0.000000
L 2.7336 3.02003356 2.73091654 3.01848287 1 P 0 ;0,1=401,2=0.000000
L 2.73091654 3.01848287 2.72133317 3.01848287 1 P 0 ;0,1=401,2=0.000000
L 2.73091654 3.01848287 2.73666673 3.0035 1 P 0 ;0,1=401,2=0.000000
L 2.75923307 3.0035 2.75999961 3.01021614 1 P 0 ;0,1=401,2=0.000000
L 2.75999961 3.01021614 2.7611501 3.01589921 1 P 0 ;0,1=401,2=0.000000
L 2.7611501 3.01589921 2.76268307 3.02106663 1 P 0 ;0,1=401,2=0.000000
L 2.76268307 3.02106663 2.7646 3.0267497 1 P 0 ;0,1=401,2=0.000000
L 2.7646 3.0267497 2.76766673 3.0345 1 P 0 ;0,1=401,2=0.000000
L 2.76766673 3.0345 2.75233317 3.0345 1 P 0 ;0,1=401,2=0.000000
L 2.78448287 3.00711585 2.78716634 3.00453307 1 P 0 ;0,1=401,2=0.000000
L 2.78716634 3.00453307 2.79023307 3.0035 1 P 0 ;0,1=401,2=0.000000
L 2.79023307 3.0035 2.7932998 3.00453307 1 P 0 ;0,1=401,2=0.000000
L 2.7932998 3.00453307 2.79598327 3.00763238 1 P 0 ;0,1=401,2=0.000000
L 2.79598327 3.00763238 2.7979002 3.01228327 1 P 0 ;0,1=401,2=0.000000
L 2.7979002 3.01228327 2.79866673 3.01693327 1 P 0 ;0,1=401,2=0.000000
L 2.79866673 3.01693327 2.79866673 3.02261634 1 P 0 ;0,1=401,2=0.000000
L 2.79866673 3.02261634 2.7979002 3.02726624 1 P 0 ;0,1=401,2=0.000000
L 2.7979002 3.02726624 2.79598327 3.0313997 1 P 0 ;0,1=401,2=0.000000
L 2.79598327 3.0313997 2.79368307 3.03346683 1 P 0 ;0,1=401,2=0.000000
L 2.79368307 3.03346683 2.79099961 3.0345 1 P 0 ;0,1=401,2=0.000000
L 2.79099961 3.0345 2.78793287 3.03346683 1 P 0 ;0,1=401,2=0.000000
L 2.78793287 3.03346683 2.78563337 3.0313997 1 P 0 ;0,1=401,2=0.000000
L 2.78563337 3.0313997 2.7840997 3.0283003 1 P 0 ;0,1=401,2=0.000000
L 2.7840997 3.0283003 2.78333317 3.02416594 1 P 0 ;0,1=401,2=0.000000
L 2.78333317 3.02416594 2.7840997 3.0205501 1 P 0 ;0,1=401,2=0.000000
L 2.7840997 3.0205501 2.78601663 3.01693327 1 P 0 ;0,1=401,2=0.000000
L 2.78601663 3.01693327 2.78831683 3.01486604 1 P 0 ;0,1=401,2=0.000000
L 2.78831683 3.01486604 2.79099961 3.01434951 1 P 0 ;0,1=401,2=0.000000
L 2.79099961 3.01434951 2.79406634 3.01538268 1 P 0 ;0,1=401,2=0.000000
L 2.79406634 3.01538268 2.79636654 3.01796634 1 P 0 ;0,1=401,2=0.000000
L 2.79636654 3.01796634 2.79866673 3.02261634 1 P 0 ;0,1=401,2=0.000000
L 3.225 2.321 3.135 2.321 1 P 0 
L 3.135 2.321 3.135 2.277 1 P 0 
L 3.135 2.277 3.225 2.277 1 P 0 
L 3.225 2.277 3.225 2.321 1 P 0 
L 2.72133317 3.0485 2.72133317 3.0795 1 P 0 ;0,1=402,2=0.000000
L 2.72133317 3.0795 2.73091654 3.0795 1 P 0 ;0,1=402,2=0.000000
L 2.73091654 3.0795 2.73398327 3.07794931 1 P 0 ;0,1=402,2=0.000000
L 2.73398327 3.07794931 2.7359002 3.07588307 1 P 0 ;0,1=402,2=0.000000
L 2.7359002 3.07588307 2.73666673 3.0717497 1 P 0 ;0,1=402,2=0.000000
L 2.73666673 3.0717497 2.7359002 3.06761634 1 P 0 ;0,1=402,2=0.000000
L 2.7359002 3.06761634 2.7336 3.06503356 1 P 0 ;0,1=402,2=0.000000
L 2.7336 3.06503356 2.73091654 3.06348287 1 P 0 ;0,1=402,2=0.000000
L 2.73091654 3.06348287 2.72133317 3.06348287 1 P 0 ;0,1=402,2=0.000000
L 2.73091654 3.06348287 2.73666673 3.0485 1 P 0 ;0,1=402,2=0.000000
L 2.75923307 3.0485 2.75999961 3.05521614 1 P 0 ;0,1=402,2=0.000000
L 2.75999961 3.05521614 2.7611501 3.06089921 1 P 0 ;0,1=402,2=0.000000
L 2.7611501 3.06089921 2.76268307 3.06606663 1 P 0 ;0,1=402,2=0.000000
L 2.76268307 3.06606663 2.7646 3.0717497 1 P 0 ;0,1=402,2=0.000000
L 2.7646 3.0717497 2.76766673 3.0795 1 P 0 ;0,1=402,2=0.000000
L 2.76766673 3.0795 2.75233317 3.0795 1 P 0 ;0,1=402,2=0.000000
L 2.79099961 3.0485 2.79368307 3.04901654 1 P 0 ;0,1=402,2=0.000000
L 2.79368307 3.04901654 2.7967498 3.05056614 1 P 0 ;0,1=402,2=0.000000
L 2.7967498 3.05056614 2.79866673 3.05314892 1 P 0 ;0,1=402,2=0.000000
L 2.79866673 3.05314892 2.79943327 3.05676673 1 P 0 ;0,1=402,2=0.000000
L 2.79943327 3.05676673 2.79866673 3.06038268 1 P 0 ;0,1=402,2=0.000000
L 2.79866673 3.06038268 2.79636654 3.06348287 1 P 0 ;0,1=402,2=0.000000
L 2.79636654 3.06348287 2.79291654 3.06503356 1 P 0 ;0,1=402,2=0.000000
L 2.79291654 3.06503356 2.78908337 3.06503356 1 P 0 ;0,1=402,2=0.000000
L 2.78908337 3.06503356 2.78678317 3.06606663 1 P 0 ;0,1=402,2=0.000000
L 2.78678317 3.06606663 2.78486614 3.06864941 1 P 0 ;0,1=402,2=0.000000
L 2.78486614 3.06864941 2.7840997 3.07226624 1 P 0 ;0,1=402,2=0.000000
L 2.7840997 3.07226624 2.7852501 3.07588307 1 P 0 ;0,1=402,2=0.000000
L 2.7852501 3.07588307 2.78793287 3.07846683 1 P 0 ;0,1=402,2=0.000000
L 2.78793287 3.07846683 2.79099961 3.0795 1 P 0 ;0,1=402,2=0.000000
L 2.79099961 3.0795 2.79406634 3.07846683 1 P 0 ;0,1=402,2=0.000000
L 2.79406634 3.07846683 2.7967498 3.07588307 1 P 0 ;0,1=402,2=0.000000
L 2.7967498 3.07588307 2.7979002 3.07226624 1 P 0 ;0,1=402,2=0.000000
L 2.7979002 3.07226624 2.79713307 3.06864941 1 P 0 ;0,1=402,2=0.000000
L 2.79713307 3.06864941 2.79521673 3.06606663 1 P 0 ;0,1=402,2=0.000000
L 2.79521673 3.06606663 2.79291654 3.06503356 1 P 0 ;0,1=402,2=0.000000
L 2.79291654 3.06503356 2.78908337 3.06503356 1 P 0 ;0,1=402,2=0.000000
L 2.78908337 3.06503356 2.78563337 3.06348287 1 P 0 ;0,1=402,2=0.000000
L 2.78563337 3.06348287 2.78333317 3.06038268 1 P 0 ;0,1=402,2=0.000000
L 2.78333317 3.06038268 2.78256663 3.05676673 1 P 0 ;0,1=402,2=0.000000
L 2.78256663 3.05676673 2.78333317 3.05314892 1 P 0 ;0,1=402,2=0.000000
L 2.78333317 3.05314892 2.7852501 3.05056614 1 P 0 ;0,1=402,2=0.000000
L 2.7852501 3.05056614 2.78831683 3.04901654 1 P 0 ;0,1=402,2=0.000000
L 2.78831683 3.04901654 2.79099961 3.0485 1 P 0 ;0,1=402,2=0.000000
L 3.225 2.366 3.135 2.366 1 P 0 
L 3.135 2.366 3.135 2.322 1 P 0 
L 3.135 2.322 3.225 2.322 1 P 0 
L 3.225 2.322 3.225 2.366 1 P 0 
L 2.72083317 3.0985 2.72083317 3.1295 1 P 0 ;0,1=403,2=0.000000
L 2.72083317 3.1295 2.73041654 3.1295 1 P 0 ;0,1=403,2=0.000000
L 2.73041654 3.1295 2.73348327 3.12794931 1 P 0 ;0,1=403,2=0.000000
L 2.73348327 3.12794931 2.7354002 3.12588307 1 P 0 ;0,1=403,2=0.000000
L 2.7354002 3.12588307 2.73616673 3.1217497 1 P 0 ;0,1=403,2=0.000000
L 2.73616673 3.1217497 2.7354002 3.11761634 1 P 0 ;0,1=403,2=0.000000
L 2.7354002 3.11761634 2.7331 3.11503356 1 P 0 ;0,1=403,2=0.000000
L 2.7331 3.11503356 2.73041654 3.11348287 1 P 0 ;0,1=403,2=0.000000
L 2.73041654 3.11348287 2.72083317 3.11348287 1 P 0 ;0,1=403,2=0.000000
L 2.73041654 3.11348287 2.73616673 3.0985 1 P 0 ;0,1=403,2=0.000000
L 2.75106663 3.10469961 2.75336614 3.10108278 1 P 0 ;0,1=403,2=0.000000
L 2.75336614 3.10108278 2.75643287 3.09901654 1 P 0 ;0,1=403,2=0.000000
L 2.75643287 3.09901654 2.75988356 3.0985 1 P 0 ;0,1=403,2=0.000000
L 2.75988356 3.0985 2.7629503 3.09901654 1 P 0 ;0,1=403,2=0.000000
L 2.7629503 3.09901654 2.76601703 3.10159931 1 P 0 ;0,1=403,2=0.000000
L 2.76601703 3.10159931 2.76793327 3.10469961 1 P 0 ;0,1=403,2=0.000000
L 2.76793327 3.10469961 2.76831654 3.1077999 1 P 0 ;0,1=403,2=0.000000
L 2.76831654 3.1077999 2.76755 3.11141575 1 P 0 ;0,1=403,2=0.000000
L 2.76755 3.11141575 2.76486654 3.11399951 1 P 0 ;0,1=403,2=0.000000
L 2.76486654 3.11399951 2.76218307 3.11503356 1 P 0 ;0,1=403,2=0.000000
L 2.76218307 3.11503356 2.75873307 3.11503356 1 P 0 ;0,1=403,2=0.000000
L 2.76218307 3.11503356 2.76448327 3.11658317 1 P 0 ;0,1=403,2=0.000000
L 2.76448327 3.11658317 2.7664002 3.11916594 1 P 0 ;0,1=403,2=0.000000
L 2.7664002 3.11916594 2.76716673 3.12226624 1 P 0 ;0,1=403,2=0.000000
L 2.76716673 3.12226624 2.7664002 3.12536654 1 P 0 ;0,1=403,2=0.000000
L 2.7664002 3.12536654 2.76448327 3.12794931 1 P 0 ;0,1=403,2=0.000000
L 2.76448327 3.12794931 2.76103327 3.1295 1 P 0 ;0,1=403,2=0.000000
L 2.76103327 3.1295 2.75758337 3.12898337 1 P 0 ;0,1=403,2=0.000000
L 2.75758337 3.12898337 2.75413337 3.12691624 1 P 0 ;0,1=403,2=0.000000
L 2.79049961 3.1295 2.78743287 3.12846683 1 P 0 ;0,1=403,2=0.000000
L 2.78743287 3.12846683 2.78513337 3.12588307 1 P 0 ;0,1=403,2=0.000000
L 2.78513337 3.12588307 2.7835997 3.12278376 1 P 0 ;0,1=403,2=0.000000
L 2.7835997 3.12278376 2.7824499 3.11864941 1 P 0 ;0,1=403,2=0.000000
L 2.7824499 3.11864941 2.78206663 3.11399951 1 P 0 ;0,1=403,2=0.000000
L 2.78206663 3.11399951 2.7824499 3.10934951 1 P 0 ;0,1=403,2=0.000000
L 2.7824499 3.10934951 2.7835997 3.10521614 1 P 0 ;0,1=403,2=0.000000
L 2.7835997 3.10521614 2.78513337 3.10211585 1 P 0 ;0,1=403,2=0.000000
L 2.78513337 3.10211585 2.78743287 3.09953307 1 P 0 ;0,1=403,2=0.000000
L 2.78743287 3.09953307 2.79049961 3.0985 1 P 0 ;0,1=403,2=0.000000
L 2.79049961 3.0985 2.79356634 3.09953307 1 P 0 ;0,1=403,2=0.000000
L 2.79356634 3.09953307 2.79586654 3.10211585 1 P 0 ;0,1=403,2=0.000000
L 2.79586654 3.10211585 2.7974002 3.10521614 1 P 0 ;0,1=403,2=0.000000
L 2.7974002 3.10521614 2.79855 3.10934951 1 P 0 ;0,1=403,2=0.000000
L 2.79855 3.10934951 2.79893327 3.11399951 1 P 0 ;0,1=403,2=0.000000
L 2.79893327 3.11399951 2.79855 3.11864941 1 P 0 ;0,1=403,2=0.000000
L 2.79855 3.11864941 2.7974002 3.12278376 1 P 0 ;0,1=403,2=0.000000
L 2.7974002 3.12278376 2.79586654 3.12588307 1 P 0 ;0,1=403,2=0.000000
L 2.79586654 3.12588307 2.79356634 3.12846683 1 P 0 ;0,1=403,2=0.000000
L 2.79356634 3.12846683 2.79049961 3.1295 1 P 0 ;0,1=403,2=0.000000
L 2.82149961 3.0985 2.82149961 3.1295 1 P 0 ;0,1=403,2=0.000000
L 2.82149961 3.1295 2.8168999 3.1233003 1 P 0 ;0,1=403,2=0.000000
L 2.8168999 3.0985 2.82609931 3.0985 1 P 0 ;0,1=403,2=0.000000
L 3.225 2.501 3.135 2.501 1 P 0 
L 3.135 2.501 3.135 2.457 1 P 0 
L 3.135 2.457 3.225 2.457 1 P 0 
L 3.225 2.457 3.225 2.501 1 P 0 
L 2.72083317 3.2295 2.72083317 3.2605 1 P 0 ;0,1=404,2=0.000000
L 2.72083317 3.2605 2.73041654 3.2605 1 P 0 ;0,1=404,2=0.000000
L 2.73041654 3.2605 2.73348327 3.25894931 1 P 0 ;0,1=404,2=0.000000
L 2.73348327 3.25894931 2.7354002 3.25688307 1 P 0 ;0,1=404,2=0.000000
L 2.7354002 3.25688307 2.73616673 3.2527497 1 P 0 ;0,1=404,2=0.000000
L 2.73616673 3.2527497 2.7354002 3.24861634 1 P 0 ;0,1=404,2=0.000000
L 2.7354002 3.24861634 2.7331 3.24603356 1 P 0 ;0,1=404,2=0.000000
L 2.7331 3.24603356 2.73041654 3.24448287 1 P 0 ;0,1=404,2=0.000000
L 2.73041654 3.24448287 2.72083317 3.24448287 1 P 0 ;0,1=404,2=0.000000
L 2.73041654 3.24448287 2.73616673 3.2295 1 P 0 ;0,1=404,2=0.000000
L 2.75106663 3.23569961 2.75336614 3.23208278 1 P 0 ;0,1=404,2=0.000000
L 2.75336614 3.23208278 2.75643287 3.23001654 1 P 0 ;0,1=404,2=0.000000
L 2.75643287 3.23001654 2.75988356 3.2295 1 P 0 ;0,1=404,2=0.000000
L 2.75988356 3.2295 2.7629503 3.23001654 1 P 0 ;0,1=404,2=0.000000
L 2.7629503 3.23001654 2.76601703 3.23259931 1 P 0 ;0,1=404,2=0.000000
L 2.76601703 3.23259931 2.76793327 3.23569961 1 P 0 ;0,1=404,2=0.000000
L 2.76793327 3.23569961 2.76831654 3.2387999 1 P 0 ;0,1=404,2=0.000000
L 2.76831654 3.2387999 2.76755 3.24241575 1 P 0 ;0,1=404,2=0.000000
L 2.76755 3.24241575 2.76486654 3.24499951 1 P 0 ;0,1=404,2=0.000000
L 2.76486654 3.24499951 2.76218307 3.24603356 1 P 0 ;0,1=404,2=0.000000
L 2.76218307 3.24603356 2.75873307 3.24603356 1 P 0 ;0,1=404,2=0.000000
L 2.76218307 3.24603356 2.76448327 3.24758317 1 P 0 ;0,1=404,2=0.000000
L 2.76448327 3.24758317 2.7664002 3.25016594 1 P 0 ;0,1=404,2=0.000000
L 2.7664002 3.25016594 2.76716673 3.25326624 1 P 0 ;0,1=404,2=0.000000
L 2.76716673 3.25326624 2.7664002 3.25636654 1 P 0 ;0,1=404,2=0.000000
L 2.7664002 3.25636654 2.76448327 3.25894931 1 P 0 ;0,1=404,2=0.000000
L 2.76448327 3.25894931 2.76103327 3.2605 1 P 0 ;0,1=404,2=0.000000
L 2.76103327 3.2605 2.75758337 3.25998337 1 P 0 ;0,1=404,2=0.000000
L 2.75758337 3.25998337 2.75413337 3.25791624 1 P 0 ;0,1=404,2=0.000000
L 2.79049961 3.2605 2.78743287 3.25946683 1 P 0 ;0,1=404,2=0.000000
L 2.78743287 3.25946683 2.78513337 3.25688307 1 P 0 ;0,1=404,2=0.000000
L 2.78513337 3.25688307 2.7835997 3.25378376 1 P 0 ;0,1=404,2=0.000000
L 2.7835997 3.25378376 2.7824499 3.24964941 1 P 0 ;0,1=404,2=0.000000
L 2.7824499 3.24964941 2.78206663 3.24499951 1 P 0 ;0,1=404,2=0.000000
L 2.78206663 3.24499951 2.7824499 3.24034951 1 P 0 ;0,1=404,2=0.000000
L 2.7824499 3.24034951 2.7835997 3.23621614 1 P 0 ;0,1=404,2=0.000000
L 2.7835997 3.23621614 2.78513337 3.23311585 1 P 0 ;0,1=404,2=0.000000
L 2.78513337 3.23311585 2.78743287 3.23053307 1 P 0 ;0,1=404,2=0.000000
L 2.78743287 3.23053307 2.79049961 3.2295 1 P 0 ;0,1=404,2=0.000000
L 2.79049961 3.2295 2.79356634 3.23053307 1 P 0 ;0,1=404,2=0.000000
L 2.79356634 3.23053307 2.79586654 3.23311585 1 P 0 ;0,1=404,2=0.000000
L 2.79586654 3.23311585 2.7974002 3.23621614 1 P 0 ;0,1=404,2=0.000000
L 2.7974002 3.23621614 2.79855 3.24034951 1 P 0 ;0,1=404,2=0.000000
L 2.79855 3.24034951 2.79893327 3.24499951 1 P 0 ;0,1=404,2=0.000000
L 2.79893327 3.24499951 2.79855 3.24964941 1 P 0 ;0,1=404,2=0.000000
L 2.79855 3.24964941 2.7974002 3.25378376 1 P 0 ;0,1=404,2=0.000000
L 2.7974002 3.25378376 2.79586654 3.25688307 1 P 0 ;0,1=404,2=0.000000
L 2.79586654 3.25688307 2.79356634 3.25946683 1 P 0 ;0,1=404,2=0.000000
L 2.79356634 3.25946683 2.79049961 3.2605 1 P 0 ;0,1=404,2=0.000000
L 2.82073307 3.2295 2.82149961 3.23621614 1 P 0 ;0,1=404,2=0.000000
L 2.82149961 3.23621614 2.8226501 3.24189921 1 P 0 ;0,1=404,2=0.000000
L 2.8226501 3.24189921 2.82418307 3.24706663 1 P 0 ;0,1=404,2=0.000000
L 2.82418307 3.24706663 2.8261 3.2527497 1 P 0 ;0,1=404,2=0.000000
L 2.8261 3.2527497 2.82916673 3.2605 1 P 0 ;0,1=404,2=0.000000
L 2.82916673 3.2605 2.81383317 3.2605 1 P 0 ;0,1=404,2=0.000000
L 4.95 1.953 4.95 1.997 1 P 0 
L 4.95 1.997 4.86 1.997 1 P 0 
L 4.86 1.997 4.86 1.953 1 P 0 
L 4.86 1.953 4.95 1.953 1 P 0 
L 4.87133317 1.8645 4.87133317 1.8955 1 P 0 ;0,1=405,2=0.000000
L 4.87133317 1.8955 4.88091654 1.8955 1 P 0 ;0,1=405,2=0.000000
L 4.88091654 1.8955 4.88398327 1.89394931 1 P 0 ;0,1=405,2=0.000000
L 4.88398327 1.89394931 4.8859002 1.89188307 1 P 0 ;0,1=405,2=0.000000
L 4.8859002 1.89188307 4.88666673 1.8877497 1 P 0 ;0,1=405,2=0.000000
L 4.88666673 1.8877497 4.8859002 1.88361634 1 P 0 ;0,1=405,2=0.000000
L 4.8859002 1.88361634 4.8836 1.88103356 1 P 0 ;0,1=405,2=0.000000
L 4.8836 1.88103356 4.88091654 1.87948287 1 P 0 ;0,1=405,2=0.000000
L 4.88091654 1.87948287 4.87133317 1.87948287 1 P 0 ;0,1=405,2=0.000000
L 4.88091654 1.87948287 4.88666673 1.8645 1 P 0 ;0,1=405,2=0.000000
L 4.90348287 1.86811585 4.90616634 1.86553307 1 P 0 ;0,1=405,2=0.000000
L 4.90616634 1.86553307 4.90923307 1.8645 1 P 0 ;0,1=405,2=0.000000
L 4.90923307 1.8645 4.9122998 1.86553307 1 P 0 ;0,1=405,2=0.000000
L 4.9122998 1.86553307 4.91498327 1.86863238 1 P 0 ;0,1=405,2=0.000000
L 4.91498327 1.86863238 4.9169002 1.87328327 1 P 0 ;0,1=405,2=0.000000
L 4.9169002 1.87328327 4.91766673 1.87793327 1 P 0 ;0,1=405,2=0.000000
L 4.91766673 1.87793327 4.91766673 1.88361634 1 P 0 ;0,1=405,2=0.000000
L 4.91766673 1.88361634 4.9169002 1.88826624 1 P 0 ;0,1=405,2=0.000000
L 4.9169002 1.88826624 4.91498327 1.8923997 1 P 0 ;0,1=405,2=0.000000
L 4.91498327 1.8923997 4.91268307 1.89446683 1 P 0 ;0,1=405,2=0.000000
L 4.91268307 1.89446683 4.90999961 1.8955 1 P 0 ;0,1=405,2=0.000000
L 4.90999961 1.8955 4.90693287 1.89446683 1 P 0 ;0,1=405,2=0.000000
L 4.90693287 1.89446683 4.90463337 1.8923997 1 P 0 ;0,1=405,2=0.000000
L 4.90463337 1.8923997 4.9030997 1.8893003 1 P 0 ;0,1=405,2=0.000000
L 4.9030997 1.8893003 4.90233317 1.88516594 1 P 0 ;0,1=405,2=0.000000
L 4.90233317 1.88516594 4.9030997 1.8815501 1 P 0 ;0,1=405,2=0.000000
L 4.9030997 1.8815501 4.90501663 1.87793327 1 P 0 ;0,1=405,2=0.000000
L 4.90501663 1.87793327 4.90731683 1.87586604 1 P 0 ;0,1=405,2=0.000000
L 4.90731683 1.87586604 4.90999961 1.87534951 1 P 0 ;0,1=405,2=0.000000
L 4.90999961 1.87534951 4.91306634 1.87638268 1 P 0 ;0,1=405,2=0.000000
L 4.91306634 1.87638268 4.91536654 1.87896634 1 P 0 ;0,1=405,2=0.000000
L 4.91536654 1.87896634 4.91766673 1.88361634 1 P 0 ;0,1=405,2=0.000000
L 4.9456 1.8645 4.9456 1.8955 1 P 0 ;0,1=405,2=0.000000
L 4.9456 1.8955 4.93141624 1.87328327 1 P 0 ;0,1=405,2=0.000000
L 4.93141624 1.87328327 4.95058366 1.87328327 1 P 0 ;0,1=405,2=0.000000
L 4.95 2.003 4.95 2.047 1 P 0 
L 4.95 2.047 4.86 2.047 1 P 0 
L 4.86 2.047 4.86 2.003 1 P 0 
L 4.86 2.003 4.95 2.003 1 P 0 
L 4.87133317 1.9145 4.87133317 1.9455 1 P 0 ;0,1=406,2=0.000000
L 4.87133317 1.9455 4.88091654 1.9455 1 P 0 ;0,1=406,2=0.000000
L 4.88091654 1.9455 4.88398327 1.94394931 1 P 0 ;0,1=406,2=0.000000
L 4.88398327 1.94394931 4.8859002 1.94188307 1 P 0 ;0,1=406,2=0.000000
L 4.8859002 1.94188307 4.88666673 1.9377497 1 P 0 ;0,1=406,2=0.000000
L 4.88666673 1.9377497 4.8859002 1.93361634 1 P 0 ;0,1=406,2=0.000000
L 4.8859002 1.93361634 4.8836 1.93103356 1 P 0 ;0,1=406,2=0.000000
L 4.8836 1.93103356 4.88091654 1.92948287 1 P 0 ;0,1=406,2=0.000000
L 4.88091654 1.92948287 4.87133317 1.92948287 1 P 0 ;0,1=406,2=0.000000
L 4.88091654 1.92948287 4.88666673 1.9145 1 P 0 ;0,1=406,2=0.000000
L 4.90348287 1.91811585 4.90616634 1.91553307 1 P 0 ;0,1=406,2=0.000000
L 4.90616634 1.91553307 4.90923307 1.9145 1 P 0 ;0,1=406,2=0.000000
L 4.90923307 1.9145 4.9122998 1.91553307 1 P 0 ;0,1=406,2=0.000000
L 4.9122998 1.91553307 4.91498327 1.91863238 1 P 0 ;0,1=406,2=0.000000
L 4.91498327 1.91863238 4.9169002 1.92328327 1 P 0 ;0,1=406,2=0.000000
L 4.9169002 1.92328327 4.91766673 1.92793327 1 P 0 ;0,1=406,2=0.000000
L 4.91766673 1.92793327 4.91766673 1.93361634 1 P 0 ;0,1=406,2=0.000000
L 4.91766673 1.93361634 4.9169002 1.93826624 1 P 0 ;0,1=406,2=0.000000
L 4.9169002 1.93826624 4.91498327 1.9423997 1 P 0 ;0,1=406,2=0.000000
L 4.91498327 1.9423997 4.91268307 1.94446683 1 P 0 ;0,1=406,2=0.000000
L 4.91268307 1.94446683 4.90999961 1.9455 1 P 0 ;0,1=406,2=0.000000
L 4.90999961 1.9455 4.90693287 1.94446683 1 P 0 ;0,1=406,2=0.000000
L 4.90693287 1.94446683 4.90463337 1.9423997 1 P 0 ;0,1=406,2=0.000000
L 4.90463337 1.9423997 4.9030997 1.9393003 1 P 0 ;0,1=406,2=0.000000
L 4.9030997 1.9393003 4.90233317 1.93516594 1 P 0 ;0,1=406,2=0.000000
L 4.90233317 1.93516594 4.9030997 1.9315501 1 P 0 ;0,1=406,2=0.000000
L 4.9030997 1.9315501 4.90501663 1.92793327 1 P 0 ;0,1=406,2=0.000000
L 4.90501663 1.92793327 4.90731683 1.92586604 1 P 0 ;0,1=406,2=0.000000
L 4.90731683 1.92586604 4.90999961 1.92534951 1 P 0 ;0,1=406,2=0.000000
L 4.90999961 1.92534951 4.91306634 1.92638268 1 P 0 ;0,1=406,2=0.000000
L 4.91306634 1.92638268 4.91536654 1.92896634 1 P 0 ;0,1=406,2=0.000000
L 4.91536654 1.92896634 4.91766673 1.93361634 1 P 0 ;0,1=406,2=0.000000
L 4.93256663 1.91914892 4.93486614 1.91656614 1 P 0 ;0,1=406,2=0.000000
L 4.93486614 1.91656614 4.93754961 1.91501654 1 P 0 ;0,1=406,2=0.000000
L 4.93754961 1.91501654 4.94099961 1.9145 1 P 0 ;0,1=406,2=0.000000
L 4.94099961 1.9145 4.9444503 1.91553307 1 P 0 ;0,1=406,2=0.000000
L 4.9444503 1.91553307 4.94713307 1.91759931 1 P 0 ;0,1=406,2=0.000000
L 4.94713307 1.91759931 4.94905 1.92121614 1 P 0 ;0,1=406,2=0.000000
L 4.94905 1.92121614 4.94943327 1.92534951 1 P 0 ;0,1=406,2=0.000000
L 4.94943327 1.92534951 4.94866673 1.92948287 1 P 0 ;0,1=406,2=0.000000
L 4.94866673 1.92948287 4.9467498 1.93206663 1 P 0 ;0,1=406,2=0.000000
L 4.9467498 1.93206663 4.94406634 1.93413287 1 P 0 ;0,1=406,2=0.000000
L 4.94406634 1.93413287 4.94138356 1.93464941 1 P 0 ;0,1=406,2=0.000000
L 4.94138356 1.93464941 4.9387001 1.93413287 1 P 0 ;0,1=406,2=0.000000
L 4.9387001 1.93413287 4.9352501 1.93206663 1 P 0 ;0,1=406,2=0.000000
L 4.9352501 1.93206663 4.9363999 1.9455 1 P 0 ;0,1=406,2=0.000000
L 4.9363999 1.9455 4.9467498 1.9455 1 P 0 ;0,1=406,2=0.000000
L 4.462 2.395 4.462 2.485 1 P 0 
L 4.462 2.485 4.418 2.485 1 P 0 
L 4.418 2.485 4.418 2.395 1 P 0 
L 4.418 2.395 4.462 2.395 1 P 0 
L 4.4705 2.51583317 4.4395 2.51583317 1 P 0 ;0,1=407,2=270.000000
L 4.4395 2.51583317 4.4395 2.52541654 1 P 0 ;0,1=407,2=270.000000
L 4.4395 2.52541654 4.44105069 2.52848327 1 P 0 ;0,1=407,2=270.000000
L 4.44105069 2.52848327 4.44311693 2.5304002 1 P 0 ;0,1=407,2=270.000000
L 4.44311693 2.5304002 4.4472503 2.53116673 1 P 0 ;0,1=407,2=270.000000
L 4.4472503 2.53116673 4.45138366 2.5304002 1 P 0 ;0,1=407,2=270.000000
L 4.45138366 2.5304002 4.45396644 2.5281 1 P 0 ;0,1=407,2=270.000000
L 4.45396644 2.5281 4.45551713 2.52541654 1 P 0 ;0,1=407,2=270.000000
L 4.45551713 2.52541654 4.45551713 2.51583317 1 P 0 ;0,1=407,2=270.000000
L 4.45551713 2.52541654 4.4705 2.53116673 1 P 0 ;0,1=407,2=270.000000
L 4.44466654 2.54721644 4.44156722 2.54951663 1 P 0 ;0,1=407,2=270.000000
L 4.44156722 2.54951663 4.44001663 2.5522001 1 P 0 ;0,1=407,2=270.000000
L 4.44001663 2.5522001 4.4395 2.55526683 1 P 0 ;0,1=407,2=270.000000
L 4.4395 2.55526683 4.44053317 2.5591 1 P 0 ;0,1=407,2=270.000000
L 4.44053317 2.5591 4.44311693 2.56178346 1 P 0 ;0,1=407,2=270.000000
L 4.44311693 2.56178346 4.44621624 2.56255 1 P 0 ;0,1=407,2=270.000000
L 4.44621624 2.56255 4.44931742 2.56216673 1 P 0 ;0,1=407,2=270.000000
L 4.44931742 2.56216673 4.4519002 2.56063307 1 P 0 ;0,1=407,2=270.000000
L 4.4519002 2.56063307 4.45706673 2.55296663 1 P 0 ;0,1=407,2=270.000000
L 4.45706673 2.55296663 4.46068356 2.54951663 1 P 0 ;0,1=407,2=270.000000
L 4.46068356 2.54951663 4.46585108 2.54721644 1 P 0 ;0,1=407,2=270.000000
L 4.46585108 2.54721644 4.4705 2.5464499 1 P 0 ;0,1=407,2=270.000000
L 4.4705 2.5464499 4.4705 2.56255 1 P 0 ;0,1=407,2=270.000000
L 4.4705 2.58549961 4.4395 2.58549961 1 P 0 ;0,1=407,2=270.000000
L 4.4395 2.58549961 4.4456997 2.5808999 1 P 0 ;0,1=407,2=270.000000
L 4.4705 2.5808999 4.4705 2.59009931 1 P 0 ;0,1=407,2=270.000000
L 4.4705 2.6211 4.4395 2.6211 1 P 0 ;0,1=407,2=270.000000
L 4.4395 2.6211 4.46171673 2.60691624 1 P 0 ;0,1=407,2=270.000000
L 4.46171673 2.60691624 4.46171673 2.62608366 1 P 0 ;0,1=407,2=270.000000
L 4.95 2.093 4.95 2.137 1 P 0 
L 4.95 2.137 4.86 2.137 1 P 0 
L 4.86 2.137 4.86 2.093 1 P 0 
L 4.86 2.093 4.95 2.093 1 P 0 
L 4.97583317 2.0895 4.97583317 2.1205 1 P 0 ;0,1=408,2=0.000000
L 4.97583317 2.1205 4.98541654 2.1205 1 P 0 ;0,1=408,2=0.000000
L 4.98541654 2.1205 4.98848327 2.11894931 1 P 0 ;0,1=408,2=0.000000
L 4.98848327 2.11894931 4.9904002 2.11688307 1 P 0 ;0,1=408,2=0.000000
L 4.9904002 2.11688307 4.99116673 2.1127497 1 P 0 ;0,1=408,2=0.000000
L 4.99116673 2.1127497 4.9904002 2.10861634 1 P 0 ;0,1=408,2=0.000000
L 4.9904002 2.10861634 4.9881 2.10603356 1 P 0 ;0,1=408,2=0.000000
L 4.9881 2.10603356 4.98541654 2.10448287 1 P 0 ;0,1=408,2=0.000000
L 4.98541654 2.10448287 4.97583317 2.10448287 1 P 0 ;0,1=408,2=0.000000
L 4.98541654 2.10448287 4.99116673 2.0895 1 P 0 ;0,1=408,2=0.000000
L 5.01449961 2.0895 5.01449961 2.1205 1 P 0 ;0,1=408,2=0.000000
L 5.01449961 2.1205 5.0098999 2.1143003 1 P 0 ;0,1=408,2=0.000000
L 5.0098999 2.0895 5.01909931 2.0895 1 P 0 ;0,1=408,2=0.000000
L 5.03898287 2.09311585 5.04166634 2.09053307 1 P 0 ;0,1=408,2=0.000000
L 5.04166634 2.09053307 5.04473307 2.0895 1 P 0 ;0,1=408,2=0.000000
L 5.04473307 2.0895 5.0477998 2.09053307 1 P 0 ;0,1=408,2=0.000000
L 5.0477998 2.09053307 5.05048327 2.09363238 1 P 0 ;0,1=408,2=0.000000
L 5.05048327 2.09363238 5.0524002 2.09828327 1 P 0 ;0,1=408,2=0.000000
L 5.0524002 2.09828327 5.05316673 2.10293327 1 P 0 ;0,1=408,2=0.000000
L 5.05316673 2.10293327 5.05316673 2.10861634 1 P 0 ;0,1=408,2=0.000000
L 5.05316673 2.10861634 5.0524002 2.11326624 1 P 0 ;0,1=408,2=0.000000
L 5.0524002 2.11326624 5.05048327 2.1173997 1 P 0 ;0,1=408,2=0.000000
L 5.05048327 2.1173997 5.04818307 2.11946683 1 P 0 ;0,1=408,2=0.000000
L 5.04818307 2.11946683 5.04549961 2.1205 1 P 0 ;0,1=408,2=0.000000
L 5.04549961 2.1205 5.04243287 2.11946683 1 P 0 ;0,1=408,2=0.000000
L 5.04243287 2.11946683 5.04013337 2.1173997 1 P 0 ;0,1=408,2=0.000000
L 5.04013337 2.1173997 5.0385997 2.1143003 1 P 0 ;0,1=408,2=0.000000
L 5.0385997 2.1143003 5.03783317 2.11016594 1 P 0 ;0,1=408,2=0.000000
L 5.03783317 2.11016594 5.0385997 2.1065501 1 P 0 ;0,1=408,2=0.000000
L 5.0385997 2.1065501 5.04051663 2.10293327 1 P 0 ;0,1=408,2=0.000000
L 5.04051663 2.10293327 5.04281683 2.10086604 1 P 0 ;0,1=408,2=0.000000
L 5.04281683 2.10086604 5.04549961 2.10034951 1 P 0 ;0,1=408,2=0.000000
L 5.04549961 2.10034951 5.04856634 2.10138268 1 P 0 ;0,1=408,2=0.000000
L 5.04856634 2.10138268 5.05086654 2.10396634 1 P 0 ;0,1=408,2=0.000000
L 5.05086654 2.10396634 5.05316673 2.10861634 1 P 0 ;0,1=408,2=0.000000
L 5.06806663 2.09569961 5.07036614 2.09208278 1 P 0 ;0,1=408,2=0.000000
L 5.07036614 2.09208278 5.07343287 2.09001654 1 P 0 ;0,1=408,2=0.000000
L 5.07343287 2.09001654 5.07688356 2.0895 1 P 0 ;0,1=408,2=0.000000
L 5.07688356 2.0895 5.0799503 2.09001654 1 P 0 ;0,1=408,2=0.000000
L 5.0799503 2.09001654 5.08301703 2.09259931 1 P 0 ;0,1=408,2=0.000000
L 5.08301703 2.09259931 5.08493327 2.09569961 1 P 0 ;0,1=408,2=0.000000
L 5.08493327 2.09569961 5.08531654 2.0987999 1 P 0 ;0,1=408,2=0.000000
L 5.08531654 2.0987999 5.08455 2.10241575 1 P 0 ;0,1=408,2=0.000000
L 5.08455 2.10241575 5.08186654 2.10499951 1 P 0 ;0,1=408,2=0.000000
L 5.08186654 2.10499951 5.07918307 2.10603356 1 P 0 ;0,1=408,2=0.000000
L 5.07918307 2.10603356 5.07573307 2.10603356 1 P 0 ;0,1=408,2=0.000000
L 5.07918307 2.10603356 5.08148327 2.10758317 1 P 0 ;0,1=408,2=0.000000
L 5.08148327 2.10758317 5.0834002 2.11016594 1 P 0 ;0,1=408,2=0.000000
L 5.0834002 2.11016594 5.08416673 2.11326624 1 P 0 ;0,1=408,2=0.000000
L 5.08416673 2.11326624 5.0834002 2.11636654 1 P 0 ;0,1=408,2=0.000000
L 5.0834002 2.11636654 5.08148327 2.11894931 1 P 0 ;0,1=408,2=0.000000
L 5.08148327 2.11894931 5.07803327 2.1205 1 P 0 ;0,1=408,2=0.000000
L 5.07803327 2.1205 5.07458337 2.11998337 1 P 0 ;0,1=408,2=0.000000
L 5.07458337 2.11998337 5.07113337 2.11791624 1 P 0 ;0,1=408,2=0.000000
L 4.373 2.485 4.373 2.395 1 P 0 
L 4.373 2.395 4.417 2.395 1 P 0 
L 4.417 2.395 4.417 2.485 1 P 0 
L 4.417 2.485 4.373 2.485 1 P 0 
L 4.4255 2.51583317 4.3945 2.51583317 1 P 0 ;0,1=409,2=270.000000
L 4.3945 2.51583317 4.3945 2.52541654 1 P 0 ;0,1=409,2=270.000000
L 4.3945 2.52541654 4.39605069 2.52848327 1 P 0 ;0,1=409,2=270.000000
L 4.39605069 2.52848327 4.39811693 2.5304002 1 P 0 ;0,1=409,2=270.000000
L 4.39811693 2.5304002 4.4022503 2.53116673 1 P 0 ;0,1=409,2=270.000000
L 4.4022503 2.53116673 4.40638366 2.5304002 1 P 0 ;0,1=409,2=270.000000
L 4.40638366 2.5304002 4.40896644 2.5281 1 P 0 ;0,1=409,2=270.000000
L 4.40896644 2.5281 4.41051713 2.52541654 1 P 0 ;0,1=409,2=270.000000
L 4.41051713 2.52541654 4.41051713 2.51583317 1 P 0 ;0,1=409,2=270.000000
L 4.41051713 2.52541654 4.4255 2.53116673 1 P 0 ;0,1=409,2=270.000000
L 4.39966654 2.54721644 4.39656722 2.54951663 1 P 0 ;0,1=409,2=270.000000
L 4.39656722 2.54951663 4.39501663 2.5522001 1 P 0 ;0,1=409,2=270.000000
L 4.39501663 2.5522001 4.3945 2.55526683 1 P 0 ;0,1=409,2=270.000000
L 4.3945 2.55526683 4.39553317 2.5591 1 P 0 ;0,1=409,2=270.000000
L 4.39553317 2.5591 4.39811693 2.56178346 1 P 0 ;0,1=409,2=270.000000
L 4.39811693 2.56178346 4.40121624 2.56255 1 P 0 ;0,1=409,2=270.000000
L 4.40121624 2.56255 4.40431742 2.56216673 1 P 0 ;0,1=409,2=270.000000
L 4.40431742 2.56216673 4.4069002 2.56063307 1 P 0 ;0,1=409,2=270.000000
L 4.4069002 2.56063307 4.41206673 2.55296663 1 P 0 ;0,1=409,2=270.000000
L 4.41206673 2.55296663 4.41568356 2.54951663 1 P 0 ;0,1=409,2=270.000000
L 4.41568356 2.54951663 4.42085108 2.54721644 1 P 0 ;0,1=409,2=270.000000
L 4.42085108 2.54721644 4.4255 2.5464499 1 P 0 ;0,1=409,2=270.000000
L 4.4255 2.5464499 4.4255 2.56255 1 P 0 ;0,1=409,2=270.000000
L 4.4255 2.58549961 4.3945 2.58549961 1 P 0 ;0,1=409,2=270.000000
L 4.3945 2.58549961 4.4006997 2.5808999 1 P 0 ;0,1=409,2=270.000000
L 4.4255 2.5808999 4.4255 2.59009931 1 P 0 ;0,1=409,2=270.000000
L 4.41930039 2.60806663 4.42291722 2.61036614 1 P 0 ;0,1=409,2=270.000000
L 4.42291722 2.61036614 4.42498346 2.61343287 1 P 0 ;0,1=409,2=270.000000
L 4.42498346 2.61343287 4.4255 2.61688356 1 P 0 ;0,1=409,2=270.000000
L 4.4255 2.61688356 4.42498346 2.6199503 1 P 0 ;0,1=409,2=270.000000
L 4.42498346 2.6199503 4.42240069 2.62301703 1 P 0 ;0,1=409,2=270.000000
L 4.42240069 2.62301703 4.41930039 2.62493327 1 P 0 ;0,1=409,2=270.000000
L 4.41930039 2.62493327 4.4162001 2.62531654 1 P 0 ;0,1=409,2=270.000000
L 4.4162001 2.62531654 4.41258425 2.62455 1 P 0 ;0,1=409,2=270.000000
L 4.41258425 2.62455 4.41000049 2.62186654 1 P 0 ;0,1=409,2=270.000000
L 4.41000049 2.62186654 4.40896644 2.61918307 1 P 0 ;0,1=409,2=270.000000
L 4.40896644 2.61918307 4.40896644 2.61573307 1 P 0 ;0,1=409,2=270.000000
L 4.40896644 2.61918307 4.40741683 2.62148327 1 P 0 ;0,1=409,2=270.000000
L 4.40741683 2.62148327 4.40483406 2.6234002 1 P 0 ;0,1=409,2=270.000000
L 4.40483406 2.6234002 4.40173376 2.62416673 1 P 0 ;0,1=409,2=270.000000
L 4.40173376 2.62416673 4.39863346 2.6234002 1 P 0 ;0,1=409,2=270.000000
L 4.39863346 2.6234002 4.39605069 2.62148327 1 P 0 ;0,1=409,2=270.000000
L 4.39605069 2.62148327 4.3945 2.61803327 1 P 0 ;0,1=409,2=270.000000
L 4.3945 2.61803327 4.39501663 2.61458337 1 P 0 ;0,1=409,2=270.000000
L 4.39501663 2.61458337 4.39708376 2.61113337 1 P 0 ;0,1=409,2=270.000000
L 3.225 2.231 3.135 2.231 1 P 0 
L 3.135 2.231 3.135 2.187 1 P 0 
L 3.135 2.187 3.225 2.187 1 P 0 
L 3.225 2.187 3.225 2.231 1 P 0 
L 2.72083317 2.9635 2.72083317 2.9945 1 P 0 ;0,1=410,2=0.000000
L 2.72083317 2.9945 2.73041654 2.9945 1 P 0 ;0,1=410,2=0.000000
L 2.73041654 2.9945 2.73348327 2.99294931 1 P 0 ;0,1=410,2=0.000000
L 2.73348327 2.99294931 2.7354002 2.99088307 1 P 0 ;0,1=410,2=0.000000
L 2.7354002 2.99088307 2.73616673 2.9867497 1 P 0 ;0,1=410,2=0.000000
L 2.73616673 2.9867497 2.7354002 2.98261634 1 P 0 ;0,1=410,2=0.000000
L 2.7354002 2.98261634 2.7331 2.98003356 1 P 0 ;0,1=410,2=0.000000
L 2.7331 2.98003356 2.73041654 2.97848287 1 P 0 ;0,1=410,2=0.000000
L 2.73041654 2.97848287 2.72083317 2.97848287 1 P 0 ;0,1=410,2=0.000000
L 2.73041654 2.97848287 2.73616673 2.9635 1 P 0 ;0,1=410,2=0.000000
L 2.75221644 2.98933346 2.75451663 2.99243278 1 P 0 ;0,1=410,2=0.000000
L 2.75451663 2.99243278 2.7572001 2.99398337 1 P 0 ;0,1=410,2=0.000000
L 2.7572001 2.99398337 2.76026683 2.9945 1 P 0 ;0,1=410,2=0.000000
L 2.76026683 2.9945 2.7641 2.99346683 1 P 0 ;0,1=410,2=0.000000
L 2.7641 2.99346683 2.76678346 2.99088307 1 P 0 ;0,1=410,2=0.000000
L 2.76678346 2.99088307 2.76755 2.98778376 1 P 0 ;0,1=410,2=0.000000
L 2.76755 2.98778376 2.76716673 2.98468258 1 P 0 ;0,1=410,2=0.000000
L 2.76716673 2.98468258 2.76563307 2.9820998 1 P 0 ;0,1=410,2=0.000000
L 2.76563307 2.9820998 2.75796663 2.97693327 1 P 0 ;0,1=410,2=0.000000
L 2.75796663 2.97693327 2.75451663 2.97331644 1 P 0 ;0,1=410,2=0.000000
L 2.75451663 2.97331644 2.75221644 2.96814892 1 P 0 ;0,1=410,2=0.000000
L 2.75221644 2.96814892 2.7514499 2.9635 1 P 0 ;0,1=410,2=0.000000
L 2.7514499 2.9635 2.76755 2.9635 1 P 0 ;0,1=410,2=0.000000
L 2.79049961 2.9635 2.79318307 2.96401654 1 P 0 ;0,1=410,2=0.000000
L 2.79318307 2.96401654 2.7962498 2.96556614 1 P 0 ;0,1=410,2=0.000000
L 2.7962498 2.96556614 2.79816673 2.96814892 1 P 0 ;0,1=410,2=0.000000
L 2.79816673 2.96814892 2.79893327 2.97176673 1 P 0 ;0,1=410,2=0.000000
L 2.79893327 2.97176673 2.79816673 2.97538268 1 P 0 ;0,1=410,2=0.000000
L 2.79816673 2.97538268 2.79586654 2.97848287 1 P 0 ;0,1=410,2=0.000000
L 2.79586654 2.97848287 2.79241654 2.98003356 1 P 0 ;0,1=410,2=0.000000
L 2.79241654 2.98003356 2.78858337 2.98003356 1 P 0 ;0,1=410,2=0.000000
L 2.78858337 2.98003356 2.78628317 2.98106663 1 P 0 ;0,1=410,2=0.000000
L 2.78628317 2.98106663 2.78436614 2.98364941 1 P 0 ;0,1=410,2=0.000000
L 2.78436614 2.98364941 2.7835997 2.98726624 1 P 0 ;0,1=410,2=0.000000
L 2.7835997 2.98726624 2.7847501 2.99088307 1 P 0 ;0,1=410,2=0.000000
L 2.7847501 2.99088307 2.78743287 2.99346683 1 P 0 ;0,1=410,2=0.000000
L 2.78743287 2.99346683 2.79049961 2.9945 1 P 0 ;0,1=410,2=0.000000
L 2.79049961 2.9945 2.79356634 2.99346683 1 P 0 ;0,1=410,2=0.000000
L 2.79356634 2.99346683 2.7962498 2.99088307 1 P 0 ;0,1=410,2=0.000000
L 2.7962498 2.99088307 2.7974002 2.98726624 1 P 0 ;0,1=410,2=0.000000
L 2.7974002 2.98726624 2.79663307 2.98364941 1 P 0 ;0,1=410,2=0.000000
L 2.79663307 2.98364941 2.79471673 2.98106663 1 P 0 ;0,1=410,2=0.000000
L 2.79471673 2.98106663 2.79241654 2.98003356 1 P 0 ;0,1=410,2=0.000000
L 2.79241654 2.98003356 2.78858337 2.98003356 1 P 0 ;0,1=410,2=0.000000
L 2.78858337 2.98003356 2.78513337 2.97848287 1 P 0 ;0,1=410,2=0.000000
L 2.78513337 2.97848287 2.78283317 2.97538268 1 P 0 ;0,1=410,2=0.000000
L 2.78283317 2.97538268 2.78206663 2.97176673 1 P 0 ;0,1=410,2=0.000000
L 2.78206663 2.97176673 2.78283317 2.96814892 1 P 0 ;0,1=410,2=0.000000
L 2.78283317 2.96814892 2.7847501 2.96556614 1 P 0 ;0,1=410,2=0.000000
L 2.7847501 2.96556614 2.78781683 2.96401654 1 P 0 ;0,1=410,2=0.000000
L 2.78781683 2.96401654 2.79049961 2.9635 1 P 0 ;0,1=410,2=0.000000
L 2.81498287 2.96711585 2.81766634 2.96453307 1 P 0 ;0,1=410,2=0.000000
L 2.81766634 2.96453307 2.82073307 2.9635 1 P 0 ;0,1=410,2=0.000000
L 2.82073307 2.9635 2.8237998 2.96453307 1 P 0 ;0,1=410,2=0.000000
L 2.8237998 2.96453307 2.82648327 2.96763238 1 P 0 ;0,1=410,2=0.000000
L 2.82648327 2.96763238 2.8284002 2.97228327 1 P 0 ;0,1=410,2=0.000000
L 2.8284002 2.97228327 2.82916673 2.97693327 1 P 0 ;0,1=410,2=0.000000
L 2.82916673 2.97693327 2.82916673 2.98261634 1 P 0 ;0,1=410,2=0.000000
L 2.82916673 2.98261634 2.8284002 2.98726624 1 P 0 ;0,1=410,2=0.000000
L 2.8284002 2.98726624 2.82648327 2.9913997 1 P 0 ;0,1=410,2=0.000000
L 2.82648327 2.9913997 2.82418307 2.99346683 1 P 0 ;0,1=410,2=0.000000
L 2.82418307 2.99346683 2.82149961 2.9945 1 P 0 ;0,1=410,2=0.000000
L 2.82149961 2.9945 2.81843287 2.99346683 1 P 0 ;0,1=410,2=0.000000
L 2.81843287 2.99346683 2.81613337 2.9913997 1 P 0 ;0,1=410,2=0.000000
L 2.81613337 2.9913997 2.8145997 2.9883003 1 P 0 ;0,1=410,2=0.000000
L 2.8145997 2.9883003 2.81383317 2.98416594 1 P 0 ;0,1=410,2=0.000000
L 2.81383317 2.98416594 2.8145997 2.9805501 1 P 0 ;0,1=410,2=0.000000
L 2.8145997 2.9805501 2.81651663 2.97693327 1 P 0 ;0,1=410,2=0.000000
L 2.81651663 2.97693327 2.81881683 2.97486604 1 P 0 ;0,1=410,2=0.000000
L 2.81881683 2.97486604 2.82149961 2.97434951 1 P 0 ;0,1=410,2=0.000000
L 2.82149961 2.97434951 2.82456634 2.97538268 1 P 0 ;0,1=410,2=0.000000
L 2.82456634 2.97538268 2.82686654 2.97796634 1 P 0 ;0,1=410,2=0.000000
L 2.82686654 2.97796634 2.82916673 2.98261634 1 P 0 ;0,1=410,2=0.000000
L 3.225 2.186 3.135 2.186 1 P 0 
L 3.135 2.186 3.135 2.142 1 P 0 
L 3.135 2.142 3.225 2.142 1 P 0 
L 3.225 2.142 3.225 2.186 1 P 0 
L 2.72583317 2.8895 2.72583317 2.9205 1 P 0 ;0,1=411,2=0.000000
L 2.72583317 2.9205 2.73541654 2.9205 1 P 0 ;0,1=411,2=0.000000
L 2.73541654 2.9205 2.73848327 2.91894931 1 P 0 ;0,1=411,2=0.000000
L 2.73848327 2.91894931 2.7404002 2.91688307 1 P 0 ;0,1=411,2=0.000000
L 2.7404002 2.91688307 2.74116673 2.9127497 1 P 0 ;0,1=411,2=0.000000
L 2.74116673 2.9127497 2.7404002 2.90861634 1 P 0 ;0,1=411,2=0.000000
L 2.7404002 2.90861634 2.7381 2.90603356 1 P 0 ;0,1=411,2=0.000000
L 2.7381 2.90603356 2.73541654 2.90448287 1 P 0 ;0,1=411,2=0.000000
L 2.73541654 2.90448287 2.72583317 2.90448287 1 P 0 ;0,1=411,2=0.000000
L 2.73541654 2.90448287 2.74116673 2.8895 1 P 0 ;0,1=411,2=0.000000
L 2.75606663 2.89569961 2.75836614 2.89208278 1 P 0 ;0,1=411,2=0.000000
L 2.75836614 2.89208278 2.76143287 2.89001654 1 P 0 ;0,1=411,2=0.000000
L 2.76143287 2.89001654 2.76488356 2.8895 1 P 0 ;0,1=411,2=0.000000
L 2.76488356 2.8895 2.7679503 2.89001654 1 P 0 ;0,1=411,2=0.000000
L 2.7679503 2.89001654 2.77101703 2.89259931 1 P 0 ;0,1=411,2=0.000000
L 2.77101703 2.89259931 2.77293327 2.89569961 1 P 0 ;0,1=411,2=0.000000
L 2.77293327 2.89569961 2.77331654 2.8987999 1 P 0 ;0,1=411,2=0.000000
L 2.77331654 2.8987999 2.77255 2.90241575 1 P 0 ;0,1=411,2=0.000000
L 2.77255 2.90241575 2.76986654 2.90499951 1 P 0 ;0,1=411,2=0.000000
L 2.76986654 2.90499951 2.76718307 2.90603356 1 P 0 ;0,1=411,2=0.000000
L 2.76718307 2.90603356 2.76373307 2.90603356 1 P 0 ;0,1=411,2=0.000000
L 2.76718307 2.90603356 2.76948327 2.90758317 1 P 0 ;0,1=411,2=0.000000
L 2.76948327 2.90758317 2.7714002 2.91016594 1 P 0 ;0,1=411,2=0.000000
L 2.7714002 2.91016594 2.77216673 2.91326624 1 P 0 ;0,1=411,2=0.000000
L 2.77216673 2.91326624 2.7714002 2.91636654 1 P 0 ;0,1=411,2=0.000000
L 2.7714002 2.91636654 2.76948327 2.91894931 1 P 0 ;0,1=411,2=0.000000
L 2.76948327 2.91894931 2.76603327 2.9205 1 P 0 ;0,1=411,2=0.000000
L 2.76603327 2.9205 2.76258337 2.91998337 1 P 0 ;0,1=411,2=0.000000
L 2.76258337 2.91998337 2.75913337 2.91791624 1 P 0 ;0,1=411,2=0.000000
L 2.79549961 2.9205 2.79243287 2.91946683 1 P 0 ;0,1=411,2=0.000000
L 2.79243287 2.91946683 2.79013337 2.91688307 1 P 0 ;0,1=411,2=0.000000
L 2.79013337 2.91688307 2.7885997 2.91378376 1 P 0 ;0,1=411,2=0.000000
L 2.7885997 2.91378376 2.7874499 2.90964941 1 P 0 ;0,1=411,2=0.000000
L 2.7874499 2.90964941 2.78706663 2.90499951 1 P 0 ;0,1=411,2=0.000000
L 2.78706663 2.90499951 2.7874499 2.90034951 1 P 0 ;0,1=411,2=0.000000
L 2.7874499 2.90034951 2.7885997 2.89621614 1 P 0 ;0,1=411,2=0.000000
L 2.7885997 2.89621614 2.79013337 2.89311585 1 P 0 ;0,1=411,2=0.000000
L 2.79013337 2.89311585 2.79243287 2.89053307 1 P 0 ;0,1=411,2=0.000000
L 2.79243287 2.89053307 2.79549961 2.8895 1 P 0 ;0,1=411,2=0.000000
L 2.79549961 2.8895 2.79856634 2.89053307 1 P 0 ;0,1=411,2=0.000000
L 2.79856634 2.89053307 2.80086654 2.89311585 1 P 0 ;0,1=411,2=0.000000
L 2.80086654 2.89311585 2.8024002 2.89621614 1 P 0 ;0,1=411,2=0.000000
L 2.8024002 2.89621614 2.80355 2.90034951 1 P 0 ;0,1=411,2=0.000000
L 2.80355 2.90034951 2.80393327 2.90499951 1 P 0 ;0,1=411,2=0.000000
L 2.80393327 2.90499951 2.80355 2.90964941 1 P 0 ;0,1=411,2=0.000000
L 2.80355 2.90964941 2.8024002 2.91378376 1 P 0 ;0,1=411,2=0.000000
L 2.8024002 2.91378376 2.80086654 2.91688307 1 P 0 ;0,1=411,2=0.000000
L 2.80086654 2.91688307 2.79856634 2.91946683 1 P 0 ;0,1=411,2=0.000000
L 2.79856634 2.91946683 2.79549961 2.9205 1 P 0 ;0,1=411,2=0.000000
L 2.81921644 2.91533346 2.82151663 2.91843278 1 P 0 ;0,1=411,2=0.000000
L 2.82151663 2.91843278 2.8242001 2.91998337 1 P 0 ;0,1=411,2=0.000000
L 2.8242001 2.91998337 2.82726683 2.9205 1 P 0 ;0,1=411,2=0.000000
L 2.82726683 2.9205 2.8311 2.91946683 1 P 0 ;0,1=411,2=0.000000
L 2.8311 2.91946683 2.83378346 2.91688307 1 P 0 ;0,1=411,2=0.000000
L 2.83378346 2.91688307 2.83455 2.91378376 1 P 0 ;0,1=411,2=0.000000
L 2.83455 2.91378376 2.83416673 2.91068258 1 P 0 ;0,1=411,2=0.000000
L 2.83416673 2.91068258 2.83263307 2.9080998 1 P 0 ;0,1=411,2=0.000000
L 2.83263307 2.9080998 2.82496663 2.90293327 1 P 0 ;0,1=411,2=0.000000
L 2.82496663 2.90293327 2.82151663 2.89931644 1 P 0 ;0,1=411,2=0.000000
L 2.82151663 2.89931644 2.81921644 2.89414892 1 P 0 ;0,1=411,2=0.000000
L 2.81921644 2.89414892 2.8184499 2.8895 1 P 0 ;0,1=411,2=0.000000
L 2.8184499 2.8895 2.83455 2.8895 1 P 0 ;0,1=411,2=0.000000
L 3.234 2.132 3.144 2.132 1 P 0 
L 3.144 2.132 3.144 2.088 1 P 0 
L 3.144 2.088 3.234 2.088 1 P 0 
L 3.234 2.088 3.234 2.132 1 P 0 
L 3.11133317 1.5195 3.11133317 1.5505 1 P 0 ;0,1=412,2=0.000000
L 3.11133317 1.5505 3.12091654 1.5505 1 P 0 ;0,1=412,2=0.000000
L 3.12091654 1.5505 3.12398327 1.54894931 1 P 0 ;0,1=412,2=0.000000
L 3.12398327 1.54894931 3.1259002 1.54688307 1 P 0 ;0,1=412,2=0.000000
L 3.1259002 1.54688307 3.12666673 1.5427497 1 P 0 ;0,1=412,2=0.000000
L 3.12666673 1.5427497 3.1259002 1.53861634 1 P 0 ;0,1=412,2=0.000000
L 3.1259002 1.53861634 3.1236 1.53603356 1 P 0 ;0,1=412,2=0.000000
L 3.1236 1.53603356 3.12091654 1.53448287 1 P 0 ;0,1=412,2=0.000000
L 3.12091654 1.53448287 3.11133317 1.53448287 1 P 0 ;0,1=412,2=0.000000
L 3.12091654 1.53448287 3.12666673 1.5195 1 P 0 ;0,1=412,2=0.000000
L 3.14999961 1.5195 3.15268307 1.52001654 1 P 0 ;0,1=412,2=0.000000
L 3.15268307 1.52001654 3.1557498 1.52156614 1 P 0 ;0,1=412,2=0.000000
L 3.1557498 1.52156614 3.15766673 1.52414892 1 P 0 ;0,1=412,2=0.000000
L 3.15766673 1.52414892 3.15843327 1.52776673 1 P 0 ;0,1=412,2=0.000000
L 3.15843327 1.52776673 3.15766673 1.53138268 1 P 0 ;0,1=412,2=0.000000
L 3.15766673 1.53138268 3.15536654 1.53448287 1 P 0 ;0,1=412,2=0.000000
L 3.15536654 1.53448287 3.15191654 1.53603356 1 P 0 ;0,1=412,2=0.000000
L 3.15191654 1.53603356 3.14808337 1.53603356 1 P 0 ;0,1=412,2=0.000000
L 3.14808337 1.53603356 3.14578317 1.53706663 1 P 0 ;0,1=412,2=0.000000
L 3.14578317 1.53706663 3.14386614 1.53964941 1 P 0 ;0,1=412,2=0.000000
L 3.14386614 1.53964941 3.1430997 1.54326624 1 P 0 ;0,1=412,2=0.000000
L 3.1430997 1.54326624 3.1442501 1.54688307 1 P 0 ;0,1=412,2=0.000000
L 3.1442501 1.54688307 3.14693287 1.54946683 1 P 0 ;0,1=412,2=0.000000
L 3.14693287 1.54946683 3.14999961 1.5505 1 P 0 ;0,1=412,2=0.000000
L 3.14999961 1.5505 3.15306634 1.54946683 1 P 0 ;0,1=412,2=0.000000
L 3.15306634 1.54946683 3.1557498 1.54688307 1 P 0 ;0,1=412,2=0.000000
L 3.1557498 1.54688307 3.1569002 1.54326624 1 P 0 ;0,1=412,2=0.000000
L 3.1569002 1.54326624 3.15613307 1.53964941 1 P 0 ;0,1=412,2=0.000000
L 3.15613307 1.53964941 3.15421673 1.53706663 1 P 0 ;0,1=412,2=0.000000
L 3.15421673 1.53706663 3.15191654 1.53603356 1 P 0 ;0,1=412,2=0.000000
L 3.15191654 1.53603356 3.14808337 1.53603356 1 P 0 ;0,1=412,2=0.000000
L 3.14808337 1.53603356 3.14463337 1.53448287 1 P 0 ;0,1=412,2=0.000000
L 3.14463337 1.53448287 3.14233317 1.53138268 1 P 0 ;0,1=412,2=0.000000
L 3.14233317 1.53138268 3.14156663 1.52776673 1 P 0 ;0,1=412,2=0.000000
L 3.14156663 1.52776673 3.14233317 1.52414892 1 P 0 ;0,1=412,2=0.000000
L 3.14233317 1.52414892 3.1442501 1.52156614 1 P 0 ;0,1=412,2=0.000000
L 3.1442501 1.52156614 3.14731683 1.52001654 1 P 0 ;0,1=412,2=0.000000
L 3.14731683 1.52001654 3.14999961 1.5195 1 P 0 ;0,1=412,2=0.000000
L 3.17256663 1.52569961 3.17486614 1.52208278 1 P 0 ;0,1=412,2=0.000000
L 3.17486614 1.52208278 3.17793287 1.52001654 1 P 0 ;0,1=412,2=0.000000
L 3.17793287 1.52001654 3.18138356 1.5195 1 P 0 ;0,1=412,2=0.000000
L 3.18138356 1.5195 3.1844503 1.52001654 1 P 0 ;0,1=412,2=0.000000
L 3.1844503 1.52001654 3.18751703 1.52259931 1 P 0 ;0,1=412,2=0.000000
L 3.18751703 1.52259931 3.18943327 1.52569961 1 P 0 ;0,1=412,2=0.000000
L 3.18943327 1.52569961 3.18981654 1.5287999 1 P 0 ;0,1=412,2=0.000000
L 3.18981654 1.5287999 3.18905 1.53241575 1 P 0 ;0,1=412,2=0.000000
L 3.18905 1.53241575 3.18636654 1.53499951 1 P 0 ;0,1=412,2=0.000000
L 3.18636654 1.53499951 3.18368307 1.53603356 1 P 0 ;0,1=412,2=0.000000
L 3.18368307 1.53603356 3.18023307 1.53603356 1 P 0 ;0,1=412,2=0.000000
L 3.18368307 1.53603356 3.18598327 1.53758317 1 P 0 ;0,1=412,2=0.000000
L 3.18598327 1.53758317 3.1879002 1.54016594 1 P 0 ;0,1=412,2=0.000000
L 3.1879002 1.54016594 3.18866673 1.54326624 1 P 0 ;0,1=412,2=0.000000
L 3.18866673 1.54326624 3.1879002 1.54636654 1 P 0 ;0,1=412,2=0.000000
L 3.1879002 1.54636654 3.18598327 1.54894931 1 P 0 ;0,1=412,2=0.000000
L 3.18598327 1.54894931 3.18253327 1.5505 1 P 0 ;0,1=412,2=0.000000
L 3.18253327 1.5505 3.17908337 1.54998337 1 P 0 ;0,1=412,2=0.000000
L 3.17908337 1.54998337 3.17563337 1.54791624 1 P 0 ;0,1=412,2=0.000000
L 3.237 2.13 3.237 2.04 1 P 0 
L 3.237 2.04 3.281 2.04 1 P 0 
L 3.281 2.04 3.281 2.13 1 P 0 
L 3.281 2.13 3.237 2.13 1 P 0 
L 3.235 1.49583317 3.204 1.49583317 1 P 0 ;0,1=413,2=270.000000
L 3.204 1.49583317 3.204 1.50541654 1 P 0 ;0,1=413,2=270.000000
L 3.204 1.50541654 3.20555069 1.50848327 1 P 0 ;0,1=413,2=270.000000
L 3.20555069 1.50848327 3.20761693 1.5104002 1 P 0 ;0,1=413,2=270.000000
L 3.20761693 1.5104002 3.2117503 1.51116673 1 P 0 ;0,1=413,2=270.000000
L 3.2117503 1.51116673 3.21588366 1.5104002 1 P 0 ;0,1=413,2=270.000000
L 3.21588366 1.5104002 3.21846644 1.5081 1 P 0 ;0,1=413,2=270.000000
L 3.21846644 1.5081 3.22001713 1.50541654 1 P 0 ;0,1=413,2=270.000000
L 3.22001713 1.50541654 3.22001713 1.49583317 1 P 0 ;0,1=413,2=270.000000
L 3.22001713 1.50541654 3.235 1.51116673 1 P 0 ;0,1=413,2=270.000000
L 3.20916654 1.52721644 3.20606722 1.52951663 1 P 0 ;0,1=413,2=270.000000
L 3.20606722 1.52951663 3.20451663 1.5322001 1 P 0 ;0,1=413,2=270.000000
L 3.20451663 1.5322001 3.204 1.53526683 1 P 0 ;0,1=413,2=270.000000
L 3.204 1.53526683 3.20503317 1.5391 1 P 0 ;0,1=413,2=270.000000
L 3.20503317 1.5391 3.20761693 1.54178346 1 P 0 ;0,1=413,2=270.000000
L 3.20761693 1.54178346 3.21071624 1.54255 1 P 0 ;0,1=413,2=270.000000
L 3.21071624 1.54255 3.21381742 1.54216673 1 P 0 ;0,1=413,2=270.000000
L 3.21381742 1.54216673 3.2164002 1.54063307 1 P 0 ;0,1=413,2=270.000000
L 3.2164002 1.54063307 3.22156673 1.53296663 1 P 0 ;0,1=413,2=270.000000
L 3.22156673 1.53296663 3.22518356 1.52951663 1 P 0 ;0,1=413,2=270.000000
L 3.22518356 1.52951663 3.23035108 1.52721644 1 P 0 ;0,1=413,2=270.000000
L 3.23035108 1.52721644 3.235 1.5264499 1 P 0 ;0,1=413,2=270.000000
L 3.235 1.5264499 3.235 1.54255 1 P 0 ;0,1=413,2=270.000000
L 3.235 1.56473307 3.22828386 1.56549961 1 P 0 ;0,1=413,2=270.000000
L 3.22828386 1.56549961 3.22260079 1.5666501 1 P 0 ;0,1=413,2=270.000000
L 3.22260079 1.5666501 3.21743337 1.56818307 1 P 0 ;0,1=413,2=270.000000
L 3.21743337 1.56818307 3.2117503 1.5701 1 P 0 ;0,1=413,2=270.000000
L 3.2117503 1.5701 3.204 1.57316673 1 P 0 ;0,1=413,2=270.000000
L 3.204 1.57316673 3.204 1.55783317 1 P 0 ;0,1=413,2=270.000000
L 3.235 1.59573307 3.22828386 1.59649961 1 P 0 ;0,1=413,2=270.000000
L 3.22828386 1.59649961 3.22260079 1.5976501 1 P 0 ;0,1=413,2=270.000000
L 3.22260079 1.5976501 3.21743337 1.59918307 1 P 0 ;0,1=413,2=270.000000
L 3.21743337 1.59918307 3.2117503 1.6011 1 P 0 ;0,1=413,2=270.000000
L 3.2117503 1.6011 3.204 1.60416673 1 P 0 ;0,1=413,2=270.000000
L 3.204 1.60416673 3.204 1.58883317 1 P 0 ;0,1=413,2=270.000000
L 3.234 2.082 3.144 2.082 1 P 0 
L 3.144 2.082 3.144 2.038 1 P 0 
L 3.144 2.038 3.234 2.038 1 P 0 
L 3.234 2.038 3.234 2.082 1 P 0 
L 3.11133317 1.4795 3.11133317 1.5105 1 P 0 ;0,1=414,2=0.000000
L 3.11133317 1.5105 3.12091654 1.5105 1 P 0 ;0,1=414,2=0.000000
L 3.12091654 1.5105 3.12398327 1.50894931 1 P 0 ;0,1=414,2=0.000000
L 3.12398327 1.50894931 3.1259002 1.50688307 1 P 0 ;0,1=414,2=0.000000
L 3.1259002 1.50688307 3.12666673 1.5027497 1 P 0 ;0,1=414,2=0.000000
L 3.12666673 1.5027497 3.1259002 1.49861634 1 P 0 ;0,1=414,2=0.000000
L 3.1259002 1.49861634 3.1236 1.49603356 1 P 0 ;0,1=414,2=0.000000
L 3.1236 1.49603356 3.12091654 1.49448287 1 P 0 ;0,1=414,2=0.000000
L 3.12091654 1.49448287 3.11133317 1.49448287 1 P 0 ;0,1=414,2=0.000000
L 3.12091654 1.49448287 3.12666673 1.4795 1 P 0 ;0,1=414,2=0.000000
L 3.14999961 1.4795 3.15268307 1.48001654 1 P 0 ;0,1=414,2=0.000000
L 3.15268307 1.48001654 3.1557498 1.48156614 1 P 0 ;0,1=414,2=0.000000
L 3.1557498 1.48156614 3.15766673 1.48414892 1 P 0 ;0,1=414,2=0.000000
L 3.15766673 1.48414892 3.15843327 1.48776673 1 P 0 ;0,1=414,2=0.000000
L 3.15843327 1.48776673 3.15766673 1.49138268 1 P 0 ;0,1=414,2=0.000000
L 3.15766673 1.49138268 3.15536654 1.49448287 1 P 0 ;0,1=414,2=0.000000
L 3.15536654 1.49448287 3.15191654 1.49603356 1 P 0 ;0,1=414,2=0.000000
L 3.15191654 1.49603356 3.14808337 1.49603356 1 P 0 ;0,1=414,2=0.000000
L 3.14808337 1.49603356 3.14578317 1.49706663 1 P 0 ;0,1=414,2=0.000000
L 3.14578317 1.49706663 3.14386614 1.49964941 1 P 0 ;0,1=414,2=0.000000
L 3.14386614 1.49964941 3.1430997 1.50326624 1 P 0 ;0,1=414,2=0.000000
L 3.1430997 1.50326624 3.1442501 1.50688307 1 P 0 ;0,1=414,2=0.000000
L 3.1442501 1.50688307 3.14693287 1.50946683 1 P 0 ;0,1=414,2=0.000000
L 3.14693287 1.50946683 3.14999961 1.5105 1 P 0 ;0,1=414,2=0.000000
L 3.14999961 1.5105 3.15306634 1.50946683 1 P 0 ;0,1=414,2=0.000000
L 3.15306634 1.50946683 3.1557498 1.50688307 1 P 0 ;0,1=414,2=0.000000
L 3.1557498 1.50688307 3.1569002 1.50326624 1 P 0 ;0,1=414,2=0.000000
L 3.1569002 1.50326624 3.15613307 1.49964941 1 P 0 ;0,1=414,2=0.000000
L 3.15613307 1.49964941 3.15421673 1.49706663 1 P 0 ;0,1=414,2=0.000000
L 3.15421673 1.49706663 3.15191654 1.49603356 1 P 0 ;0,1=414,2=0.000000
L 3.15191654 1.49603356 3.14808337 1.49603356 1 P 0 ;0,1=414,2=0.000000
L 3.14808337 1.49603356 3.14463337 1.49448287 1 P 0 ;0,1=414,2=0.000000
L 3.14463337 1.49448287 3.14233317 1.49138268 1 P 0 ;0,1=414,2=0.000000
L 3.14233317 1.49138268 3.14156663 1.48776673 1 P 0 ;0,1=414,2=0.000000
L 3.14156663 1.48776673 3.14233317 1.48414892 1 P 0 ;0,1=414,2=0.000000
L 3.14233317 1.48414892 3.1442501 1.48156614 1 P 0 ;0,1=414,2=0.000000
L 3.1442501 1.48156614 3.14731683 1.48001654 1 P 0 ;0,1=414,2=0.000000
L 3.14731683 1.48001654 3.14999961 1.4795 1 P 0 ;0,1=414,2=0.000000
L 3.1856 1.4795 3.1856 1.5105 1 P 0 ;0,1=414,2=0.000000
L 3.1856 1.5105 3.17141624 1.48828327 1 P 0 ;0,1=414,2=0.000000
L 3.17141624 1.48828327 3.19058366 1.48828327 1 P 0 ;0,1=414,2=0.000000
L 3.234 2.037 3.144 2.037 1 P 0 
L 3.144 2.037 3.144 1.993 1 P 0 
L 3.144 1.993 3.234 1.993 1 P 0 
L 3.234 1.993 3.234 2.037 1 P 0 
L 3.11133317 1.415 3.11133317 1.446 1 P 0 ;0,1=415,2=0.000000
L 3.11133317 1.446 3.12091654 1.446 1 P 0 ;0,1=415,2=0.000000
L 3.12091654 1.446 3.12398327 1.44444931 1 P 0 ;0,1=415,2=0.000000
L 3.12398327 1.44444931 3.1259002 1.44238307 1 P 0 ;0,1=415,2=0.000000
L 3.1259002 1.44238307 3.12666673 1.4382497 1 P 0 ;0,1=415,2=0.000000
L 3.12666673 1.4382497 3.1259002 1.43411634 1 P 0 ;0,1=415,2=0.000000
L 3.1259002 1.43411634 3.1236 1.43153356 1 P 0 ;0,1=415,2=0.000000
L 3.1236 1.43153356 3.12091654 1.42998287 1 P 0 ;0,1=415,2=0.000000
L 3.12091654 1.42998287 3.11133317 1.42998287 1 P 0 ;0,1=415,2=0.000000
L 3.12091654 1.42998287 3.12666673 1.415 1 P 0 ;0,1=415,2=0.000000
L 3.14999961 1.415 3.15268307 1.41551654 1 P 0 ;0,1=415,2=0.000000
L 3.15268307 1.41551654 3.1557498 1.41706614 1 P 0 ;0,1=415,2=0.000000
L 3.1557498 1.41706614 3.15766673 1.41964892 1 P 0 ;0,1=415,2=0.000000
L 3.15766673 1.41964892 3.15843327 1.42326673 1 P 0 ;0,1=415,2=0.000000
L 3.15843327 1.42326673 3.15766673 1.42688268 1 P 0 ;0,1=415,2=0.000000
L 3.15766673 1.42688268 3.15536654 1.42998287 1 P 0 ;0,1=415,2=0.000000
L 3.15536654 1.42998287 3.15191654 1.43153356 1 P 0 ;0,1=415,2=0.000000
L 3.15191654 1.43153356 3.14808337 1.43153356 1 P 0 ;0,1=415,2=0.000000
L 3.14808337 1.43153356 3.14578317 1.43256663 1 P 0 ;0,1=415,2=0.000000
L 3.14578317 1.43256663 3.14386614 1.43514941 1 P 0 ;0,1=415,2=0.000000
L 3.14386614 1.43514941 3.1430997 1.43876624 1 P 0 ;0,1=415,2=0.000000
L 3.1430997 1.43876624 3.1442501 1.44238307 1 P 0 ;0,1=415,2=0.000000
L 3.1442501 1.44238307 3.14693287 1.44496683 1 P 0 ;0,1=415,2=0.000000
L 3.14693287 1.44496683 3.14999961 1.446 1 P 0 ;0,1=415,2=0.000000
L 3.14999961 1.446 3.15306634 1.44496683 1 P 0 ;0,1=415,2=0.000000
L 3.15306634 1.44496683 3.1557498 1.44238307 1 P 0 ;0,1=415,2=0.000000
L 3.1557498 1.44238307 3.1569002 1.43876624 1 P 0 ;0,1=415,2=0.000000
L 3.1569002 1.43876624 3.15613307 1.43514941 1 P 0 ;0,1=415,2=0.000000
L 3.15613307 1.43514941 3.15421673 1.43256663 1 P 0 ;0,1=415,2=0.000000
L 3.15421673 1.43256663 3.15191654 1.43153356 1 P 0 ;0,1=415,2=0.000000
L 3.15191654 1.43153356 3.14808337 1.43153356 1 P 0 ;0,1=415,2=0.000000
L 3.14808337 1.43153356 3.14463337 1.42998287 1 P 0 ;0,1=415,2=0.000000
L 3.14463337 1.42998287 3.14233317 1.42688268 1 P 0 ;0,1=415,2=0.000000
L 3.14233317 1.42688268 3.14156663 1.42326673 1 P 0 ;0,1=415,2=0.000000
L 3.14156663 1.42326673 3.14233317 1.41964892 1 P 0 ;0,1=415,2=0.000000
L 3.14233317 1.41964892 3.1442501 1.41706614 1 P 0 ;0,1=415,2=0.000000
L 3.1442501 1.41706614 3.14731683 1.41551654 1 P 0 ;0,1=415,2=0.000000
L 3.14731683 1.41551654 3.14999961 1.415 1 P 0 ;0,1=415,2=0.000000
L 3.17256663 1.41964892 3.17486614 1.41706614 1 P 0 ;0,1=415,2=0.000000
L 3.17486614 1.41706614 3.17754961 1.41551654 1 P 0 ;0,1=415,2=0.000000
L 3.17754961 1.41551654 3.18099961 1.415 1 P 0 ;0,1=415,2=0.000000
L 3.18099961 1.415 3.1844503 1.41603307 1 P 0 ;0,1=415,2=0.000000
L 3.1844503 1.41603307 3.18713307 1.41809931 1 P 0 ;0,1=415,2=0.000000
L 3.18713307 1.41809931 3.18905 1.42171614 1 P 0 ;0,1=415,2=0.000000
L 3.18905 1.42171614 3.18943327 1.42584951 1 P 0 ;0,1=415,2=0.000000
L 3.18943327 1.42584951 3.18866673 1.42998287 1 P 0 ;0,1=415,2=0.000000
L 3.18866673 1.42998287 3.1867498 1.43256663 1 P 0 ;0,1=415,2=0.000000
L 3.1867498 1.43256663 3.18406634 1.43463287 1 P 0 ;0,1=415,2=0.000000
L 3.18406634 1.43463287 3.18138356 1.43514941 1 P 0 ;0,1=415,2=0.000000
L 3.18138356 1.43514941 3.1787001 1.43463287 1 P 0 ;0,1=415,2=0.000000
L 3.1787001 1.43463287 3.1752501 1.43256663 1 P 0 ;0,1=415,2=0.000000
L 3.1752501 1.43256663 3.1763999 1.446 1 P 0 ;0,1=415,2=0.000000
L 3.1763999 1.446 3.1867498 1.446 1 P 0 ;0,1=415,2=0.000000
L 3.281 2.035 3.237 2.035 1 P 0 
L 3.237 2.035 3.237 1.945 1 P 0 
L 3.237 1.945 3.281 1.945 1 P 0 
L 3.281 1.945 3.281 2.035 1 P 0 
L 3.23 1.36583317 3.199 1.36583317 1 P 0 ;0,1=416,2=270.000000
L 3.199 1.36583317 3.199 1.37541654 1 P 0 ;0,1=416,2=270.000000
L 3.199 1.37541654 3.20055069 1.37848327 1 P 0 ;0,1=416,2=270.000000
L 3.20055069 1.37848327 3.20261693 1.3804002 1 P 0 ;0,1=416,2=270.000000
L 3.20261693 1.3804002 3.2067503 1.38116673 1 P 0 ;0,1=416,2=270.000000
L 3.2067503 1.38116673 3.21088366 1.3804002 1 P 0 ;0,1=416,2=270.000000
L 3.21088366 1.3804002 3.21346644 1.3781 1 P 0 ;0,1=416,2=270.000000
L 3.21346644 1.3781 3.21501713 1.37541654 1 P 0 ;0,1=416,2=270.000000
L 3.21501713 1.37541654 3.21501713 1.36583317 1 P 0 ;0,1=416,2=270.000000
L 3.21501713 1.37541654 3.23 1.38116673 1 P 0 ;0,1=416,2=270.000000
L 3.20416654 1.39721644 3.20106722 1.39951663 1 P 0 ;0,1=416,2=270.000000
L 3.20106722 1.39951663 3.19951663 1.4022001 1 P 0 ;0,1=416,2=270.000000
L 3.19951663 1.4022001 3.199 1.40526683 1 P 0 ;0,1=416,2=270.000000
L 3.199 1.40526683 3.20003317 1.4091 1 P 0 ;0,1=416,2=270.000000
L 3.20003317 1.4091 3.20261693 1.41178346 1 P 0 ;0,1=416,2=270.000000
L 3.20261693 1.41178346 3.20571624 1.41255 1 P 0 ;0,1=416,2=270.000000
L 3.20571624 1.41255 3.20881742 1.41216673 1 P 0 ;0,1=416,2=270.000000
L 3.20881742 1.41216673 3.2114002 1.41063307 1 P 0 ;0,1=416,2=270.000000
L 3.2114002 1.41063307 3.21656673 1.40296663 1 P 0 ;0,1=416,2=270.000000
L 3.21656673 1.40296663 3.22018356 1.39951663 1 P 0 ;0,1=416,2=270.000000
L 3.22018356 1.39951663 3.22535108 1.39721644 1 P 0 ;0,1=416,2=270.000000
L 3.22535108 1.39721644 3.23 1.3964499 1 P 0 ;0,1=416,2=270.000000
L 3.23 1.3964499 3.23 1.41255 1 P 0 ;0,1=416,2=270.000000
L 3.23 1.43473307 3.22328386 1.43549961 1 P 0 ;0,1=416,2=270.000000
L 3.22328386 1.43549961 3.21760079 1.4366501 1 P 0 ;0,1=416,2=270.000000
L 3.21760079 1.4366501 3.21243337 1.43818307 1 P 0 ;0,1=416,2=270.000000
L 3.21243337 1.43818307 3.2067503 1.4401 1 P 0 ;0,1=416,2=270.000000
L 3.2067503 1.4401 3.199 1.44316673 1 P 0 ;0,1=416,2=270.000000
L 3.199 1.44316673 3.199 1.42783317 1 P 0 ;0,1=416,2=270.000000
L 3.21708425 1.45921644 3.21346644 1.4618999 1 P 0 ;0,1=416,2=270.000000
L 3.21346644 1.4618999 3.2114002 1.4642001 1 P 0 ;0,1=416,2=270.000000
L 3.2114002 1.4642001 3.21036713 1.46726683 1 P 0 ;0,1=416,2=270.000000
L 3.21036713 1.46726683 3.2114002 1.4699503 1 P 0 ;0,1=416,2=270.000000
L 3.2114002 1.4699503 3.21346644 1.47186654 1 P 0 ;0,1=416,2=270.000000
L 3.21346644 1.47186654 3.21656673 1.4734002 1 P 0 ;0,1=416,2=270.000000
L 3.21656673 1.4734002 3.22018356 1.47378346 1 P 0 ;0,1=416,2=270.000000
L 3.22018356 1.47378346 3.22328386 1.4734002 1 P 0 ;0,1=416,2=270.000000
L 3.22328386 1.4734002 3.22638415 1.47186654 1 P 0 ;0,1=416,2=270.000000
L 3.22638415 1.47186654 3.22896693 1.46956634 1 P 0 ;0,1=416,2=270.000000
L 3.22896693 1.46956634 3.23 1.46688356 1 P 0 ;0,1=416,2=270.000000
L 3.23 1.46688356 3.22896693 1.46381683 1 P 0 ;0,1=416,2=270.000000
L 3.22896693 1.46381683 3.22586762 1.46113337 1 P 0 ;0,1=416,2=270.000000
L 3.22586762 1.46113337 3.22121673 1.4595997 1 P 0 ;0,1=416,2=270.000000
L 3.22121673 1.4595997 3.2160502 1.45921644 1 P 0 ;0,1=416,2=270.000000
L 3.2160502 1.45921644 3.20933406 1.45998287 1 P 0 ;0,1=416,2=270.000000
L 3.20933406 1.45998287 3.20571624 1.46113337 1 P 0 ;0,1=416,2=270.000000
L 3.20571624 1.46113337 3.2021003 1.46304961 1 P 0 ;0,1=416,2=270.000000
L 3.2021003 1.46304961 3.19951663 1.46573307 1 P 0 ;0,1=416,2=270.000000
L 3.19951663 1.46573307 3.199 1.46841654 1 P 0 ;0,1=416,2=270.000000
L 3.199 1.46841654 3.20003317 1.4711 1 P 0 ;0,1=416,2=270.000000
L 3.20003317 1.4711 3.20261693 1.47301703 1 P 0 ;0,1=416,2=270.000000
L 3.234 1.987 3.144 1.987 1 P 0 
L 3.144 1.987 3.144 1.943 1 P 0 
L 3.144 1.943 3.234 1.943 1 P 0 
L 3.234 1.943 3.234 1.987 1 P 0 
L 3.11033317 1.3745 3.11033317 1.4055 1 P 0 ;0,1=417,2=0.000000
L 3.11033317 1.4055 3.11991654 1.4055 1 P 0 ;0,1=417,2=0.000000
L 3.11991654 1.4055 3.12298327 1.40394931 1 P 0 ;0,1=417,2=0.000000
L 3.12298327 1.40394931 3.1249002 1.40188307 1 P 0 ;0,1=417,2=0.000000
L 3.1249002 1.40188307 3.12566673 1.3977497 1 P 0 ;0,1=417,2=0.000000
L 3.12566673 1.3977497 3.1249002 1.39361634 1 P 0 ;0,1=417,2=0.000000
L 3.1249002 1.39361634 3.1226 1.39103356 1 P 0 ;0,1=417,2=0.000000
L 3.1226 1.39103356 3.11991654 1.38948287 1 P 0 ;0,1=417,2=0.000000
L 3.11991654 1.38948287 3.11033317 1.38948287 1 P 0 ;0,1=417,2=0.000000
L 3.11991654 1.38948287 3.12566673 1.3745 1 P 0 ;0,1=417,2=0.000000
L 3.14899961 1.3745 3.15168307 1.37501654 1 P 0 ;0,1=417,2=0.000000
L 3.15168307 1.37501654 3.1547498 1.37656614 1 P 0 ;0,1=417,2=0.000000
L 3.1547498 1.37656614 3.15666673 1.37914892 1 P 0 ;0,1=417,2=0.000000
L 3.15666673 1.37914892 3.15743327 1.38276673 1 P 0 ;0,1=417,2=0.000000
L 3.15743327 1.38276673 3.15666673 1.38638268 1 P 0 ;0,1=417,2=0.000000
L 3.15666673 1.38638268 3.15436654 1.38948287 1 P 0 ;0,1=417,2=0.000000
L 3.15436654 1.38948287 3.15091654 1.39103356 1 P 0 ;0,1=417,2=0.000000
L 3.15091654 1.39103356 3.14708337 1.39103356 1 P 0 ;0,1=417,2=0.000000
L 3.14708337 1.39103356 3.14478317 1.39206663 1 P 0 ;0,1=417,2=0.000000
L 3.14478317 1.39206663 3.14286614 1.39464941 1 P 0 ;0,1=417,2=0.000000
L 3.14286614 1.39464941 3.1420997 1.39826624 1 P 0 ;0,1=417,2=0.000000
L 3.1420997 1.39826624 3.1432501 1.40188307 1 P 0 ;0,1=417,2=0.000000
L 3.1432501 1.40188307 3.14593287 1.40446683 1 P 0 ;0,1=417,2=0.000000
L 3.14593287 1.40446683 3.14899961 1.4055 1 P 0 ;0,1=417,2=0.000000
L 3.14899961 1.4055 3.15206634 1.40446683 1 P 0 ;0,1=417,2=0.000000
L 3.15206634 1.40446683 3.1547498 1.40188307 1 P 0 ;0,1=417,2=0.000000
L 3.1547498 1.40188307 3.1559002 1.39826624 1 P 0 ;0,1=417,2=0.000000
L 3.1559002 1.39826624 3.15513307 1.39464941 1 P 0 ;0,1=417,2=0.000000
L 3.15513307 1.39464941 3.15321673 1.39206663 1 P 0 ;0,1=417,2=0.000000
L 3.15321673 1.39206663 3.15091654 1.39103356 1 P 0 ;0,1=417,2=0.000000
L 3.15091654 1.39103356 3.14708337 1.39103356 1 P 0 ;0,1=417,2=0.000000
L 3.14708337 1.39103356 3.14363337 1.38948287 1 P 0 ;0,1=417,2=0.000000
L 3.14363337 1.38948287 3.14133317 1.38638268 1 P 0 ;0,1=417,2=0.000000
L 3.14133317 1.38638268 3.14056663 1.38276673 1 P 0 ;0,1=417,2=0.000000
L 3.14056663 1.38276673 3.14133317 1.37914892 1 P 0 ;0,1=417,2=0.000000
L 3.14133317 1.37914892 3.1432501 1.37656614 1 P 0 ;0,1=417,2=0.000000
L 3.1432501 1.37656614 3.14631683 1.37501654 1 P 0 ;0,1=417,2=0.000000
L 3.14631683 1.37501654 3.14899961 1.3745 1 P 0 ;0,1=417,2=0.000000
L 3.17271644 1.38741575 3.1753999 1.39103356 1 P 0 ;0,1=417,2=0.000000
L 3.1753999 1.39103356 3.1777001 1.3930998 1 P 0 ;0,1=417,2=0.000000
L 3.1777001 1.3930998 3.18076683 1.39413287 1 P 0 ;0,1=417,2=0.000000
L 3.18076683 1.39413287 3.1834503 1.3930998 1 P 0 ;0,1=417,2=0.000000
L 3.1834503 1.3930998 3.18536654 1.39103356 1 P 0 ;0,1=417,2=0.000000
L 3.18536654 1.39103356 3.1869002 1.38793327 1 P 0 ;0,1=417,2=0.000000
L 3.1869002 1.38793327 3.18728346 1.38431644 1 P 0 ;0,1=417,2=0.000000
L 3.18728346 1.38431644 3.1869002 1.38121614 1 P 0 ;0,1=417,2=0.000000
L 3.1869002 1.38121614 3.18536654 1.37811585 1 P 0 ;0,1=417,2=0.000000
L 3.18536654 1.37811585 3.18306634 1.37553307 1 P 0 ;0,1=417,2=0.000000
L 3.18306634 1.37553307 3.18038356 1.3745 1 P 0 ;0,1=417,2=0.000000
L 3.18038356 1.3745 3.17731683 1.37553307 1 P 0 ;0,1=417,2=0.000000
L 3.17731683 1.37553307 3.17463337 1.37863238 1 P 0 ;0,1=417,2=0.000000
L 3.17463337 1.37863238 3.1730997 1.38328327 1 P 0 ;0,1=417,2=0.000000
L 3.1730997 1.38328327 3.17271644 1.3884498 1 P 0 ;0,1=417,2=0.000000
L 3.17271644 1.3884498 3.17348287 1.39516594 1 P 0 ;0,1=417,2=0.000000
L 3.17348287 1.39516594 3.17463337 1.39878376 1 P 0 ;0,1=417,2=0.000000
L 3.17463337 1.39878376 3.17654961 1.4023997 1 P 0 ;0,1=417,2=0.000000
L 3.17654961 1.4023997 3.17923307 1.40498337 1 P 0 ;0,1=417,2=0.000000
L 3.17923307 1.40498337 3.18191654 1.4055 1 P 0 ;0,1=417,2=0.000000
L 3.18191654 1.4055 3.1846 1.40446683 1 P 0 ;0,1=417,2=0.000000
L 3.1846 1.40446683 3.18651703 1.40188307 1 P 0 ;0,1=417,2=0.000000
L 3.32 2.143 3.32 2.187 1 P 0 
L 3.32 2.187 3.23 2.187 1 P 0 
L 3.23 2.143 3.32 2.143 1 P 0 
L 3.23 2.187 3.23 2.143 1 P 0 
L 2.85083317 2.8845 2.85083317 2.9155 1 P 0 ;0,1=418,2=0.000000
L 2.85083317 2.9155 2.86041654 2.9155 1 P 0 ;0,1=418,2=0.000000
L 2.86041654 2.9155 2.86348327 2.91394931 1 P 0 ;0,1=418,2=0.000000
L 2.86348327 2.91394931 2.8654002 2.91188307 1 P 0 ;0,1=418,2=0.000000
L 2.8654002 2.91188307 2.86616673 2.9077497 1 P 0 ;0,1=418,2=0.000000
L 2.86616673 2.9077497 2.8654002 2.90361634 1 P 0 ;0,1=418,2=0.000000
L 2.8654002 2.90361634 2.8631 2.90103356 1 P 0 ;0,1=418,2=0.000000
L 2.8631 2.90103356 2.86041654 2.89948287 1 P 0 ;0,1=418,2=0.000000
L 2.86041654 2.89948287 2.85083317 2.89948287 1 P 0 ;0,1=418,2=0.000000
L 2.86041654 2.89948287 2.86616673 2.8845 1 P 0 ;0,1=418,2=0.000000
L 2.88221644 2.91033346 2.88451663 2.91343278 1 P 0 ;0,1=418,2=0.000000
L 2.88451663 2.91343278 2.8872001 2.91498337 1 P 0 ;0,1=418,2=0.000000
L 2.8872001 2.91498337 2.89026683 2.9155 1 P 0 ;0,1=418,2=0.000000
L 2.89026683 2.9155 2.8941 2.91446683 1 P 0 ;0,1=418,2=0.000000
L 2.8941 2.91446683 2.89678346 2.91188307 1 P 0 ;0,1=418,2=0.000000
L 2.89678346 2.91188307 2.89755 2.90878376 1 P 0 ;0,1=418,2=0.000000
L 2.89755 2.90878376 2.89716673 2.90568258 1 P 0 ;0,1=418,2=0.000000
L 2.89716673 2.90568258 2.89563307 2.9030998 1 P 0 ;0,1=418,2=0.000000
L 2.89563307 2.9030998 2.88796663 2.89793327 1 P 0 ;0,1=418,2=0.000000
L 2.88796663 2.89793327 2.88451663 2.89431644 1 P 0 ;0,1=418,2=0.000000
L 2.88451663 2.89431644 2.88221644 2.88914892 1 P 0 ;0,1=418,2=0.000000
L 2.88221644 2.88914892 2.8814499 2.8845 1 P 0 ;0,1=418,2=0.000000
L 2.8814499 2.8845 2.89755 2.8845 1 P 0 ;0,1=418,2=0.000000
L 2.91398287 2.88811585 2.91666634 2.88553307 1 P 0 ;0,1=418,2=0.000000
L 2.91666634 2.88553307 2.91973307 2.8845 1 P 0 ;0,1=418,2=0.000000
L 2.91973307 2.8845 2.9227998 2.88553307 1 P 0 ;0,1=418,2=0.000000
L 2.9227998 2.88553307 2.92548327 2.88863238 1 P 0 ;0,1=418,2=0.000000
L 2.92548327 2.88863238 2.9274002 2.89328327 1 P 0 ;0,1=418,2=0.000000
L 2.9274002 2.89328327 2.92816673 2.89793327 1 P 0 ;0,1=418,2=0.000000
L 2.92816673 2.89793327 2.92816673 2.90361634 1 P 0 ;0,1=418,2=0.000000
L 2.92816673 2.90361634 2.9274002 2.90826624 1 P 0 ;0,1=418,2=0.000000
L 2.9274002 2.90826624 2.92548327 2.9123997 1 P 0 ;0,1=418,2=0.000000
L 2.92548327 2.9123997 2.92318307 2.91446683 1 P 0 ;0,1=418,2=0.000000
L 2.92318307 2.91446683 2.92049961 2.9155 1 P 0 ;0,1=418,2=0.000000
L 2.92049961 2.9155 2.91743287 2.91446683 1 P 0 ;0,1=418,2=0.000000
L 2.91743287 2.91446683 2.91513337 2.9123997 1 P 0 ;0,1=418,2=0.000000
L 2.91513337 2.9123997 2.9135997 2.9093003 1 P 0 ;0,1=418,2=0.000000
L 2.9135997 2.9093003 2.91283317 2.90516594 1 P 0 ;0,1=418,2=0.000000
L 2.91283317 2.90516594 2.9135997 2.9015501 1 P 0 ;0,1=418,2=0.000000
L 2.9135997 2.9015501 2.91551663 2.89793327 1 P 0 ;0,1=418,2=0.000000
L 2.91551663 2.89793327 2.91781683 2.89586604 1 P 0 ;0,1=418,2=0.000000
L 2.91781683 2.89586604 2.92049961 2.89534951 1 P 0 ;0,1=418,2=0.000000
L 2.92049961 2.89534951 2.92356634 2.89638268 1 P 0 ;0,1=418,2=0.000000
L 2.92356634 2.89638268 2.92586654 2.89896634 1 P 0 ;0,1=418,2=0.000000
L 2.92586654 2.89896634 2.92816673 2.90361634 1 P 0 ;0,1=418,2=0.000000
L 2.95149961 2.9155 2.94843287 2.91446683 1 P 0 ;0,1=418,2=0.000000
L 2.94843287 2.91446683 2.94613337 2.91188307 1 P 0 ;0,1=418,2=0.000000
L 2.94613337 2.91188307 2.9445997 2.90878376 1 P 0 ;0,1=418,2=0.000000
L 2.9445997 2.90878376 2.9434499 2.90464941 1 P 0 ;0,1=418,2=0.000000
L 2.9434499 2.90464941 2.94306663 2.89999951 1 P 0 ;0,1=418,2=0.000000
L 2.94306663 2.89999951 2.9434499 2.89534951 1 P 0 ;0,1=418,2=0.000000
L 2.9434499 2.89534951 2.9445997 2.89121614 1 P 0 ;0,1=418,2=0.000000
L 2.9445997 2.89121614 2.94613337 2.88811585 1 P 0 ;0,1=418,2=0.000000
L 2.94613337 2.88811585 2.94843287 2.88553307 1 P 0 ;0,1=418,2=0.000000
L 2.94843287 2.88553307 2.95149961 2.8845 1 P 0 ;0,1=418,2=0.000000
L 2.95149961 2.8845 2.95456634 2.88553307 1 P 0 ;0,1=418,2=0.000000
L 2.95456634 2.88553307 2.95686654 2.88811585 1 P 0 ;0,1=418,2=0.000000
L 2.95686654 2.88811585 2.9584002 2.89121614 1 P 0 ;0,1=418,2=0.000000
L 2.9584002 2.89121614 2.95955 2.89534951 1 P 0 ;0,1=418,2=0.000000
L 2.95955 2.89534951 2.95993327 2.89999951 1 P 0 ;0,1=418,2=0.000000
L 2.95993327 2.89999951 2.95955 2.90464941 1 P 0 ;0,1=418,2=0.000000
L 2.95955 2.90464941 2.9584002 2.90878376 1 P 0 ;0,1=418,2=0.000000
L 2.9584002 2.90878376 2.95686654 2.91188307 1 P 0 ;0,1=418,2=0.000000
L 2.95686654 2.91188307 2.95456634 2.91446683 1 P 0 ;0,1=418,2=0.000000
L 2.95456634 2.91446683 2.95149961 2.9155 1 P 0 ;0,1=418,2=0.000000
L 5.025 1.357 4.935 1.357 1 P 0 
L 4.935 1.357 4.935 1.313 1 P 0 
L 4.935 1.313 5.025 1.313 1 P 0 
L 5.025 1.313 5.025 1.357 1 P 0 
L 5.04083317 1.2645 5.04083317 1.2955 1 P 0 ;0,1=419,2=0.000000
L 5.04083317 1.2955 5.05041654 1.2955 1 P 0 ;0,1=419,2=0.000000
L 5.05041654 1.2955 5.05348327 1.29394931 1 P 0 ;0,1=419,2=0.000000
L 5.05348327 1.29394931 5.0554002 1.29188307 1 P 0 ;0,1=419,2=0.000000
L 5.0554002 1.29188307 5.05616673 1.2877497 1 P 0 ;0,1=419,2=0.000000
L 5.05616673 1.2877497 5.0554002 1.28361634 1 P 0 ;0,1=419,2=0.000000
L 5.0554002 1.28361634 5.0531 1.28103356 1 P 0 ;0,1=419,2=0.000000
L 5.0531 1.28103356 5.05041654 1.27948287 1 P 0 ;0,1=419,2=0.000000
L 5.05041654 1.27948287 5.04083317 1.27948287 1 P 0 ;0,1=419,2=0.000000
L 5.05041654 1.27948287 5.05616673 1.2645 1 P 0 ;0,1=419,2=0.000000
L 5.07949961 1.2645 5.07949961 1.2955 1 P 0 ;0,1=419,2=0.000000
L 5.07949961 1.2955 5.0748999 1.2893003 1 P 0 ;0,1=419,2=0.000000
L 5.0748999 1.2645 5.08409931 1.2645 1 P 0 ;0,1=419,2=0.000000
L 5.10398287 1.26811585 5.10666634 1.26553307 1 P 0 ;0,1=419,2=0.000000
L 5.10666634 1.26553307 5.10973307 1.2645 1 P 0 ;0,1=419,2=0.000000
L 5.10973307 1.2645 5.1127998 1.26553307 1 P 0 ;0,1=419,2=0.000000
L 5.1127998 1.26553307 5.11548327 1.26863238 1 P 0 ;0,1=419,2=0.000000
L 5.11548327 1.26863238 5.1174002 1.27328327 1 P 0 ;0,1=419,2=0.000000
L 5.1174002 1.27328327 5.11816673 1.27793327 1 P 0 ;0,1=419,2=0.000000
L 5.11816673 1.27793327 5.11816673 1.28361634 1 P 0 ;0,1=419,2=0.000000
L 5.11816673 1.28361634 5.1174002 1.28826624 1 P 0 ;0,1=419,2=0.000000
L 5.1174002 1.28826624 5.11548327 1.2923997 1 P 0 ;0,1=419,2=0.000000
L 5.11548327 1.2923997 5.11318307 1.29446683 1 P 0 ;0,1=419,2=0.000000
L 5.11318307 1.29446683 5.11049961 1.2955 1 P 0 ;0,1=419,2=0.000000
L 5.11049961 1.2955 5.10743287 1.29446683 1 P 0 ;0,1=419,2=0.000000
L 5.10743287 1.29446683 5.10513337 1.2923997 1 P 0 ;0,1=419,2=0.000000
L 5.10513337 1.2923997 5.1035997 1.2893003 1 P 0 ;0,1=419,2=0.000000
L 5.1035997 1.2893003 5.10283317 1.28516594 1 P 0 ;0,1=419,2=0.000000
L 5.10283317 1.28516594 5.1035997 1.2815501 1 P 0 ;0,1=419,2=0.000000
L 5.1035997 1.2815501 5.10551663 1.27793327 1 P 0 ;0,1=419,2=0.000000
L 5.10551663 1.27793327 5.10781683 1.27586604 1 P 0 ;0,1=419,2=0.000000
L 5.10781683 1.27586604 5.11049961 1.27534951 1 P 0 ;0,1=419,2=0.000000
L 5.11049961 1.27534951 5.11356634 1.27638268 1 P 0 ;0,1=419,2=0.000000
L 5.11356634 1.27638268 5.11586654 1.27896634 1 P 0 ;0,1=419,2=0.000000
L 5.11586654 1.27896634 5.11816673 1.28361634 1 P 0 ;0,1=419,2=0.000000
L 5.1461 1.2645 5.1461 1.2955 1 P 0 ;0,1=419,2=0.000000
L 5.1461 1.2955 5.13191624 1.27328327 1 P 0 ;0,1=419,2=0.000000
L 5.13191624 1.27328327 5.15108366 1.27328327 1 P 0 ;0,1=419,2=0.000000
L 5.025 1.452 4.935 1.452 1 P 0 
L 4.935 1.408 5.025 1.408 1 P 0 
L 5.025 1.408 5.025 1.452 1 P 0 
L 4.935 1.452 4.935 1.408 1 P 0 
L 5.04083317 1.3545 5.04083317 1.3855 1 P 0 ;0,1=420,2=0.000000
L 5.04083317 1.3855 5.05041654 1.3855 1 P 0 ;0,1=420,2=0.000000
L 5.05041654 1.3855 5.05348327 1.38394931 1 P 0 ;0,1=420,2=0.000000
L 5.05348327 1.38394931 5.0554002 1.38188307 1 P 0 ;0,1=420,2=0.000000
L 5.0554002 1.38188307 5.05616673 1.3777497 1 P 0 ;0,1=420,2=0.000000
L 5.05616673 1.3777497 5.0554002 1.37361634 1 P 0 ;0,1=420,2=0.000000
L 5.0554002 1.37361634 5.0531 1.37103356 1 P 0 ;0,1=420,2=0.000000
L 5.0531 1.37103356 5.05041654 1.36948287 1 P 0 ;0,1=420,2=0.000000
L 5.05041654 1.36948287 5.04083317 1.36948287 1 P 0 ;0,1=420,2=0.000000
L 5.05041654 1.36948287 5.05616673 1.3545 1 P 0 ;0,1=420,2=0.000000
L 5.07221644 1.38033346 5.07451663 1.38343278 1 P 0 ;0,1=420,2=0.000000
L 5.07451663 1.38343278 5.0772001 1.38498337 1 P 0 ;0,1=420,2=0.000000
L 5.0772001 1.38498337 5.08026683 1.3855 1 P 0 ;0,1=420,2=0.000000
L 5.08026683 1.3855 5.0841 1.38446683 1 P 0 ;0,1=420,2=0.000000
L 5.0841 1.38446683 5.08678346 1.38188307 1 P 0 ;0,1=420,2=0.000000
L 5.08678346 1.38188307 5.08755 1.37878376 1 P 0 ;0,1=420,2=0.000000
L 5.08755 1.37878376 5.08716673 1.37568258 1 P 0 ;0,1=420,2=0.000000
L 5.08716673 1.37568258 5.08563307 1.3730998 1 P 0 ;0,1=420,2=0.000000
L 5.08563307 1.3730998 5.07796663 1.36793327 1 P 0 ;0,1=420,2=0.000000
L 5.07796663 1.36793327 5.07451663 1.36431644 1 P 0 ;0,1=420,2=0.000000
L 5.07451663 1.36431644 5.07221644 1.35914892 1 P 0 ;0,1=420,2=0.000000
L 5.07221644 1.35914892 5.0714499 1.3545 1 P 0 ;0,1=420,2=0.000000
L 5.0714499 1.3545 5.08755 1.3545 1 P 0 ;0,1=420,2=0.000000
L 5.10321644 1.38033346 5.10551663 1.38343278 1 P 0 ;0,1=420,2=0.000000
L 5.10551663 1.38343278 5.1082001 1.38498337 1 P 0 ;0,1=420,2=0.000000
L 5.1082001 1.38498337 5.11126683 1.3855 1 P 0 ;0,1=420,2=0.000000
L 5.11126683 1.3855 5.1151 1.38446683 1 P 0 ;0,1=420,2=0.000000
L 5.1151 1.38446683 5.11778346 1.38188307 1 P 0 ;0,1=420,2=0.000000
L 5.11778346 1.38188307 5.11855 1.37878376 1 P 0 ;0,1=420,2=0.000000
L 5.11855 1.37878376 5.11816673 1.37568258 1 P 0 ;0,1=420,2=0.000000
L 5.11816673 1.37568258 5.11663307 1.3730998 1 P 0 ;0,1=420,2=0.000000
L 5.11663307 1.3730998 5.10896663 1.36793327 1 P 0 ;0,1=420,2=0.000000
L 5.10896663 1.36793327 5.10551663 1.36431644 1 P 0 ;0,1=420,2=0.000000
L 5.10551663 1.36431644 5.10321644 1.35914892 1 P 0 ;0,1=420,2=0.000000
L 5.10321644 1.35914892 5.1024499 1.3545 1 P 0 ;0,1=420,2=0.000000
L 5.1024499 1.3545 5.11855 1.3545 1 P 0 ;0,1=420,2=0.000000
L 5.13421644 1.38033346 5.13651663 1.38343278 1 P 0 ;0,1=420,2=0.000000
L 5.13651663 1.38343278 5.1392001 1.38498337 1 P 0 ;0,1=420,2=0.000000
L 5.1392001 1.38498337 5.14226683 1.3855 1 P 0 ;0,1=420,2=0.000000
L 5.14226683 1.3855 5.1461 1.38446683 1 P 0 ;0,1=420,2=0.000000
L 5.1461 1.38446683 5.14878346 1.38188307 1 P 0 ;0,1=420,2=0.000000
L 5.14878346 1.38188307 5.14955 1.37878376 1 P 0 ;0,1=420,2=0.000000
L 5.14955 1.37878376 5.14916673 1.37568258 1 P 0 ;0,1=420,2=0.000000
L 5.14916673 1.37568258 5.14763307 1.3730998 1 P 0 ;0,1=420,2=0.000000
L 5.14763307 1.3730998 5.13996663 1.36793327 1 P 0 ;0,1=420,2=0.000000
L 5.13996663 1.36793327 5.13651663 1.36431644 1 P 0 ;0,1=420,2=0.000000
L 5.13651663 1.36431644 5.13421644 1.35914892 1 P 0 ;0,1=420,2=0.000000
L 5.13421644 1.35914892 5.1334499 1.3545 1 P 0 ;0,1=420,2=0.000000
L 5.1334499 1.3545 5.14955 1.3545 1 P 0 ;0,1=420,2=0.000000
L 5.025 1.407 4.935 1.407 1 P 0 
L 4.935 1.407 4.935 1.363 1 P 0 
L 4.935 1.363 5.025 1.363 1 P 0 
L 5.025 1.363 5.025 1.407 1 P 0 
L 5.04083317 1.3095 5.04083317 1.3405 1 P 0 ;0,1=421,2=0.000000
L 5.04083317 1.3405 5.05041654 1.3405 1 P 0 ;0,1=421,2=0.000000
L 5.05041654 1.3405 5.05348327 1.33894931 1 P 0 ;0,1=421,2=0.000000
L 5.05348327 1.33894931 5.0554002 1.33688307 1 P 0 ;0,1=421,2=0.000000
L 5.0554002 1.33688307 5.05616673 1.3327497 1 P 0 ;0,1=421,2=0.000000
L 5.05616673 1.3327497 5.0554002 1.32861634 1 P 0 ;0,1=421,2=0.000000
L 5.0554002 1.32861634 5.0531 1.32603356 1 P 0 ;0,1=421,2=0.000000
L 5.0531 1.32603356 5.05041654 1.32448287 1 P 0 ;0,1=421,2=0.000000
L 5.05041654 1.32448287 5.04083317 1.32448287 1 P 0 ;0,1=421,2=0.000000
L 5.05041654 1.32448287 5.05616673 1.3095 1 P 0 ;0,1=421,2=0.000000
L 5.07221644 1.33533346 5.07451663 1.33843278 1 P 0 ;0,1=421,2=0.000000
L 5.07451663 1.33843278 5.0772001 1.33998337 1 P 0 ;0,1=421,2=0.000000
L 5.0772001 1.33998337 5.08026683 1.3405 1 P 0 ;0,1=421,2=0.000000
L 5.08026683 1.3405 5.0841 1.33946683 1 P 0 ;0,1=421,2=0.000000
L 5.0841 1.33946683 5.08678346 1.33688307 1 P 0 ;0,1=421,2=0.000000
L 5.08678346 1.33688307 5.08755 1.33378376 1 P 0 ;0,1=421,2=0.000000
L 5.08755 1.33378376 5.08716673 1.33068258 1 P 0 ;0,1=421,2=0.000000
L 5.08716673 1.33068258 5.08563307 1.3280998 1 P 0 ;0,1=421,2=0.000000
L 5.08563307 1.3280998 5.07796663 1.32293327 1 P 0 ;0,1=421,2=0.000000
L 5.07796663 1.32293327 5.07451663 1.31931644 1 P 0 ;0,1=421,2=0.000000
L 5.07451663 1.31931644 5.07221644 1.31414892 1 P 0 ;0,1=421,2=0.000000
L 5.07221644 1.31414892 5.0714499 1.3095 1 P 0 ;0,1=421,2=0.000000
L 5.0714499 1.3095 5.08755 1.3095 1 P 0 ;0,1=421,2=0.000000
L 5.10321644 1.33533346 5.10551663 1.33843278 1 P 0 ;0,1=421,2=0.000000
L 5.10551663 1.33843278 5.1082001 1.33998337 1 P 0 ;0,1=421,2=0.000000
L 5.1082001 1.33998337 5.11126683 1.3405 1 P 0 ;0,1=421,2=0.000000
L 5.11126683 1.3405 5.1151 1.33946683 1 P 0 ;0,1=421,2=0.000000
L 5.1151 1.33946683 5.11778346 1.33688307 1 P 0 ;0,1=421,2=0.000000
L 5.11778346 1.33688307 5.11855 1.33378376 1 P 0 ;0,1=421,2=0.000000
L 5.11855 1.33378376 5.11816673 1.33068258 1 P 0 ;0,1=421,2=0.000000
L 5.11816673 1.33068258 5.11663307 1.3280998 1 P 0 ;0,1=421,2=0.000000
L 5.11663307 1.3280998 5.10896663 1.32293327 1 P 0 ;0,1=421,2=0.000000
L 5.10896663 1.32293327 5.10551663 1.31931644 1 P 0 ;0,1=421,2=0.000000
L 5.10551663 1.31931644 5.10321644 1.31414892 1 P 0 ;0,1=421,2=0.000000
L 5.10321644 1.31414892 5.1024499 1.3095 1 P 0 ;0,1=421,2=0.000000
L 5.1024499 1.3095 5.11855 1.3095 1 P 0 ;0,1=421,2=0.000000
L 5.14149961 1.3095 5.14149961 1.3405 1 P 0 ;0,1=421,2=0.000000
L 5.14149961 1.3405 5.1368999 1.3343003 1 P 0 ;0,1=421,2=0.000000
L 5.1368999 1.3095 5.14609931 1.3095 1 P 0 ;0,1=421,2=0.000000
L 4.394 0.951 4.484 0.951 1 P 0 
L 4.484 0.951 4.484 0.995 1 P 0 
L 4.484 0.995 4.394 0.995 1 P 0 
L 4.394 0.995 4.394 0.951 1 P 0 
L 4.37583317 0.6195 4.37583317 0.6505 1 P 0 ;0,1=422,2=0.000000
L 4.37583317 0.6505 4.38541654 0.6505 1 P 0 ;0,1=422,2=0.000000
L 4.38541654 0.6505 4.38848327 0.64894931 1 P 0 ;0,1=422,2=0.000000
L 4.38848327 0.64894931 4.3904002 0.64688307 1 P 0 ;0,1=422,2=0.000000
L 4.3904002 0.64688307 4.39116673 0.6427497 1 P 0 ;0,1=422,2=0.000000
L 4.39116673 0.6427497 4.3904002 0.63861634 1 P 0 ;0,1=422,2=0.000000
L 4.3904002 0.63861634 4.3881 0.63603356 1 P 0 ;0,1=422,2=0.000000
L 4.3881 0.63603356 4.38541654 0.63448287 1 P 0 ;0,1=422,2=0.000000
L 4.38541654 0.63448287 4.37583317 0.63448287 1 P 0 ;0,1=422,2=0.000000
L 4.38541654 0.63448287 4.39116673 0.6195 1 P 0 ;0,1=422,2=0.000000
L 4.40721644 0.64533346 4.40951663 0.64843278 1 P 0 ;0,1=422,2=0.000000
L 4.40951663 0.64843278 4.4122001 0.64998337 1 P 0 ;0,1=422,2=0.000000
L 4.4122001 0.64998337 4.41526683 0.6505 1 P 0 ;0,1=422,2=0.000000
L 4.41526683 0.6505 4.4191 0.64946683 1 P 0 ;0,1=422,2=0.000000
L 4.4191 0.64946683 4.42178346 0.64688307 1 P 0 ;0,1=422,2=0.000000
L 4.42178346 0.64688307 4.42255 0.64378376 1 P 0 ;0,1=422,2=0.000000
L 4.42255 0.64378376 4.42216673 0.64068258 1 P 0 ;0,1=422,2=0.000000
L 4.42216673 0.64068258 4.42063307 0.6380998 1 P 0 ;0,1=422,2=0.000000
L 4.42063307 0.6380998 4.41296663 0.63293327 1 P 0 ;0,1=422,2=0.000000
L 4.41296663 0.63293327 4.40951663 0.62931644 1 P 0 ;0,1=422,2=0.000000
L 4.40951663 0.62931644 4.40721644 0.62414892 1 P 0 ;0,1=422,2=0.000000
L 4.40721644 0.62414892 4.4064499 0.6195 1 P 0 ;0,1=422,2=0.000000
L 4.4064499 0.6195 4.42255 0.6195 1 P 0 ;0,1=422,2=0.000000
L 4.4501 0.6195 4.4501 0.6505 1 P 0 ;0,1=422,2=0.000000
L 4.4501 0.6505 4.43591624 0.62828327 1 P 0 ;0,1=422,2=0.000000
L 4.43591624 0.62828327 4.45508366 0.62828327 1 P 0 ;0,1=422,2=0.000000
L 4.47649961 0.6195 4.47649961 0.6505 1 P 0 ;0,1=422,2=0.000000
L 4.47649961 0.6505 4.4718999 0.6443003 1 P 0 ;0,1=422,2=0.000000
L 4.4718999 0.6195 4.48109931 0.6195 1 P 0 ;0,1=422,2=0.000000
L 4.388 0.951 4.388 0.995 1 P 0 
L 4.388 0.995 4.298 0.995 1 P 0 
L 4.298 0.995 4.298 0.951 1 P 0 
L 4.298 0.951 4.388 0.951 1 P 0 
L 4.25083317 0.6195 4.25083317 0.6505 1 P 0 ;0,1=423,2=0.000000
L 4.25083317 0.6505 4.26041654 0.6505 1 P 0 ;0,1=423,2=0.000000
L 4.26041654 0.6505 4.26348327 0.64894931 1 P 0 ;0,1=423,2=0.000000
L 4.26348327 0.64894931 4.2654002 0.64688307 1 P 0 ;0,1=423,2=0.000000
L 4.2654002 0.64688307 4.26616673 0.6427497 1 P 0 ;0,1=423,2=0.000000
L 4.26616673 0.6427497 4.2654002 0.63861634 1 P 0 ;0,1=423,2=0.000000
L 4.2654002 0.63861634 4.2631 0.63603356 1 P 0 ;0,1=423,2=0.000000
L 4.2631 0.63603356 4.26041654 0.63448287 1 P 0 ;0,1=423,2=0.000000
L 4.26041654 0.63448287 4.25083317 0.63448287 1 P 0 ;0,1=423,2=0.000000
L 4.26041654 0.63448287 4.26616673 0.6195 1 P 0 ;0,1=423,2=0.000000
L 4.28221644 0.64533346 4.28451663 0.64843278 1 P 0 ;0,1=423,2=0.000000
L 4.28451663 0.64843278 4.2872001 0.64998337 1 P 0 ;0,1=423,2=0.000000
L 4.2872001 0.64998337 4.29026683 0.6505 1 P 0 ;0,1=423,2=0.000000
L 4.29026683 0.6505 4.2941 0.64946683 1 P 0 ;0,1=423,2=0.000000
L 4.2941 0.64946683 4.29678346 0.64688307 1 P 0 ;0,1=423,2=0.000000
L 4.29678346 0.64688307 4.29755 0.64378376 1 P 0 ;0,1=423,2=0.000000
L 4.29755 0.64378376 4.29716673 0.64068258 1 P 0 ;0,1=423,2=0.000000
L 4.29716673 0.64068258 4.29563307 0.6380998 1 P 0 ;0,1=423,2=0.000000
L 4.29563307 0.6380998 4.28796663 0.63293327 1 P 0 ;0,1=423,2=0.000000
L 4.28796663 0.63293327 4.28451663 0.62931644 1 P 0 ;0,1=423,2=0.000000
L 4.28451663 0.62931644 4.28221644 0.62414892 1 P 0 ;0,1=423,2=0.000000
L 4.28221644 0.62414892 4.2814499 0.6195 1 P 0 ;0,1=423,2=0.000000
L 4.2814499 0.6195 4.29755 0.6195 1 P 0 ;0,1=423,2=0.000000
L 4.31206663 0.62569961 4.31436614 0.62208278 1 P 0 ;0,1=423,2=0.000000
L 4.31436614 0.62208278 4.31743287 0.62001654 1 P 0 ;0,1=423,2=0.000000
L 4.31743287 0.62001654 4.32088356 0.6195 1 P 0 ;0,1=423,2=0.000000
L 4.32088356 0.6195 4.3239503 0.62001654 1 P 0 ;0,1=423,2=0.000000
L 4.3239503 0.62001654 4.32701703 0.62259931 1 P 0 ;0,1=423,2=0.000000
L 4.32701703 0.62259931 4.32893327 0.62569961 1 P 0 ;0,1=423,2=0.000000
L 4.32893327 0.62569961 4.32931654 0.6287999 1 P 0 ;0,1=423,2=0.000000
L 4.32931654 0.6287999 4.32855 0.63241575 1 P 0 ;0,1=423,2=0.000000
L 4.32855 0.63241575 4.32586654 0.63499951 1 P 0 ;0,1=423,2=0.000000
L 4.32586654 0.63499951 4.32318307 0.63603356 1 P 0 ;0,1=423,2=0.000000
L 4.32318307 0.63603356 4.31973307 0.63603356 1 P 0 ;0,1=423,2=0.000000
L 4.32318307 0.63603356 4.32548327 0.63758317 1 P 0 ;0,1=423,2=0.000000
L 4.32548327 0.63758317 4.3274002 0.64016594 1 P 0 ;0,1=423,2=0.000000
L 4.3274002 0.64016594 4.32816673 0.64326624 1 P 0 ;0,1=423,2=0.000000
L 4.32816673 0.64326624 4.3274002 0.64636654 1 P 0 ;0,1=423,2=0.000000
L 4.3274002 0.64636654 4.32548327 0.64894931 1 P 0 ;0,1=423,2=0.000000
L 4.32548327 0.64894931 4.32203327 0.6505 1 P 0 ;0,1=423,2=0.000000
L 4.32203327 0.6505 4.31858337 0.64998337 1 P 0 ;0,1=423,2=0.000000
L 4.31858337 0.64998337 4.31513337 0.64791624 1 P 0 ;0,1=423,2=0.000000
L 4.34498287 0.62311585 4.34766634 0.62053307 1 P 0 ;0,1=423,2=0.000000
L 4.34766634 0.62053307 4.35073307 0.6195 1 P 0 ;0,1=423,2=0.000000
L 4.35073307 0.6195 4.3537998 0.62053307 1 P 0 ;0,1=423,2=0.000000
L 4.3537998 0.62053307 4.35648327 0.62363238 1 P 0 ;0,1=423,2=0.000000
L 4.35648327 0.62363238 4.3584002 0.62828327 1 P 0 ;0,1=423,2=0.000000
L 4.3584002 0.62828327 4.35916673 0.63293327 1 P 0 ;0,1=423,2=0.000000
L 4.35916673 0.63293327 4.35916673 0.63861634 1 P 0 ;0,1=423,2=0.000000
L 4.35916673 0.63861634 4.3584002 0.64326624 1 P 0 ;0,1=423,2=0.000000
L 4.3584002 0.64326624 4.35648327 0.6473997 1 P 0 ;0,1=423,2=0.000000
L 4.35648327 0.6473997 4.35418307 0.64946683 1 P 0 ;0,1=423,2=0.000000
L 4.35418307 0.64946683 4.35149961 0.6505 1 P 0 ;0,1=423,2=0.000000
L 4.35149961 0.6505 4.34843287 0.64946683 1 P 0 ;0,1=423,2=0.000000
L 4.34843287 0.64946683 4.34613337 0.6473997 1 P 0 ;0,1=423,2=0.000000
L 4.34613337 0.6473997 4.3445997 0.6443003 1 P 0 ;0,1=423,2=0.000000
L 4.3445997 0.6443003 4.34383317 0.64016594 1 P 0 ;0,1=423,2=0.000000
L 4.34383317 0.64016594 4.3445997 0.6365501 1 P 0 ;0,1=423,2=0.000000
L 4.3445997 0.6365501 4.34651663 0.63293327 1 P 0 ;0,1=423,2=0.000000
L 4.34651663 0.63293327 4.34881683 0.63086604 1 P 0 ;0,1=423,2=0.000000
L 4.34881683 0.63086604 4.35149961 0.63034951 1 P 0 ;0,1=423,2=0.000000
L 4.35149961 0.63034951 4.35456634 0.63138268 1 P 0 ;0,1=423,2=0.000000
L 4.35456634 0.63138268 4.35686654 0.63396634 1 P 0 ;0,1=423,2=0.000000
L 4.35686654 0.63396634 4.35916673 0.63861634 1 P 0 ;0,1=423,2=0.000000
L 4.227 0.945 4.183 0.945 1 P 0 
L 4.183 0.945 4.183 0.855 1 P 0 
L 4.183 0.855 4.227 0.855 1 P 0 
L 4.227 0.855 4.227 0.945 1 P 0 
L 4.2055 0.95083317 4.1745 0.95083317 1 P 0 ;0,1=424,2=270.000000
L 4.1745 0.95083317 4.1745 0.96041654 1 P 0 ;0,1=424,2=270.000000
L 4.1745 0.96041654 4.17605069 0.96348327 1 P 0 ;0,1=424,2=270.000000
L 4.17605069 0.96348327 4.17811693 0.9654002 1 P 0 ;0,1=424,2=270.000000
L 4.17811693 0.9654002 4.1822503 0.96616673 1 P 0 ;0,1=424,2=270.000000
L 4.1822503 0.96616673 4.18638366 0.9654002 1 P 0 ;0,1=424,2=270.000000
L 4.18638366 0.9654002 4.18896644 0.9631 1 P 0 ;0,1=424,2=270.000000
L 4.18896644 0.9631 4.19051713 0.96041654 1 P 0 ;0,1=424,2=270.000000
L 4.19051713 0.96041654 4.19051713 0.95083317 1 P 0 ;0,1=424,2=270.000000
L 4.19051713 0.96041654 4.2055 0.96616673 1 P 0 ;0,1=424,2=270.000000
L 4.17966654 0.98221644 4.17656722 0.98451663 1 P 0 ;0,1=424,2=270.000000
L 4.17656722 0.98451663 4.17501663 0.9872001 1 P 0 ;0,1=424,2=270.000000
L 4.17501663 0.9872001 4.1745 0.99026683 1 P 0 ;0,1=424,2=270.000000
L 4.1745 0.99026683 4.17553317 0.9941 1 P 0 ;0,1=424,2=270.000000
L 4.17553317 0.9941 4.17811693 0.99678346 1 P 0 ;0,1=424,2=270.000000
L 4.17811693 0.99678346 4.18121624 0.99755 1 P 0 ;0,1=424,2=270.000000
L 4.18121624 0.99755 4.18431742 0.99716673 1 P 0 ;0,1=424,2=270.000000
L 4.18431742 0.99716673 4.1869002 0.99563307 1 P 0 ;0,1=424,2=270.000000
L 4.1869002 0.99563307 4.19206673 0.98796663 1 P 0 ;0,1=424,2=270.000000
L 4.19206673 0.98796663 4.19568356 0.98451663 1 P 0 ;0,1=424,2=270.000000
L 4.19568356 0.98451663 4.20085108 0.98221644 1 P 0 ;0,1=424,2=270.000000
L 4.20085108 0.98221644 4.2055 0.9814499 1 P 0 ;0,1=424,2=270.000000
L 4.2055 0.9814499 4.2055 0.99755 1 P 0 ;0,1=424,2=270.000000
L 4.19930039 1.01206663 4.20291722 1.01436614 1 P 0 ;0,1=424,2=270.000000
L 4.20291722 1.01436614 4.20498346 1.01743287 1 P 0 ;0,1=424,2=270.000000
L 4.20498346 1.01743287 4.2055 1.02088356 1 P 0 ;0,1=424,2=270.000000
L 4.2055 1.02088356 4.20498346 1.0239503 1 P 0 ;0,1=424,2=270.000000
L 4.20498346 1.0239503 4.20240069 1.02701703 1 P 0 ;0,1=424,2=270.000000
L 4.20240069 1.02701703 4.19930039 1.02893327 1 P 0 ;0,1=424,2=270.000000
L 4.19930039 1.02893327 4.1962001 1.02931654 1 P 0 ;0,1=424,2=270.000000
L 4.1962001 1.02931654 4.19258425 1.02855 1 P 0 ;0,1=424,2=270.000000
L 4.19258425 1.02855 4.19000049 1.02586654 1 P 0 ;0,1=424,2=270.000000
L 4.19000049 1.02586654 4.18896644 1.02318307 1 P 0 ;0,1=424,2=270.000000
L 4.18896644 1.02318307 4.18896644 1.01973307 1 P 0 ;0,1=424,2=270.000000
L 4.18896644 1.02318307 4.18741683 1.02548327 1 P 0 ;0,1=424,2=270.000000
L 4.18741683 1.02548327 4.18483406 1.0274002 1 P 0 ;0,1=424,2=270.000000
L 4.18483406 1.0274002 4.18173376 1.02816673 1 P 0 ;0,1=424,2=270.000000
L 4.18173376 1.02816673 4.17863346 1.0274002 1 P 0 ;0,1=424,2=270.000000
L 4.17863346 1.0274002 4.17605069 1.02548327 1 P 0 ;0,1=424,2=270.000000
L 4.17605069 1.02548327 4.1745 1.02203327 1 P 0 ;0,1=424,2=270.000000
L 4.1745 1.02203327 4.17501663 1.01858337 1 P 0 ;0,1=424,2=270.000000
L 4.17501663 1.01858337 4.17708376 1.01513337 1 P 0 ;0,1=424,2=270.000000
L 4.20085108 1.04306663 4.20343386 1.04536614 1 P 0 ;0,1=424,2=270.000000
L 4.20343386 1.04536614 4.20498346 1.04804961 1 P 0 ;0,1=424,2=270.000000
L 4.20498346 1.04804961 4.2055 1.05149961 1 P 0 ;0,1=424,2=270.000000
L 4.2055 1.05149961 4.20446693 1.0549503 1 P 0 ;0,1=424,2=270.000000
L 4.20446693 1.0549503 4.20240069 1.05763307 1 P 0 ;0,1=424,2=270.000000
L 4.20240069 1.05763307 4.19878386 1.05955 1 P 0 ;0,1=424,2=270.000000
L 4.19878386 1.05955 4.19465049 1.05993327 1 P 0 ;0,1=424,2=270.000000
L 4.19465049 1.05993327 4.19051713 1.05916673 1 P 0 ;0,1=424,2=270.000000
L 4.19051713 1.05916673 4.18793337 1.0572498 1 P 0 ;0,1=424,2=270.000000
L 4.18793337 1.0572498 4.18586713 1.05456634 1 P 0 ;0,1=424,2=270.000000
L 4.18586713 1.05456634 4.18535059 1.05188356 1 P 0 ;0,1=424,2=270.000000
L 4.18535059 1.05188356 4.18586713 1.0492001 1 P 0 ;0,1=424,2=270.000000
L 4.18586713 1.0492001 4.18793337 1.0457501 1 P 0 ;0,1=424,2=270.000000
L 4.18793337 1.0457501 4.1745 1.0468999 1 P 0 ;0,1=424,2=270.000000
L 4.1745 1.0468999 4.1745 1.0572498 1 P 0 ;0,1=424,2=270.000000
L 4.95 1.698 4.95 1.742 1 P 0 
L 4.86 1.698 4.95 1.698 1 P 0 
L 4.95 1.742 4.86 1.742 1 P 0 
L 4.86 1.742 4.86 1.698 1 P 0 
L 4.97083317 1.7595 4.97083317 1.7905 1 P 0 ;0,1=425,2=0.000000
L 4.97083317 1.7905 4.98041654 1.7905 1 P 0 ;0,1=425,2=0.000000
L 4.98041654 1.7905 4.98348327 1.78894931 1 P 0 ;0,1=425,2=0.000000
L 4.98348327 1.78894931 4.9854002 1.78688307 1 P 0 ;0,1=425,2=0.000000
L 4.9854002 1.78688307 4.98616673 1.7827497 1 P 0 ;0,1=425,2=0.000000
L 4.98616673 1.7827497 4.9854002 1.77861634 1 P 0 ;0,1=425,2=0.000000
L 4.9854002 1.77861634 4.9831 1.77603356 1 P 0 ;0,1=425,2=0.000000
L 4.9831 1.77603356 4.98041654 1.77448287 1 P 0 ;0,1=425,2=0.000000
L 4.98041654 1.77448287 4.97083317 1.77448287 1 P 0 ;0,1=425,2=0.000000
L 4.98041654 1.77448287 4.98616673 1.7595 1 P 0 ;0,1=425,2=0.000000
L 5.00221644 1.78533346 5.00451663 1.78843278 1 P 0 ;0,1=425,2=0.000000
L 5.00451663 1.78843278 5.0072001 1.78998337 1 P 0 ;0,1=425,2=0.000000
L 5.0072001 1.78998337 5.01026683 1.7905 1 P 0 ;0,1=425,2=0.000000
L 5.01026683 1.7905 5.0141 1.78946683 1 P 0 ;0,1=425,2=0.000000
L 5.0141 1.78946683 5.01678346 1.78688307 1 P 0 ;0,1=425,2=0.000000
L 5.01678346 1.78688307 5.01755 1.78378376 1 P 0 ;0,1=425,2=0.000000
L 5.01755 1.78378376 5.01716673 1.78068258 1 P 0 ;0,1=425,2=0.000000
L 5.01716673 1.78068258 5.01563307 1.7780998 1 P 0 ;0,1=425,2=0.000000
L 5.01563307 1.7780998 5.00796663 1.77293327 1 P 0 ;0,1=425,2=0.000000
L 5.00796663 1.77293327 5.00451663 1.76931644 1 P 0 ;0,1=425,2=0.000000
L 5.00451663 1.76931644 5.00221644 1.76414892 1 P 0 ;0,1=425,2=0.000000
L 5.00221644 1.76414892 5.0014499 1.7595 1 P 0 ;0,1=425,2=0.000000
L 5.0014499 1.7595 5.01755 1.7595 1 P 0 ;0,1=425,2=0.000000
L 5.04049961 1.7595 5.04049961 1.7905 1 P 0 ;0,1=425,2=0.000000
L 5.04049961 1.7905 5.0358999 1.7843003 1 P 0 ;0,1=425,2=0.000000
L 5.0358999 1.7595 5.04509931 1.7595 1 P 0 ;0,1=425,2=0.000000
L 5.06421644 1.78533346 5.06651663 1.78843278 1 P 0 ;0,1=425,2=0.000000
L 5.06651663 1.78843278 5.0692001 1.78998337 1 P 0 ;0,1=425,2=0.000000
L 5.0692001 1.78998337 5.07226683 1.7905 1 P 0 ;0,1=425,2=0.000000
L 5.07226683 1.7905 5.0761 1.78946683 1 P 0 ;0,1=425,2=0.000000
L 5.0761 1.78946683 5.07878346 1.78688307 1 P 0 ;0,1=425,2=0.000000
L 5.07878346 1.78688307 5.07955 1.78378376 1 P 0 ;0,1=425,2=0.000000
L 5.07955 1.78378376 5.07916673 1.78068258 1 P 0 ;0,1=425,2=0.000000
L 5.07916673 1.78068258 5.07763307 1.7780998 1 P 0 ;0,1=425,2=0.000000
L 5.07763307 1.7780998 5.06996663 1.77293327 1 P 0 ;0,1=425,2=0.000000
L 5.06996663 1.77293327 5.06651663 1.76931644 1 P 0 ;0,1=425,2=0.000000
L 5.06651663 1.76931644 5.06421644 1.76414892 1 P 0 ;0,1=425,2=0.000000
L 5.06421644 1.76414892 5.0634499 1.7595 1 P 0 ;0,1=425,2=0.000000
L 5.0634499 1.7595 5.07955 1.7595 1 P 0 ;0,1=425,2=0.000000
L 4.95 1.743 4.95 1.787 1 P 0 
L 4.95 1.787 4.86 1.787 1 P 0 
L 4.86 1.787 4.86 1.743 1 P 0 
L 4.86 1.743 4.95 1.743 1 P 0 
L 4.97083317 1.8045 4.97083317 1.8355 1 P 0 ;0,1=426,2=0.000000
L 4.97083317 1.8355 4.98041654 1.8355 1 P 0 ;0,1=426,2=0.000000
L 4.98041654 1.8355 4.98348327 1.83394931 1 P 0 ;0,1=426,2=0.000000
L 4.98348327 1.83394931 4.9854002 1.83188307 1 P 0 ;0,1=426,2=0.000000
L 4.9854002 1.83188307 4.98616673 1.8277497 1 P 0 ;0,1=426,2=0.000000
L 4.98616673 1.8277497 4.9854002 1.82361634 1 P 0 ;0,1=426,2=0.000000
L 4.9854002 1.82361634 4.9831 1.82103356 1 P 0 ;0,1=426,2=0.000000
L 4.9831 1.82103356 4.98041654 1.81948287 1 P 0 ;0,1=426,2=0.000000
L 4.98041654 1.81948287 4.97083317 1.81948287 1 P 0 ;0,1=426,2=0.000000
L 4.98041654 1.81948287 4.98616673 1.8045 1 P 0 ;0,1=426,2=0.000000
L 5.00221644 1.83033346 5.00451663 1.83343278 1 P 0 ;0,1=426,2=0.000000
L 5.00451663 1.83343278 5.0072001 1.83498337 1 P 0 ;0,1=426,2=0.000000
L 5.0072001 1.83498337 5.01026683 1.8355 1 P 0 ;0,1=426,2=0.000000
L 5.01026683 1.8355 5.0141 1.83446683 1 P 0 ;0,1=426,2=0.000000
L 5.0141 1.83446683 5.01678346 1.83188307 1 P 0 ;0,1=426,2=0.000000
L 5.01678346 1.83188307 5.01755 1.82878376 1 P 0 ;0,1=426,2=0.000000
L 5.01755 1.82878376 5.01716673 1.82568258 1 P 0 ;0,1=426,2=0.000000
L 5.01716673 1.82568258 5.01563307 1.8230998 1 P 0 ;0,1=426,2=0.000000
L 5.01563307 1.8230998 5.00796663 1.81793327 1 P 0 ;0,1=426,2=0.000000
L 5.00796663 1.81793327 5.00451663 1.81431644 1 P 0 ;0,1=426,2=0.000000
L 5.00451663 1.81431644 5.00221644 1.80914892 1 P 0 ;0,1=426,2=0.000000
L 5.00221644 1.80914892 5.0014499 1.8045 1 P 0 ;0,1=426,2=0.000000
L 5.0014499 1.8045 5.01755 1.8045 1 P 0 ;0,1=426,2=0.000000
L 5.04049961 1.8045 5.04049961 1.8355 1 P 0 ;0,1=426,2=0.000000
L 5.04049961 1.8355 5.0358999 1.8293003 1 P 0 ;0,1=426,2=0.000000
L 5.0358999 1.8045 5.04509931 1.8045 1 P 0 ;0,1=426,2=0.000000
L 5.07149961 1.8045 5.07149961 1.8355 1 P 0 ;0,1=426,2=0.000000
L 5.07149961 1.8355 5.0668999 1.8293003 1 P 0 ;0,1=426,2=0.000000
L 5.0668999 1.8045 5.07609931 1.8045 1 P 0 ;0,1=426,2=0.000000
L 4.95 1.608 4.95 1.652 1 P 0 
L 4.95 1.652 4.86 1.652 1 P 0 
L 4.86 1.652 4.86 1.608 1 P 0 
L 4.86 1.608 4.95 1.608 1 P 0 
L 4.97133317 1.6745 4.97133317 1.7055 1 P 0 ;0,1=427,2=0.000000
L 4.97133317 1.7055 4.98091654 1.7055 1 P 0 ;0,1=427,2=0.000000
L 4.98091654 1.7055 4.98398327 1.70394931 1 P 0 ;0,1=427,2=0.000000
L 4.98398327 1.70394931 4.9859002 1.70188307 1 P 0 ;0,1=427,2=0.000000
L 4.9859002 1.70188307 4.98666673 1.6977497 1 P 0 ;0,1=427,2=0.000000
L 4.98666673 1.6977497 4.9859002 1.69361634 1 P 0 ;0,1=427,2=0.000000
L 4.9859002 1.69361634 4.9836 1.69103356 1 P 0 ;0,1=427,2=0.000000
L 4.9836 1.69103356 4.98091654 1.68948287 1 P 0 ;0,1=427,2=0.000000
L 4.98091654 1.68948287 4.97133317 1.68948287 1 P 0 ;0,1=427,2=0.000000
L 4.98091654 1.68948287 4.98666673 1.6745 1 P 0 ;0,1=427,2=0.000000
L 5.00348287 1.67811585 5.00616634 1.67553307 1 P 0 ;0,1=427,2=0.000000
L 5.00616634 1.67553307 5.00923307 1.6745 1 P 0 ;0,1=427,2=0.000000
L 5.00923307 1.6745 5.0122998 1.67553307 1 P 0 ;0,1=427,2=0.000000
L 5.0122998 1.67553307 5.01498327 1.67863238 1 P 0 ;0,1=427,2=0.000000
L 5.01498327 1.67863238 5.0169002 1.68328327 1 P 0 ;0,1=427,2=0.000000
L 5.0169002 1.68328327 5.01766673 1.68793327 1 P 0 ;0,1=427,2=0.000000
L 5.01766673 1.68793327 5.01766673 1.69361634 1 P 0 ;0,1=427,2=0.000000
L 5.01766673 1.69361634 5.0169002 1.69826624 1 P 0 ;0,1=427,2=0.000000
L 5.0169002 1.69826624 5.01498327 1.7023997 1 P 0 ;0,1=427,2=0.000000
L 5.01498327 1.7023997 5.01268307 1.70446683 1 P 0 ;0,1=427,2=0.000000
L 5.01268307 1.70446683 5.00999961 1.7055 1 P 0 ;0,1=427,2=0.000000
L 5.00999961 1.7055 5.00693287 1.70446683 1 P 0 ;0,1=427,2=0.000000
L 5.00693287 1.70446683 5.00463337 1.7023997 1 P 0 ;0,1=427,2=0.000000
L 5.00463337 1.7023997 5.0030997 1.6993003 1 P 0 ;0,1=427,2=0.000000
L 5.0030997 1.6993003 5.00233317 1.69516594 1 P 0 ;0,1=427,2=0.000000
L 5.00233317 1.69516594 5.0030997 1.6915501 1 P 0 ;0,1=427,2=0.000000
L 5.0030997 1.6915501 5.00501663 1.68793327 1 P 0 ;0,1=427,2=0.000000
L 5.00501663 1.68793327 5.00731683 1.68586604 1 P 0 ;0,1=427,2=0.000000
L 5.00731683 1.68586604 5.00999961 1.68534951 1 P 0 ;0,1=427,2=0.000000
L 5.00999961 1.68534951 5.01306634 1.68638268 1 P 0 ;0,1=427,2=0.000000
L 5.01306634 1.68638268 5.01536654 1.68896634 1 P 0 ;0,1=427,2=0.000000
L 5.01536654 1.68896634 5.01766673 1.69361634 1 P 0 ;0,1=427,2=0.000000
L 5.03256663 1.68069961 5.03486614 1.67708278 1 P 0 ;0,1=427,2=0.000000
L 5.03486614 1.67708278 5.03793287 1.67501654 1 P 0 ;0,1=427,2=0.000000
L 5.03793287 1.67501654 5.04138356 1.6745 1 P 0 ;0,1=427,2=0.000000
L 5.04138356 1.6745 5.0444503 1.67501654 1 P 0 ;0,1=427,2=0.000000
L 5.0444503 1.67501654 5.04751703 1.67759931 1 P 0 ;0,1=427,2=0.000000
L 5.04751703 1.67759931 5.04943327 1.68069961 1 P 0 ;0,1=427,2=0.000000
L 5.04943327 1.68069961 5.04981654 1.6837999 1 P 0 ;0,1=427,2=0.000000
L 5.04981654 1.6837999 5.04905 1.68741575 1 P 0 ;0,1=427,2=0.000000
L 5.04905 1.68741575 5.04636654 1.68999951 1 P 0 ;0,1=427,2=0.000000
L 5.04636654 1.68999951 5.04368307 1.69103356 1 P 0 ;0,1=427,2=0.000000
L 5.04368307 1.69103356 5.04023307 1.69103356 1 P 0 ;0,1=427,2=0.000000
L 5.04368307 1.69103356 5.04598327 1.69258317 1 P 0 ;0,1=427,2=0.000000
L 5.04598327 1.69258317 5.0479002 1.69516594 1 P 0 ;0,1=427,2=0.000000
L 5.0479002 1.69516594 5.04866673 1.69826624 1 P 0 ;0,1=427,2=0.000000
L 5.04866673 1.69826624 5.0479002 1.70136654 1 P 0 ;0,1=427,2=0.000000
L 5.0479002 1.70136654 5.04598327 1.70394931 1 P 0 ;0,1=427,2=0.000000
L 5.04598327 1.70394931 5.04253327 1.7055 1 P 0 ;0,1=427,2=0.000000
L 5.04253327 1.7055 5.03908337 1.70498337 1 P 0 ;0,1=427,2=0.000000
L 5.03908337 1.70498337 5.03563337 1.70291624 1 P 0 ;0,1=427,2=0.000000
L 4.95 1.653 4.95 1.697 1 P 0 
L 4.95 1.697 4.86 1.697 1 P 0 
L 4.86 1.697 4.86 1.653 1 P 0 
L 4.86 1.653 4.95 1.653 1 P 0 
L 4.97083317 1.7145 4.97083317 1.7455 1 P 0 ;0,1=428,2=0.000000
L 4.97083317 1.7455 4.98041654 1.7455 1 P 0 ;0,1=428,2=0.000000
L 4.98041654 1.7455 4.98348327 1.74394931 1 P 0 ;0,1=428,2=0.000000
L 4.98348327 1.74394931 4.9854002 1.74188307 1 P 0 ;0,1=428,2=0.000000
L 4.9854002 1.74188307 4.98616673 1.7377497 1 P 0 ;0,1=428,2=0.000000
L 4.98616673 1.7377497 4.9854002 1.73361634 1 P 0 ;0,1=428,2=0.000000
L 4.9854002 1.73361634 4.9831 1.73103356 1 P 0 ;0,1=428,2=0.000000
L 4.9831 1.73103356 4.98041654 1.72948287 1 P 0 ;0,1=428,2=0.000000
L 4.98041654 1.72948287 4.97083317 1.72948287 1 P 0 ;0,1=428,2=0.000000
L 4.98041654 1.72948287 4.98616673 1.7145 1 P 0 ;0,1=428,2=0.000000
L 5.00221644 1.74033346 5.00451663 1.74343278 1 P 0 ;0,1=428,2=0.000000
L 5.00451663 1.74343278 5.0072001 1.74498337 1 P 0 ;0,1=428,2=0.000000
L 5.0072001 1.74498337 5.01026683 1.7455 1 P 0 ;0,1=428,2=0.000000
L 5.01026683 1.7455 5.0141 1.74446683 1 P 0 ;0,1=428,2=0.000000
L 5.0141 1.74446683 5.01678346 1.74188307 1 P 0 ;0,1=428,2=0.000000
L 5.01678346 1.74188307 5.01755 1.73878376 1 P 0 ;0,1=428,2=0.000000
L 5.01755 1.73878376 5.01716673 1.73568258 1 P 0 ;0,1=428,2=0.000000
L 5.01716673 1.73568258 5.01563307 1.7330998 1 P 0 ;0,1=428,2=0.000000
L 5.01563307 1.7330998 5.00796663 1.72793327 1 P 0 ;0,1=428,2=0.000000
L 5.00796663 1.72793327 5.00451663 1.72431644 1 P 0 ;0,1=428,2=0.000000
L 5.00451663 1.72431644 5.00221644 1.71914892 1 P 0 ;0,1=428,2=0.000000
L 5.00221644 1.71914892 5.0014499 1.7145 1 P 0 ;0,1=428,2=0.000000
L 5.0014499 1.7145 5.01755 1.7145 1 P 0 ;0,1=428,2=0.000000
L 5.04049961 1.7145 5.04318307 1.71501654 1 P 0 ;0,1=428,2=0.000000
L 5.04318307 1.71501654 5.0462498 1.71656614 1 P 0 ;0,1=428,2=0.000000
L 5.0462498 1.71656614 5.04816673 1.71914892 1 P 0 ;0,1=428,2=0.000000
L 5.04816673 1.71914892 5.04893327 1.72276673 1 P 0 ;0,1=428,2=0.000000
L 5.04893327 1.72276673 5.04816673 1.72638268 1 P 0 ;0,1=428,2=0.000000
L 5.04816673 1.72638268 5.04586654 1.72948287 1 P 0 ;0,1=428,2=0.000000
L 5.04586654 1.72948287 5.04241654 1.73103356 1 P 0 ;0,1=428,2=0.000000
L 5.04241654 1.73103356 5.03858337 1.73103356 1 P 0 ;0,1=428,2=0.000000
L 5.03858337 1.73103356 5.03628317 1.73206663 1 P 0 ;0,1=428,2=0.000000
L 5.03628317 1.73206663 5.03436614 1.73464941 1 P 0 ;0,1=428,2=0.000000
L 5.03436614 1.73464941 5.0335997 1.73826624 1 P 0 ;0,1=428,2=0.000000
L 5.0335997 1.73826624 5.0347501 1.74188307 1 P 0 ;0,1=428,2=0.000000
L 5.0347501 1.74188307 5.03743287 1.74446683 1 P 0 ;0,1=428,2=0.000000
L 5.03743287 1.74446683 5.04049961 1.7455 1 P 0 ;0,1=428,2=0.000000
L 5.04049961 1.7455 5.04356634 1.74446683 1 P 0 ;0,1=428,2=0.000000
L 5.04356634 1.74446683 5.0462498 1.74188307 1 P 0 ;0,1=428,2=0.000000
L 5.0462498 1.74188307 5.0474002 1.73826624 1 P 0 ;0,1=428,2=0.000000
L 5.0474002 1.73826624 5.04663307 1.73464941 1 P 0 ;0,1=428,2=0.000000
L 5.04663307 1.73464941 5.04471673 1.73206663 1 P 0 ;0,1=428,2=0.000000
L 5.04471673 1.73206663 5.04241654 1.73103356 1 P 0 ;0,1=428,2=0.000000
L 5.04241654 1.73103356 5.03858337 1.73103356 1 P 0 ;0,1=428,2=0.000000
L 5.03858337 1.73103356 5.03513337 1.72948287 1 P 0 ;0,1=428,2=0.000000
L 5.03513337 1.72948287 5.03283317 1.72638268 1 P 0 ;0,1=428,2=0.000000
L 5.03283317 1.72638268 5.03206663 1.72276673 1 P 0 ;0,1=428,2=0.000000
L 5.03206663 1.72276673 5.03283317 1.71914892 1 P 0 ;0,1=428,2=0.000000
L 5.03283317 1.71914892 5.0347501 1.71656614 1 P 0 ;0,1=428,2=0.000000
L 5.0347501 1.71656614 5.03781683 1.71501654 1 P 0 ;0,1=428,2=0.000000
L 5.03781683 1.71501654 5.04049961 1.7145 1 P 0 ;0,1=428,2=0.000000
L 5.07149961 1.7145 5.07418307 1.71501654 1 P 0 ;0,1=428,2=0.000000
L 5.07418307 1.71501654 5.0772498 1.71656614 1 P 0 ;0,1=428,2=0.000000
L 5.0772498 1.71656614 5.07916673 1.71914892 1 P 0 ;0,1=428,2=0.000000
L 5.07916673 1.71914892 5.07993327 1.72276673 1 P 0 ;0,1=428,2=0.000000
L 5.07993327 1.72276673 5.07916673 1.72638268 1 P 0 ;0,1=428,2=0.000000
L 5.07916673 1.72638268 5.07686654 1.72948287 1 P 0 ;0,1=428,2=0.000000
L 5.07686654 1.72948287 5.07341654 1.73103356 1 P 0 ;0,1=428,2=0.000000
L 5.07341654 1.73103356 5.06958337 1.73103356 1 P 0 ;0,1=428,2=0.000000
L 5.06958337 1.73103356 5.06728317 1.73206663 1 P 0 ;0,1=428,2=0.000000
L 5.06728317 1.73206663 5.06536614 1.73464941 1 P 0 ;0,1=428,2=0.000000
L 5.06536614 1.73464941 5.0645997 1.73826624 1 P 0 ;0,1=428,2=0.000000
L 5.0645997 1.73826624 5.0657501 1.74188307 1 P 0 ;0,1=428,2=0.000000
L 5.0657501 1.74188307 5.06843287 1.74446683 1 P 0 ;0,1=428,2=0.000000
L 5.06843287 1.74446683 5.07149961 1.7455 1 P 0 ;0,1=428,2=0.000000
L 5.07149961 1.7455 5.07456634 1.74446683 1 P 0 ;0,1=428,2=0.000000
L 5.07456634 1.74446683 5.0772498 1.74188307 1 P 0 ;0,1=428,2=0.000000
L 5.0772498 1.74188307 5.0784002 1.73826624 1 P 0 ;0,1=428,2=0.000000
L 5.0784002 1.73826624 5.07763307 1.73464941 1 P 0 ;0,1=428,2=0.000000
L 5.07763307 1.73464941 5.07571673 1.73206663 1 P 0 ;0,1=428,2=0.000000
L 5.07571673 1.73206663 5.07341654 1.73103356 1 P 0 ;0,1=428,2=0.000000
L 5.07341654 1.73103356 5.06958337 1.73103356 1 P 0 ;0,1=428,2=0.000000
L 5.06958337 1.73103356 5.06613337 1.72948287 1 P 0 ;0,1=428,2=0.000000
L 5.06613337 1.72948287 5.06383317 1.72638268 1 P 0 ;0,1=428,2=0.000000
L 5.06383317 1.72638268 5.06306663 1.72276673 1 P 0 ;0,1=428,2=0.000000
L 5.06306663 1.72276673 5.06383317 1.71914892 1 P 0 ;0,1=428,2=0.000000
L 5.06383317 1.71914892 5.0657501 1.71656614 1 P 0 ;0,1=428,2=0.000000
L 5.0657501 1.71656614 5.06881683 1.71501654 1 P 0 ;0,1=428,2=0.000000
L 5.06881683 1.71501654 5.07149961 1.7145 1 P 0 ;0,1=428,2=0.000000
L 4.59 2.973 4.59 3.017 1 P 0 
L 4.59 3.017 4.5 3.017 1 P 0 
L 4.5 3.017 4.5 2.973 1 P 0 
L 4.5 2.973 4.59 2.973 1 P 0 
L 4.62583317 2.9995 4.62583317 3.0305 1 P 0 ;0,1=429,2=0.000000
L 4.62583317 3.0305 4.63541654 3.0305 1 P 0 ;0,1=429,2=0.000000
L 4.63541654 3.0305 4.63848327 3.02894931 1 P 0 ;0,1=429,2=0.000000
L 4.63848327 3.02894931 4.6404002 3.02688307 1 P 0 ;0,1=429,2=0.000000
L 4.6404002 3.02688307 4.64116673 3.0227497 1 P 0 ;0,1=429,2=0.000000
L 4.64116673 3.0227497 4.6404002 3.01861634 1 P 0 ;0,1=429,2=0.000000
L 4.6404002 3.01861634 4.6381 3.01603356 1 P 0 ;0,1=429,2=0.000000
L 4.6381 3.01603356 4.63541654 3.01448287 1 P 0 ;0,1=429,2=0.000000
L 4.63541654 3.01448287 4.62583317 3.01448287 1 P 0 ;0,1=429,2=0.000000
L 4.63541654 3.01448287 4.64116673 2.9995 1 P 0 ;0,1=429,2=0.000000
L 4.66449961 2.9995 4.66449961 3.0305 1 P 0 ;0,1=429,2=0.000000
L 4.66449961 3.0305 4.6598999 3.0243003 1 P 0 ;0,1=429,2=0.000000
L 4.6598999 2.9995 4.66909931 2.9995 1 P 0 ;0,1=429,2=0.000000
L 4.7001 2.9995 4.7001 3.0305 1 P 0 ;0,1=429,2=0.000000
L 4.7001 3.0305 4.68591624 3.00828327 1 P 0 ;0,1=429,2=0.000000
L 4.68591624 3.00828327 4.70508366 3.00828327 1 P 0 ;0,1=429,2=0.000000
L 4.71806663 3.00569961 4.72036614 3.00208278 1 P 0 ;0,1=429,2=0.000000
L 4.72036614 3.00208278 4.72343287 3.00001654 1 P 0 ;0,1=429,2=0.000000
L 4.72343287 3.00001654 4.72688356 2.9995 1 P 0 ;0,1=429,2=0.000000
L 4.72688356 2.9995 4.7299503 3.00001654 1 P 0 ;0,1=429,2=0.000000
L 4.7299503 3.00001654 4.73301703 3.00259931 1 P 0 ;0,1=429,2=0.000000
L 4.73301703 3.00259931 4.73493327 3.00569961 1 P 0 ;0,1=429,2=0.000000
L 4.73493327 3.00569961 4.73531654 3.0087999 1 P 0 ;0,1=429,2=0.000000
L 4.73531654 3.0087999 4.73455 3.01241575 1 P 0 ;0,1=429,2=0.000000
L 4.73455 3.01241575 4.73186654 3.01499951 1 P 0 ;0,1=429,2=0.000000
L 4.73186654 3.01499951 4.72918307 3.01603356 1 P 0 ;0,1=429,2=0.000000
L 4.72918307 3.01603356 4.72573307 3.01603356 1 P 0 ;0,1=429,2=0.000000
L 4.72918307 3.01603356 4.73148327 3.01758317 1 P 0 ;0,1=429,2=0.000000
L 4.73148327 3.01758317 4.7334002 3.02016594 1 P 0 ;0,1=429,2=0.000000
L 4.7334002 3.02016594 4.73416673 3.02326624 1 P 0 ;0,1=429,2=0.000000
L 4.73416673 3.02326624 4.7334002 3.02636654 1 P 0 ;0,1=429,2=0.000000
L 4.7334002 3.02636654 4.73148327 3.02894931 1 P 0 ;0,1=429,2=0.000000
L 4.73148327 3.02894931 4.72803327 3.0305 1 P 0 ;0,1=429,2=0.000000
L 4.72803327 3.0305 4.72458337 3.02998337 1 P 0 ;0,1=429,2=0.000000
L 4.72458337 3.02998337 4.72113337 3.02791624 1 P 0 ;0,1=429,2=0.000000
L 3.902 2.703 3.992 2.703 1 P 0 
L 3.992 2.703 3.992 2.747 1 P 0 
L 3.992 2.747 3.902 2.747 1 P 0 
L 3.902 2.747 3.902 2.703 1 P 0 
L 4.00583317 2.7145 4.00583317 2.7455 1 P 0 ;0,1=430,2=0.000000
L 4.00583317 2.7455 4.01541654 2.7455 1 P 0 ;0,1=430,2=0.000000
L 4.01541654 2.7455 4.01848327 2.74394931 1 P 0 ;0,1=430,2=0.000000
L 4.01848327 2.74394931 4.0204002 2.74188307 1 P 0 ;0,1=430,2=0.000000
L 4.0204002 2.74188307 4.02116673 2.7377497 1 P 0 ;0,1=430,2=0.000000
L 4.02116673 2.7377497 4.0204002 2.73361634 1 P 0 ;0,1=430,2=0.000000
L 4.0204002 2.73361634 4.0181 2.73103356 1 P 0 ;0,1=430,2=0.000000
L 4.0181 2.73103356 4.01541654 2.72948287 1 P 0 ;0,1=430,2=0.000000
L 4.01541654 2.72948287 4.00583317 2.72948287 1 P 0 ;0,1=430,2=0.000000
L 4.01541654 2.72948287 4.02116673 2.7145 1 P 0 ;0,1=430,2=0.000000
L 4.04449961 2.7145 4.04449961 2.7455 1 P 0 ;0,1=430,2=0.000000
L 4.04449961 2.7455 4.0398999 2.7393003 1 P 0 ;0,1=430,2=0.000000
L 4.0398999 2.7145 4.04909931 2.7145 1 P 0 ;0,1=430,2=0.000000
L 4.07549961 2.7145 4.07818307 2.71501654 1 P 0 ;0,1=430,2=0.000000
L 4.07818307 2.71501654 4.0812498 2.71656614 1 P 0 ;0,1=430,2=0.000000
L 4.0812498 2.71656614 4.08316673 2.71914892 1 P 0 ;0,1=430,2=0.000000
L 4.08316673 2.71914892 4.08393327 2.72276673 1 P 0 ;0,1=430,2=0.000000
L 4.08393327 2.72276673 4.08316673 2.72638268 1 P 0 ;0,1=430,2=0.000000
L 4.08316673 2.72638268 4.08086654 2.72948287 1 P 0 ;0,1=430,2=0.000000
L 4.08086654 2.72948287 4.07741654 2.73103356 1 P 0 ;0,1=430,2=0.000000
L 4.07741654 2.73103356 4.07358337 2.73103356 1 P 0 ;0,1=430,2=0.000000
L 4.07358337 2.73103356 4.07128317 2.73206663 1 P 0 ;0,1=430,2=0.000000
L 4.07128317 2.73206663 4.06936614 2.73464941 1 P 0 ;0,1=430,2=0.000000
L 4.06936614 2.73464941 4.0685997 2.73826624 1 P 0 ;0,1=430,2=0.000000
L 4.0685997 2.73826624 4.0697501 2.74188307 1 P 0 ;0,1=430,2=0.000000
L 4.0697501 2.74188307 4.07243287 2.74446683 1 P 0 ;0,1=430,2=0.000000
L 4.07243287 2.74446683 4.07549961 2.7455 1 P 0 ;0,1=430,2=0.000000
L 4.07549961 2.7455 4.07856634 2.74446683 1 P 0 ;0,1=430,2=0.000000
L 4.07856634 2.74446683 4.0812498 2.74188307 1 P 0 ;0,1=430,2=0.000000
L 4.0812498 2.74188307 4.0824002 2.73826624 1 P 0 ;0,1=430,2=0.000000
L 4.0824002 2.73826624 4.08163307 2.73464941 1 P 0 ;0,1=430,2=0.000000
L 4.08163307 2.73464941 4.07971673 2.73206663 1 P 0 ;0,1=430,2=0.000000
L 4.07971673 2.73206663 4.07741654 2.73103356 1 P 0 ;0,1=430,2=0.000000
L 4.07741654 2.73103356 4.07358337 2.73103356 1 P 0 ;0,1=430,2=0.000000
L 4.07358337 2.73103356 4.07013337 2.72948287 1 P 0 ;0,1=430,2=0.000000
L 4.07013337 2.72948287 4.06783317 2.72638268 1 P 0 ;0,1=430,2=0.000000
L 4.06783317 2.72638268 4.06706663 2.72276673 1 P 0 ;0,1=430,2=0.000000
L 4.06706663 2.72276673 4.06783317 2.71914892 1 P 0 ;0,1=430,2=0.000000
L 4.06783317 2.71914892 4.0697501 2.71656614 1 P 0 ;0,1=430,2=0.000000
L 4.0697501 2.71656614 4.07281683 2.71501654 1 P 0 ;0,1=430,2=0.000000
L 4.07281683 2.71501654 4.07549961 2.7145 1 P 0 ;0,1=430,2=0.000000
L 4.10649961 2.7145 4.10649961 2.7455 1 P 0 ;0,1=430,2=0.000000
L 4.10649961 2.7455 4.1018999 2.7393003 1 P 0 ;0,1=430,2=0.000000
L 4.1018999 2.7145 4.11109931 2.7145 1 P 0 ;0,1=430,2=0.000000
L 3.992 2.702 3.902 2.702 1 P 0 
L 3.902 2.702 3.902 2.658 1 P 0 
L 3.902 2.658 3.992 2.658 1 P 0 
L 3.992 2.658 3.992 2.702 1 P 0 
L 4.00583317 2.6695 4.00583317 2.7005 1 P 0 ;0,1=431,2=0.000000
L 4.00583317 2.7005 4.01541654 2.7005 1 P 0 ;0,1=431,2=0.000000
L 4.01541654 2.7005 4.01848327 2.69894931 1 P 0 ;0,1=431,2=0.000000
L 4.01848327 2.69894931 4.0204002 2.69688307 1 P 0 ;0,1=431,2=0.000000
L 4.0204002 2.69688307 4.02116673 2.6927497 1 P 0 ;0,1=431,2=0.000000
L 4.02116673 2.6927497 4.0204002 2.68861634 1 P 0 ;0,1=431,2=0.000000
L 4.0204002 2.68861634 4.0181 2.68603356 1 P 0 ;0,1=431,2=0.000000
L 4.0181 2.68603356 4.01541654 2.68448287 1 P 0 ;0,1=431,2=0.000000
L 4.01541654 2.68448287 4.00583317 2.68448287 1 P 0 ;0,1=431,2=0.000000
L 4.01541654 2.68448287 4.02116673 2.6695 1 P 0 ;0,1=431,2=0.000000
L 4.04449961 2.6695 4.04449961 2.7005 1 P 0 ;0,1=431,2=0.000000
L 4.04449961 2.7005 4.0398999 2.6943003 1 P 0 ;0,1=431,2=0.000000
L 4.0398999 2.6695 4.04909931 2.6695 1 P 0 ;0,1=431,2=0.000000
L 4.07473307 2.6695 4.07549961 2.67621614 1 P 0 ;0,1=431,2=0.000000
L 4.07549961 2.67621614 4.0766501 2.68189921 1 P 0 ;0,1=431,2=0.000000
L 4.0766501 2.68189921 4.07818307 2.68706663 1 P 0 ;0,1=431,2=0.000000
L 4.07818307 2.68706663 4.0801 2.6927497 1 P 0 ;0,1=431,2=0.000000
L 4.0801 2.6927497 4.08316673 2.7005 1 P 0 ;0,1=431,2=0.000000
L 4.08316673 2.7005 4.06783317 2.7005 1 P 0 ;0,1=431,2=0.000000
L 4.10649961 2.6695 4.10918307 2.67001654 1 P 0 ;0,1=431,2=0.000000
L 4.10918307 2.67001654 4.1122498 2.67156614 1 P 0 ;0,1=431,2=0.000000
L 4.1122498 2.67156614 4.11416673 2.67414892 1 P 0 ;0,1=431,2=0.000000
L 4.11416673 2.67414892 4.11493327 2.67776673 1 P 0 ;0,1=431,2=0.000000
L 4.11493327 2.67776673 4.11416673 2.68138268 1 P 0 ;0,1=431,2=0.000000
L 4.11416673 2.68138268 4.11186654 2.68448287 1 P 0 ;0,1=431,2=0.000000
L 4.11186654 2.68448287 4.10841654 2.68603356 1 P 0 ;0,1=431,2=0.000000
L 4.10841654 2.68603356 4.10458337 2.68603356 1 P 0 ;0,1=431,2=0.000000
L 4.10458337 2.68603356 4.10228317 2.68706663 1 P 0 ;0,1=431,2=0.000000
L 4.10228317 2.68706663 4.10036614 2.68964941 1 P 0 ;0,1=431,2=0.000000
L 4.10036614 2.68964941 4.0995997 2.69326624 1 P 0 ;0,1=431,2=0.000000
L 4.0995997 2.69326624 4.1007501 2.69688307 1 P 0 ;0,1=431,2=0.000000
L 4.1007501 2.69688307 4.10343287 2.69946683 1 P 0 ;0,1=431,2=0.000000
L 4.10343287 2.69946683 4.10649961 2.7005 1 P 0 ;0,1=431,2=0.000000
L 4.10649961 2.7005 4.10956634 2.69946683 1 P 0 ;0,1=431,2=0.000000
L 4.10956634 2.69946683 4.1122498 2.69688307 1 P 0 ;0,1=431,2=0.000000
L 4.1122498 2.69688307 4.1134002 2.69326624 1 P 0 ;0,1=431,2=0.000000
L 4.1134002 2.69326624 4.11263307 2.68964941 1 P 0 ;0,1=431,2=0.000000
L 4.11263307 2.68964941 4.11071673 2.68706663 1 P 0 ;0,1=431,2=0.000000
L 4.11071673 2.68706663 4.10841654 2.68603356 1 P 0 ;0,1=431,2=0.000000
L 4.10841654 2.68603356 4.10458337 2.68603356 1 P 0 ;0,1=431,2=0.000000
L 4.10458337 2.68603356 4.10113337 2.68448287 1 P 0 ;0,1=431,2=0.000000
L 4.10113337 2.68448287 4.09883317 2.68138268 1 P 0 ;0,1=431,2=0.000000
L 4.09883317 2.68138268 4.09806663 2.67776673 1 P 0 ;0,1=431,2=0.000000
L 4.09806663 2.67776673 4.09883317 2.67414892 1 P 0 ;0,1=431,2=0.000000
L 4.09883317 2.67414892 4.1007501 2.67156614 1 P 0 ;0,1=431,2=0.000000
L 4.1007501 2.67156614 4.10381683 2.67001654 1 P 0 ;0,1=431,2=0.000000
L 4.10381683 2.67001654 4.10649961 2.6695 1 P 0 ;0,1=431,2=0.000000
L 3.225 2.591 3.135 2.591 1 P 0 
L 3.135 2.591 3.135 2.547 1 P 0 
L 3.135 2.547 3.225 2.547 1 P 0 
L 3.225 2.547 3.225 2.591 1 P 0 
L 2.72083317 3.3095 2.72083317 3.3405 1 P 0 ;0,1=432,2=0.000000
L 2.72083317 3.3405 2.73041654 3.3405 1 P 0 ;0,1=432,2=0.000000
L 2.73041654 3.3405 2.73348327 3.33894931 1 P 0 ;0,1=432,2=0.000000
L 2.73348327 3.33894931 2.7354002 3.33688307 1 P 0 ;0,1=432,2=0.000000
L 2.7354002 3.33688307 2.73616673 3.3327497 1 P 0 ;0,1=432,2=0.000000
L 2.73616673 3.3327497 2.7354002 3.32861634 1 P 0 ;0,1=432,2=0.000000
L 2.7354002 3.32861634 2.7331 3.32603356 1 P 0 ;0,1=432,2=0.000000
L 2.7331 3.32603356 2.73041654 3.32448287 1 P 0 ;0,1=432,2=0.000000
L 2.73041654 3.32448287 2.72083317 3.32448287 1 P 0 ;0,1=432,2=0.000000
L 2.73041654 3.32448287 2.73616673 3.3095 1 P 0 ;0,1=432,2=0.000000
L 2.75106663 3.31569961 2.75336614 3.31208278 1 P 0 ;0,1=432,2=0.000000
L 2.75336614 3.31208278 2.75643287 3.31001654 1 P 0 ;0,1=432,2=0.000000
L 2.75643287 3.31001654 2.75988356 3.3095 1 P 0 ;0,1=432,2=0.000000
L 2.75988356 3.3095 2.7629503 3.31001654 1 P 0 ;0,1=432,2=0.000000
L 2.7629503 3.31001654 2.76601703 3.31259931 1 P 0 ;0,1=432,2=0.000000
L 2.76601703 3.31259931 2.76793327 3.31569961 1 P 0 ;0,1=432,2=0.000000
L 2.76793327 3.31569961 2.76831654 3.3187999 1 P 0 ;0,1=432,2=0.000000
L 2.76831654 3.3187999 2.76755 3.32241575 1 P 0 ;0,1=432,2=0.000000
L 2.76755 3.32241575 2.76486654 3.32499951 1 P 0 ;0,1=432,2=0.000000
L 2.76486654 3.32499951 2.76218307 3.32603356 1 P 0 ;0,1=432,2=0.000000
L 2.76218307 3.32603356 2.75873307 3.32603356 1 P 0 ;0,1=432,2=0.000000
L 2.76218307 3.32603356 2.76448327 3.32758317 1 P 0 ;0,1=432,2=0.000000
L 2.76448327 3.32758317 2.7664002 3.33016594 1 P 0 ;0,1=432,2=0.000000
L 2.7664002 3.33016594 2.76716673 3.33326624 1 P 0 ;0,1=432,2=0.000000
L 2.76716673 3.33326624 2.7664002 3.33636654 1 P 0 ;0,1=432,2=0.000000
L 2.7664002 3.33636654 2.76448327 3.33894931 1 P 0 ;0,1=432,2=0.000000
L 2.76448327 3.33894931 2.76103327 3.3405 1 P 0 ;0,1=432,2=0.000000
L 2.76103327 3.3405 2.75758337 3.33998337 1 P 0 ;0,1=432,2=0.000000
L 2.75758337 3.33998337 2.75413337 3.33791624 1 P 0 ;0,1=432,2=0.000000
L 2.79049961 3.3405 2.78743287 3.33946683 1 P 0 ;0,1=432,2=0.000000
L 2.78743287 3.33946683 2.78513337 3.33688307 1 P 0 ;0,1=432,2=0.000000
L 2.78513337 3.33688307 2.7835997 3.33378376 1 P 0 ;0,1=432,2=0.000000
L 2.7835997 3.33378376 2.7824499 3.32964941 1 P 0 ;0,1=432,2=0.000000
L 2.7824499 3.32964941 2.78206663 3.32499951 1 P 0 ;0,1=432,2=0.000000
L 2.78206663 3.32499951 2.7824499 3.32034951 1 P 0 ;0,1=432,2=0.000000
L 2.7824499 3.32034951 2.7835997 3.31621614 1 P 0 ;0,1=432,2=0.000000
L 2.7835997 3.31621614 2.78513337 3.31311585 1 P 0 ;0,1=432,2=0.000000
L 2.78513337 3.31311585 2.78743287 3.31053307 1 P 0 ;0,1=432,2=0.000000
L 2.78743287 3.31053307 2.79049961 3.3095 1 P 0 ;0,1=432,2=0.000000
L 2.79049961 3.3095 2.79356634 3.31053307 1 P 0 ;0,1=432,2=0.000000
L 2.79356634 3.31053307 2.79586654 3.31311585 1 P 0 ;0,1=432,2=0.000000
L 2.79586654 3.31311585 2.7974002 3.31621614 1 P 0 ;0,1=432,2=0.000000
L 2.7974002 3.31621614 2.79855 3.32034951 1 P 0 ;0,1=432,2=0.000000
L 2.79855 3.32034951 2.79893327 3.32499951 1 P 0 ;0,1=432,2=0.000000
L 2.79893327 3.32499951 2.79855 3.32964941 1 P 0 ;0,1=432,2=0.000000
L 2.79855 3.32964941 2.7974002 3.33378376 1 P 0 ;0,1=432,2=0.000000
L 2.7974002 3.33378376 2.79586654 3.33688307 1 P 0 ;0,1=432,2=0.000000
L 2.79586654 3.33688307 2.79356634 3.33946683 1 P 0 ;0,1=432,2=0.000000
L 2.79356634 3.33946683 2.79049961 3.3405 1 P 0 ;0,1=432,2=0.000000
L 2.81306663 3.31414892 2.81536614 3.31156614 1 P 0 ;0,1=432,2=0.000000
L 2.81536614 3.31156614 2.81804961 3.31001654 1 P 0 ;0,1=432,2=0.000000
L 2.81804961 3.31001654 2.82149961 3.3095 1 P 0 ;0,1=432,2=0.000000
L 2.82149961 3.3095 2.8249503 3.31053307 1 P 0 ;0,1=432,2=0.000000
L 2.8249503 3.31053307 2.82763307 3.31259931 1 P 0 ;0,1=432,2=0.000000
L 2.82763307 3.31259931 2.82955 3.31621614 1 P 0 ;0,1=432,2=0.000000
L 2.82955 3.31621614 2.82993327 3.32034951 1 P 0 ;0,1=432,2=0.000000
L 2.82993327 3.32034951 2.82916673 3.32448287 1 P 0 ;0,1=432,2=0.000000
L 2.82916673 3.32448287 2.8272498 3.32706663 1 P 0 ;0,1=432,2=0.000000
L 2.8272498 3.32706663 2.82456634 3.32913287 1 P 0 ;0,1=432,2=0.000000
L 2.82456634 3.32913287 2.82188356 3.32964941 1 P 0 ;0,1=432,2=0.000000
L 2.82188356 3.32964941 2.8192001 3.32913287 1 P 0 ;0,1=432,2=0.000000
L 2.8192001 3.32913287 2.8157501 3.32706663 1 P 0 ;0,1=432,2=0.000000
L 2.8157501 3.32706663 2.8168999 3.3405 1 P 0 ;0,1=432,2=0.000000
L 2.8168999 3.3405 2.8272498 3.3405 1 P 0 ;0,1=432,2=0.000000
L 4.911 2.662 4.911 2.752 1 P 0 
L 4.911 2.752 4.867 2.752 1 P 0 
L 4.867 2.752 4.867 2.662 1 P 0 
L 4.867 2.662 4.911 2.662 1 P 0 
L 4.8955 2.55083317 4.8645 2.55083317 1 P 0 ;0,1=433,2=270.000000
L 4.8645 2.55083317 4.8645 2.56041654 1 P 0 ;0,1=433,2=270.000000
L 4.8645 2.56041654 4.86605069 2.56348327 1 P 0 ;0,1=433,2=270.000000
L 4.86605069 2.56348327 4.86811693 2.5654002 1 P 0 ;0,1=433,2=270.000000
L 4.86811693 2.5654002 4.8722503 2.56616673 1 P 0 ;0,1=433,2=270.000000
L 4.8722503 2.56616673 4.87638366 2.5654002 1 P 0 ;0,1=433,2=270.000000
L 4.87638366 2.5654002 4.87896644 2.5631 1 P 0 ;0,1=433,2=270.000000
L 4.87896644 2.5631 4.88051713 2.56041654 1 P 0 ;0,1=433,2=270.000000
L 4.88051713 2.56041654 4.88051713 2.55083317 1 P 0 ;0,1=433,2=270.000000
L 4.88051713 2.56041654 4.8955 2.56616673 1 P 0 ;0,1=433,2=270.000000
L 4.8955 2.58949961 4.8645 2.58949961 1 P 0 ;0,1=433,2=270.000000
L 4.8645 2.58949961 4.8706997 2.5848999 1 P 0 ;0,1=433,2=270.000000
L 4.8955 2.5848999 4.8955 2.59409931 1 P 0 ;0,1=433,2=270.000000
L 4.8955 2.6251 4.8645 2.6251 1 P 0 ;0,1=433,2=270.000000
L 4.8645 2.6251 4.88671673 2.61091624 1 P 0 ;0,1=433,2=270.000000
L 4.88671673 2.61091624 4.88671673 2.63008366 1 P 0 ;0,1=433,2=270.000000
L 4.8955 2.65149961 4.8645 2.65149961 1 P 0 ;0,1=433,2=270.000000
L 4.8645 2.65149961 4.8706997 2.6468999 1 P 0 ;0,1=433,2=270.000000
L 4.8955 2.6468999 4.8955 2.65609931 1 P 0 ;0,1=433,2=270.000000
L 4.42 3.843 4.42 3.887 1 P 0 
L 4.42 3.887 4.33 3.887 1 P 0 
L 4.33 3.887 4.33 3.843 1 P 0 
L 4.33 3.843 4.42 3.843 1 P 0 
L 4.45083317 3.9845 4.45083317 4.0155 1 P 0 ;0,1=434,2=0.000000
L 4.45083317 4.0155 4.46041654 4.0155 1 P 0 ;0,1=434,2=0.000000
L 4.46041654 4.0155 4.46348327 4.01394931 1 P 0 ;0,1=434,2=0.000000
L 4.46348327 4.01394931 4.4654002 4.01188307 1 P 0 ;0,1=434,2=0.000000
L 4.4654002 4.01188307 4.46616673 4.0077497 1 P 0 ;0,1=434,2=0.000000
L 4.46616673 4.0077497 4.4654002 4.00361634 1 P 0 ;0,1=434,2=0.000000
L 4.4654002 4.00361634 4.4631 4.00103356 1 P 0 ;0,1=434,2=0.000000
L 4.4631 4.00103356 4.46041654 3.99948287 1 P 0 ;0,1=434,2=0.000000
L 4.46041654 3.99948287 4.45083317 3.99948287 1 P 0 ;0,1=434,2=0.000000
L 4.46041654 3.99948287 4.46616673 3.9845 1 P 0 ;0,1=434,2=0.000000
L 4.48106663 3.99069961 4.48336614 3.98708278 1 P 0 ;0,1=434,2=0.000000
L 4.48336614 3.98708278 4.48643287 3.98501654 1 P 0 ;0,1=434,2=0.000000
L 4.48643287 3.98501654 4.48988356 3.9845 1 P 0 ;0,1=434,2=0.000000
L 4.48988356 3.9845 4.4929503 3.98501654 1 P 0 ;0,1=434,2=0.000000
L 4.4929503 3.98501654 4.49601703 3.98759931 1 P 0 ;0,1=434,2=0.000000
L 4.49601703 3.98759931 4.49793327 3.99069961 1 P 0 ;0,1=434,2=0.000000
L 4.49793327 3.99069961 4.49831654 3.9937999 1 P 0 ;0,1=434,2=0.000000
L 4.49831654 3.9937999 4.49755 3.99741575 1 P 0 ;0,1=434,2=0.000000
L 4.49755 3.99741575 4.49486654 3.99999951 1 P 0 ;0,1=434,2=0.000000
L 4.49486654 3.99999951 4.49218307 4.00103356 1 P 0 ;0,1=434,2=0.000000
L 4.49218307 4.00103356 4.48873307 4.00103356 1 P 0 ;0,1=434,2=0.000000
L 4.49218307 4.00103356 4.49448327 4.00258317 1 P 0 ;0,1=434,2=0.000000
L 4.49448327 4.00258317 4.4964002 4.00516594 1 P 0 ;0,1=434,2=0.000000
L 4.4964002 4.00516594 4.49716673 4.00826624 1 P 0 ;0,1=434,2=0.000000
L 4.49716673 4.00826624 4.4964002 4.01136654 1 P 0 ;0,1=434,2=0.000000
L 4.4964002 4.01136654 4.49448327 4.01394931 1 P 0 ;0,1=434,2=0.000000
L 4.49448327 4.01394931 4.49103327 4.0155 1 P 0 ;0,1=434,2=0.000000
L 4.49103327 4.0155 4.48758337 4.01498337 1 P 0 ;0,1=434,2=0.000000
L 4.48758337 4.01498337 4.48413337 4.01291624 1 P 0 ;0,1=434,2=0.000000
L 4.51321644 4.01033346 4.51551663 4.01343278 1 P 0 ;0,1=434,2=0.000000
L 4.51551663 4.01343278 4.5182001 4.01498337 1 P 0 ;0,1=434,2=0.000000
L 4.5182001 4.01498337 4.52126683 4.0155 1 P 0 ;0,1=434,2=0.000000
L 4.52126683 4.0155 4.5251 4.01446683 1 P 0 ;0,1=434,2=0.000000
L 4.5251 4.01446683 4.52778346 4.01188307 1 P 0 ;0,1=434,2=0.000000
L 4.52778346 4.01188307 4.52855 4.00878376 1 P 0 ;0,1=434,2=0.000000
L 4.52855 4.00878376 4.52816673 4.00568258 1 P 0 ;0,1=434,2=0.000000
L 4.52816673 4.00568258 4.52663307 4.0030998 1 P 0 ;0,1=434,2=0.000000
L 4.52663307 4.0030998 4.51896663 3.99793327 1 P 0 ;0,1=434,2=0.000000
L 4.51896663 3.99793327 4.51551663 3.99431644 1 P 0 ;0,1=434,2=0.000000
L 4.51551663 3.99431644 4.51321644 3.98914892 1 P 0 ;0,1=434,2=0.000000
L 4.51321644 3.98914892 4.5124499 3.9845 1 P 0 ;0,1=434,2=0.000000
L 4.5124499 3.9845 4.52855 3.9845 1 P 0 ;0,1=434,2=0.000000
L 4.55149961 4.0155 4.54843287 4.01446683 1 P 0 ;0,1=434,2=0.000000
L 4.54843287 4.01446683 4.54613337 4.01188307 1 P 0 ;0,1=434,2=0.000000
L 4.54613337 4.01188307 4.5445997 4.00878376 1 P 0 ;0,1=434,2=0.000000
L 4.5445997 4.00878376 4.5434499 4.00464941 1 P 0 ;0,1=434,2=0.000000
L 4.5434499 4.00464941 4.54306663 3.99999951 1 P 0 ;0,1=434,2=0.000000
L 4.54306663 3.99999951 4.5434499 3.99534951 1 P 0 ;0,1=434,2=0.000000
L 4.5434499 3.99534951 4.5445997 3.99121614 1 P 0 ;0,1=434,2=0.000000
L 4.5445997 3.99121614 4.54613337 3.98811585 1 P 0 ;0,1=434,2=0.000000
L 4.54613337 3.98811585 4.54843287 3.98553307 1 P 0 ;0,1=434,2=0.000000
L 4.54843287 3.98553307 4.55149961 3.9845 1 P 0 ;0,1=434,2=0.000000
L 4.55149961 3.9845 4.55456634 3.98553307 1 P 0 ;0,1=434,2=0.000000
L 4.55456634 3.98553307 4.55686654 3.98811585 1 P 0 ;0,1=434,2=0.000000
L 4.55686654 3.98811585 4.5584002 3.99121614 1 P 0 ;0,1=434,2=0.000000
L 4.5584002 3.99121614 4.55955 3.99534951 1 P 0 ;0,1=434,2=0.000000
L 4.55955 3.99534951 4.55993327 3.99999951 1 P 0 ;0,1=434,2=0.000000
L 4.55993327 3.99999951 4.55955 4.00464941 1 P 0 ;0,1=434,2=0.000000
L 4.55955 4.00464941 4.5584002 4.00878376 1 P 0 ;0,1=434,2=0.000000
L 4.5584002 4.00878376 4.55686654 4.01188307 1 P 0 ;0,1=434,2=0.000000
L 4.55686654 4.01188307 4.55456634 4.01446683 1 P 0 ;0,1=434,2=0.000000
L 4.55456634 4.01446683 4.55149961 4.0155 1 P 0 ;0,1=434,2=0.000000
L 2.962 3.31 2.962 3.354 1 P 0 
L 2.872 3.31 2.962 3.31 1 P 0 
L 2.962 3.354 2.872 3.354 1 P 0 
L 2.872 3.354 2.872 3.31 1 P 0 
L 2.85583317 3.4495 2.85583317 3.4805 1 P 0 ;0,1=435,2=0.000000
L 2.85583317 3.4805 2.86541654 3.4805 1 P 0 ;0,1=435,2=0.000000
L 2.86541654 3.4805 2.86848327 3.47894931 1 P 0 ;0,1=435,2=0.000000
L 2.86848327 3.47894931 2.8704002 3.47688307 1 P 0 ;0,1=435,2=0.000000
L 2.8704002 3.47688307 2.87116673 3.4727497 1 P 0 ;0,1=435,2=0.000000
L 2.87116673 3.4727497 2.8704002 3.46861634 1 P 0 ;0,1=435,2=0.000000
L 2.8704002 3.46861634 2.8681 3.46603356 1 P 0 ;0,1=435,2=0.000000
L 2.8681 3.46603356 2.86541654 3.46448287 1 P 0 ;0,1=435,2=0.000000
L 2.86541654 3.46448287 2.85583317 3.46448287 1 P 0 ;0,1=435,2=0.000000
L 2.86541654 3.46448287 2.87116673 3.4495 1 P 0 ;0,1=435,2=0.000000
L 2.88606663 3.45569961 2.88836614 3.45208278 1 P 0 ;0,1=435,2=0.000000
L 2.88836614 3.45208278 2.89143287 3.45001654 1 P 0 ;0,1=435,2=0.000000
L 2.89143287 3.45001654 2.89488356 3.4495 1 P 0 ;0,1=435,2=0.000000
L 2.89488356 3.4495 2.8979503 3.45001654 1 P 0 ;0,1=435,2=0.000000
L 2.8979503 3.45001654 2.90101703 3.45259931 1 P 0 ;0,1=435,2=0.000000
L 2.90101703 3.45259931 2.90293327 3.45569961 1 P 0 ;0,1=435,2=0.000000
L 2.90293327 3.45569961 2.90331654 3.4587999 1 P 0 ;0,1=435,2=0.000000
L 2.90331654 3.4587999 2.90255 3.46241575 1 P 0 ;0,1=435,2=0.000000
L 2.90255 3.46241575 2.89986654 3.46499951 1 P 0 ;0,1=435,2=0.000000
L 2.89986654 3.46499951 2.89718307 3.46603356 1 P 0 ;0,1=435,2=0.000000
L 2.89718307 3.46603356 2.89373307 3.46603356 1 P 0 ;0,1=435,2=0.000000
L 2.89718307 3.46603356 2.89948327 3.46758317 1 P 0 ;0,1=435,2=0.000000
L 2.89948327 3.46758317 2.9014002 3.47016594 1 P 0 ;0,1=435,2=0.000000
L 2.9014002 3.47016594 2.90216673 3.47326624 1 P 0 ;0,1=435,2=0.000000
L 2.90216673 3.47326624 2.9014002 3.47636654 1 P 0 ;0,1=435,2=0.000000
L 2.9014002 3.47636654 2.89948327 3.47894931 1 P 0 ;0,1=435,2=0.000000
L 2.89948327 3.47894931 2.89603327 3.4805 1 P 0 ;0,1=435,2=0.000000
L 2.89603327 3.4805 2.89258337 3.47998337 1 P 0 ;0,1=435,2=0.000000
L 2.89258337 3.47998337 2.88913337 3.47791624 1 P 0 ;0,1=435,2=0.000000
L 2.92549961 3.4495 2.92549961 3.4805 1 P 0 ;0,1=435,2=0.000000
L 2.92549961 3.4805 2.9208999 3.4743003 1 P 0 ;0,1=435,2=0.000000
L 2.9208999 3.4495 2.93009931 3.4495 1 P 0 ;0,1=435,2=0.000000
L 2.95649961 3.4495 2.95649961 3.4805 1 P 0 ;0,1=435,2=0.000000
L 2.95649961 3.4805 2.9518999 3.4743003 1 P 0 ;0,1=435,2=0.000000
L 2.9518999 3.4495 2.96109931 3.4495 1 P 0 ;0,1=435,2=0.000000
L 2.961 3.237 2.961 3.281 1 P 0 
L 2.871 3.237 2.961 3.237 1 P 0 
L 2.961 3.281 2.871 3.281 1 P 0 
L 2.871 3.281 2.871 3.237 1 P 0 
L 2.85583317 3.4095 2.85583317 3.4405 1 P 0 ;0,1=436,2=0.000000
L 2.85583317 3.4405 2.86541654 3.4405 1 P 0 ;0,1=436,2=0.000000
L 2.86541654 3.4405 2.86848327 3.43894931 1 P 0 ;0,1=436,2=0.000000
L 2.86848327 3.43894931 2.8704002 3.43688307 1 P 0 ;0,1=436,2=0.000000
L 2.8704002 3.43688307 2.87116673 3.4327497 1 P 0 ;0,1=436,2=0.000000
L 2.87116673 3.4327497 2.8704002 3.42861634 1 P 0 ;0,1=436,2=0.000000
L 2.8704002 3.42861634 2.8681 3.42603356 1 P 0 ;0,1=436,2=0.000000
L 2.8681 3.42603356 2.86541654 3.42448287 1 P 0 ;0,1=436,2=0.000000
L 2.86541654 3.42448287 2.85583317 3.42448287 1 P 0 ;0,1=436,2=0.000000
L 2.86541654 3.42448287 2.87116673 3.4095 1 P 0 ;0,1=436,2=0.000000
L 2.88606663 3.41569961 2.88836614 3.41208278 1 P 0 ;0,1=436,2=0.000000
L 2.88836614 3.41208278 2.89143287 3.41001654 1 P 0 ;0,1=436,2=0.000000
L 2.89143287 3.41001654 2.89488356 3.4095 1 P 0 ;0,1=436,2=0.000000
L 2.89488356 3.4095 2.8979503 3.41001654 1 P 0 ;0,1=436,2=0.000000
L 2.8979503 3.41001654 2.90101703 3.41259931 1 P 0 ;0,1=436,2=0.000000
L 2.90101703 3.41259931 2.90293327 3.41569961 1 P 0 ;0,1=436,2=0.000000
L 2.90293327 3.41569961 2.90331654 3.4187999 1 P 0 ;0,1=436,2=0.000000
L 2.90331654 3.4187999 2.90255 3.42241575 1 P 0 ;0,1=436,2=0.000000
L 2.90255 3.42241575 2.89986654 3.42499951 1 P 0 ;0,1=436,2=0.000000
L 2.89986654 3.42499951 2.89718307 3.42603356 1 P 0 ;0,1=436,2=0.000000
L 2.89718307 3.42603356 2.89373307 3.42603356 1 P 0 ;0,1=436,2=0.000000
L 2.89718307 3.42603356 2.89948327 3.42758317 1 P 0 ;0,1=436,2=0.000000
L 2.89948327 3.42758317 2.9014002 3.43016594 1 P 0 ;0,1=436,2=0.000000
L 2.9014002 3.43016594 2.90216673 3.43326624 1 P 0 ;0,1=436,2=0.000000
L 2.90216673 3.43326624 2.9014002 3.43636654 1 P 0 ;0,1=436,2=0.000000
L 2.9014002 3.43636654 2.89948327 3.43894931 1 P 0 ;0,1=436,2=0.000000
L 2.89948327 3.43894931 2.89603327 3.4405 1 P 0 ;0,1=436,2=0.000000
L 2.89603327 3.4405 2.89258337 3.43998337 1 P 0 ;0,1=436,2=0.000000
L 2.89258337 3.43998337 2.88913337 3.43791624 1 P 0 ;0,1=436,2=0.000000
L 2.92549961 3.4095 2.92549961 3.4405 1 P 0 ;0,1=436,2=0.000000
L 2.92549961 3.4405 2.9208999 3.4343003 1 P 0 ;0,1=436,2=0.000000
L 2.9208999 3.4095 2.93009931 3.4095 1 P 0 ;0,1=436,2=0.000000
L 2.95649961 3.4405 2.95343287 3.43946683 1 P 0 ;0,1=436,2=0.000000
L 2.95343287 3.43946683 2.95113337 3.43688307 1 P 0 ;0,1=436,2=0.000000
L 2.95113337 3.43688307 2.9495997 3.43378376 1 P 0 ;0,1=436,2=0.000000
L 2.9495997 3.43378376 2.9484499 3.42964941 1 P 0 ;0,1=436,2=0.000000
L 2.9484499 3.42964941 2.94806663 3.42499951 1 P 0 ;0,1=436,2=0.000000
L 2.94806663 3.42499951 2.9484499 3.42034951 1 P 0 ;0,1=436,2=0.000000
L 2.9484499 3.42034951 2.9495997 3.41621614 1 P 0 ;0,1=436,2=0.000000
L 2.9495997 3.41621614 2.95113337 3.41311585 1 P 0 ;0,1=436,2=0.000000
L 2.95113337 3.41311585 2.95343287 3.41053307 1 P 0 ;0,1=436,2=0.000000
L 2.95343287 3.41053307 2.95649961 3.4095 1 P 0 ;0,1=436,2=0.000000
L 2.95649961 3.4095 2.95956634 3.41053307 1 P 0 ;0,1=436,2=0.000000
L 2.95956634 3.41053307 2.96186654 3.41311585 1 P 0 ;0,1=436,2=0.000000
L 2.96186654 3.41311585 2.9634002 3.41621614 1 P 0 ;0,1=436,2=0.000000
L 2.9634002 3.41621614 2.96455 3.42034951 1 P 0 ;0,1=436,2=0.000000
L 2.96455 3.42034951 2.96493327 3.42499951 1 P 0 ;0,1=436,2=0.000000
L 2.96493327 3.42499951 2.96455 3.42964941 1 P 0 ;0,1=436,2=0.000000
L 2.96455 3.42964941 2.9634002 3.43378376 1 P 0 ;0,1=436,2=0.000000
L 2.9634002 3.43378376 2.96186654 3.43688307 1 P 0 ;0,1=436,2=0.000000
L 2.96186654 3.43688307 2.95956634 3.43946683 1 P 0 ;0,1=436,2=0.000000
L 2.95956634 3.43946683 2.95649961 3.4405 1 P 0 ;0,1=436,2=0.000000
L 3.859 3.07 3.859 3.114 1 P 0 
L 3.769 3.07 3.859 3.07 1 P 0 
L 3.859 3.114 3.769 3.114 1 P 0 
L 3.769 3.114 3.769 3.07 1 P 0 
L 3.76083317 3.1245 3.76083317 3.1555 1 P 0 ;0,1=437,2=0.000000
L 3.76083317 3.1555 3.77041654 3.1555 1 P 0 ;0,1=437,2=0.000000
L 3.77041654 3.1555 3.77348327 3.15394931 1 P 0 ;0,1=437,2=0.000000
L 3.77348327 3.15394931 3.7754002 3.15188307 1 P 0 ;0,1=437,2=0.000000
L 3.7754002 3.15188307 3.77616673 3.1477497 1 P 0 ;0,1=437,2=0.000000
L 3.77616673 3.1477497 3.7754002 3.14361634 1 P 0 ;0,1=437,2=0.000000
L 3.7754002 3.14361634 3.7731 3.14103356 1 P 0 ;0,1=437,2=0.000000
L 3.7731 3.14103356 3.77041654 3.13948287 1 P 0 ;0,1=437,2=0.000000
L 3.77041654 3.13948287 3.76083317 3.13948287 1 P 0 ;0,1=437,2=0.000000
L 3.77041654 3.13948287 3.77616673 3.1245 1 P 0 ;0,1=437,2=0.000000
L 3.79949961 3.1245 3.79949961 3.1555 1 P 0 ;0,1=437,2=0.000000
L 3.79949961 3.1555 3.7948999 3.1493003 1 P 0 ;0,1=437,2=0.000000
L 3.7948999 3.1245 3.80409931 3.1245 1 P 0 ;0,1=437,2=0.000000
L 3.8351 3.1245 3.8351 3.1555 1 P 0 ;0,1=437,2=0.000000
L 3.8351 3.1555 3.82091624 3.13328327 1 P 0 ;0,1=437,2=0.000000
L 3.82091624 3.13328327 3.84008366 3.13328327 1 P 0 ;0,1=437,2=0.000000
L 3.86149961 3.1555 3.85843287 3.15446683 1 P 0 ;0,1=437,2=0.000000
L 3.85843287 3.15446683 3.85613337 3.15188307 1 P 0 ;0,1=437,2=0.000000
L 3.85613337 3.15188307 3.8545997 3.14878376 1 P 0 ;0,1=437,2=0.000000
L 3.8545997 3.14878376 3.8534499 3.14464941 1 P 0 ;0,1=437,2=0.000000
L 3.8534499 3.14464941 3.85306663 3.13999951 1 P 0 ;0,1=437,2=0.000000
L 3.85306663 3.13999951 3.8534499 3.13534951 1 P 0 ;0,1=437,2=0.000000
L 3.8534499 3.13534951 3.8545997 3.13121614 1 P 0 ;0,1=437,2=0.000000
L 3.8545997 3.13121614 3.85613337 3.12811585 1 P 0 ;0,1=437,2=0.000000
L 3.85613337 3.12811585 3.85843287 3.12553307 1 P 0 ;0,1=437,2=0.000000
L 3.85843287 3.12553307 3.86149961 3.1245 1 P 0 ;0,1=437,2=0.000000
L 3.86149961 3.1245 3.86456634 3.12553307 1 P 0 ;0,1=437,2=0.000000
L 3.86456634 3.12553307 3.86686654 3.12811585 1 P 0 ;0,1=437,2=0.000000
L 3.86686654 3.12811585 3.8684002 3.13121614 1 P 0 ;0,1=437,2=0.000000
L 3.8684002 3.13121614 3.86955 3.13534951 1 P 0 ;0,1=437,2=0.000000
L 3.86955 3.13534951 3.86993327 3.13999951 1 P 0 ;0,1=437,2=0.000000
L 3.86993327 3.13999951 3.86955 3.14464941 1 P 0 ;0,1=437,2=0.000000
L 3.86955 3.14464941 3.8684002 3.14878376 1 P 0 ;0,1=437,2=0.000000
L 3.8684002 3.14878376 3.86686654 3.15188307 1 P 0 ;0,1=437,2=0.000000
L 3.86686654 3.15188307 3.86456634 3.15446683 1 P 0 ;0,1=437,2=0.000000
L 3.86456634 3.15446683 3.86149961 3.1555 1 P 0 ;0,1=437,2=0.000000
L 3.588 4.099 3.498 4.099 1 P 0 
L 3.498 4.055 3.588 4.055 1 P 0 
L 3.588 4.055 3.588 4.099 1 P 0 
L 3.498 4.099 3.498 4.055 1 P 0 
L 3.62433317 4.0515 3.62433317 4.0825 1 P 0 ;0,1=438,2=0.000000
L 3.62433317 4.0825 3.63391654 4.0825 1 P 0 ;0,1=438,2=0.000000
L 3.63391654 4.0825 3.63698327 4.08094931 1 P 0 ;0,1=438,2=0.000000
L 3.63698327 4.08094931 3.6389002 4.07888307 1 P 0 ;0,1=438,2=0.000000
L 3.6389002 4.07888307 3.63966673 4.0747497 1 P 0 ;0,1=438,2=0.000000
L 3.63966673 4.0747497 3.6389002 4.07061634 1 P 0 ;0,1=438,2=0.000000
L 3.6389002 4.07061634 3.6366 4.06803356 1 P 0 ;0,1=438,2=0.000000
L 3.6366 4.06803356 3.63391654 4.06648287 1 P 0 ;0,1=438,2=0.000000
L 3.63391654 4.06648287 3.62433317 4.06648287 1 P 0 ;0,1=438,2=0.000000
L 3.63391654 4.06648287 3.63966673 4.0515 1 P 0 ;0,1=438,2=0.000000
L 3.65456663 4.05614892 3.65686614 4.05356614 1 P 0 ;0,1=438,2=0.000000
L 3.65686614 4.05356614 3.65954961 4.05201654 1 P 0 ;0,1=438,2=0.000000
L 3.65954961 4.05201654 3.66299961 4.0515 1 P 0 ;0,1=438,2=0.000000
L 3.66299961 4.0515 3.6664503 4.05253307 1 P 0 ;0,1=438,2=0.000000
L 3.6664503 4.05253307 3.66913307 4.05459931 1 P 0 ;0,1=438,2=0.000000
L 3.66913307 4.05459931 3.67105 4.05821614 1 P 0 ;0,1=438,2=0.000000
L 3.67105 4.05821614 3.67143327 4.06234951 1 P 0 ;0,1=438,2=0.000000
L 3.67143327 4.06234951 3.67066673 4.06648287 1 P 0 ;0,1=438,2=0.000000
L 3.67066673 4.06648287 3.6687498 4.06906663 1 P 0 ;0,1=438,2=0.000000
L 3.6687498 4.06906663 3.66606634 4.07113287 1 P 0 ;0,1=438,2=0.000000
L 3.66606634 4.07113287 3.66338356 4.07164941 1 P 0 ;0,1=438,2=0.000000
L 3.66338356 4.07164941 3.6607001 4.07113287 1 P 0 ;0,1=438,2=0.000000
L 3.6607001 4.07113287 3.6572501 4.06906663 1 P 0 ;0,1=438,2=0.000000
L 3.6572501 4.06906663 3.6583999 4.0825 1 P 0 ;0,1=438,2=0.000000
L 3.6583999 4.0825 3.6687498 4.0825 1 P 0 ;0,1=438,2=0.000000
L 3.68671644 4.07733346 3.68901663 4.08043278 1 P 0 ;0,1=438,2=0.000000
L 3.68901663 4.08043278 3.6917001 4.08198337 1 P 0 ;0,1=438,2=0.000000
L 3.6917001 4.08198337 3.69476683 4.0825 1 P 0 ;0,1=438,2=0.000000
L 3.69476683 4.0825 3.6986 4.08146683 1 P 0 ;0,1=438,2=0.000000
L 3.6986 4.08146683 3.70128346 4.07888307 1 P 0 ;0,1=438,2=0.000000
L 3.70128346 4.07888307 3.70205 4.07578376 1 P 0 ;0,1=438,2=0.000000
L 3.70205 4.07578376 3.70166673 4.07268258 1 P 0 ;0,1=438,2=0.000000
L 3.70166673 4.07268258 3.70013307 4.0700998 1 P 0 ;0,1=438,2=0.000000
L 3.70013307 4.0700998 3.69246663 4.06493327 1 P 0 ;0,1=438,2=0.000000
L 3.69246663 4.06493327 3.68901663 4.06131644 1 P 0 ;0,1=438,2=0.000000
L 3.68901663 4.06131644 3.68671644 4.05614892 1 P 0 ;0,1=438,2=0.000000
L 3.68671644 4.05614892 3.6859499 4.0515 1 P 0 ;0,1=438,2=0.000000
L 3.6859499 4.0515 3.70205 4.0515 1 P 0 ;0,1=438,2=0.000000
L 3.421 3.882 3.421 3.792 1 P 0 
L 3.421 3.792 3.465 3.792 1 P 0 
L 3.465 3.792 3.465 3.882 1 P 0 
L 3.465 3.882 3.421 3.882 1 P 0 
L 3.2255 3.59133317 3.1945 3.59133317 1 P 0 ;0,1=439,2=270.000000
L 3.1945 3.59133317 3.1945 3.60091654 1 P 0 ;0,1=439,2=270.000000
L 3.1945 3.60091654 3.19605069 3.60398327 1 P 0 ;0,1=439,2=270.000000
L 3.19605069 3.60398327 3.19811693 3.6059002 1 P 0 ;0,1=439,2=270.000000
L 3.19811693 3.6059002 3.2022503 3.60666673 1 P 0 ;0,1=439,2=270.000000
L 3.2022503 3.60666673 3.20638366 3.6059002 1 P 0 ;0,1=439,2=270.000000
L 3.20638366 3.6059002 3.20896644 3.6036 1 P 0 ;0,1=439,2=270.000000
L 3.20896644 3.6036 3.21051713 3.60091654 1 P 0 ;0,1=439,2=270.000000
L 3.21051713 3.60091654 3.21051713 3.59133317 1 P 0 ;0,1=439,2=270.000000
L 3.21051713 3.60091654 3.2255 3.60666673 1 P 0 ;0,1=439,2=270.000000
L 3.21930039 3.62156663 3.22291722 3.62386614 1 P 0 ;0,1=439,2=270.000000
L 3.22291722 3.62386614 3.22498346 3.62693287 1 P 0 ;0,1=439,2=270.000000
L 3.22498346 3.62693287 3.2255 3.63038356 1 P 0 ;0,1=439,2=270.000000
L 3.2255 3.63038356 3.22498346 3.6334503 1 P 0 ;0,1=439,2=270.000000
L 3.22498346 3.6334503 3.22240069 3.63651703 1 P 0 ;0,1=439,2=270.000000
L 3.22240069 3.63651703 3.21930039 3.63843327 1 P 0 ;0,1=439,2=270.000000
L 3.21930039 3.63843327 3.2162001 3.63881654 1 P 0 ;0,1=439,2=270.000000
L 3.2162001 3.63881654 3.21258425 3.63805 1 P 0 ;0,1=439,2=270.000000
L 3.21258425 3.63805 3.21000049 3.63536654 1 P 0 ;0,1=439,2=270.000000
L 3.21000049 3.63536654 3.20896644 3.63268307 1 P 0 ;0,1=439,2=270.000000
L 3.20896644 3.63268307 3.20896644 3.62923307 1 P 0 ;0,1=439,2=270.000000
L 3.20896644 3.63268307 3.20741683 3.63498327 1 P 0 ;0,1=439,2=270.000000
L 3.20741683 3.63498327 3.20483406 3.6369002 1 P 0 ;0,1=439,2=270.000000
L 3.20483406 3.6369002 3.20173376 3.63766673 1 P 0 ;0,1=439,2=270.000000
L 3.20173376 3.63766673 3.19863346 3.6369002 1 P 0 ;0,1=439,2=270.000000
L 3.19863346 3.6369002 3.19605069 3.63498327 1 P 0 ;0,1=439,2=270.000000
L 3.19605069 3.63498327 3.1945 3.63153327 1 P 0 ;0,1=439,2=270.000000
L 3.1945 3.63153327 3.19501663 3.62808337 1 P 0 ;0,1=439,2=270.000000
L 3.19501663 3.62808337 3.19708376 3.62463337 1 P 0 ;0,1=439,2=270.000000
L 3.22085108 3.65256663 3.22343386 3.65486614 1 P 0 ;0,1=439,2=270.000000
L 3.22343386 3.65486614 3.22498346 3.65754961 1 P 0 ;0,1=439,2=270.000000
L 3.22498346 3.65754961 3.2255 3.66099961 1 P 0 ;0,1=439,2=270.000000
L 3.2255 3.66099961 3.22446693 3.6644503 1 P 0 ;0,1=439,2=270.000000
L 3.22446693 3.6644503 3.22240069 3.66713307 1 P 0 ;0,1=439,2=270.000000
L 3.22240069 3.66713307 3.21878386 3.66905 1 P 0 ;0,1=439,2=270.000000
L 3.21878386 3.66905 3.21465049 3.66943327 1 P 0 ;0,1=439,2=270.000000
L 3.21465049 3.66943327 3.21051713 3.66866673 1 P 0 ;0,1=439,2=270.000000
L 3.21051713 3.66866673 3.20793337 3.6667498 1 P 0 ;0,1=439,2=270.000000
L 3.20793337 3.6667498 3.20586713 3.66406634 1 P 0 ;0,1=439,2=270.000000
L 3.20586713 3.66406634 3.20535059 3.66138356 1 P 0 ;0,1=439,2=270.000000
L 3.20535059 3.66138356 3.20586713 3.6587001 1 P 0 ;0,1=439,2=270.000000
L 3.20586713 3.6587001 3.20793337 3.6552501 1 P 0 ;0,1=439,2=270.000000
L 3.20793337 3.6552501 3.1945 3.6563999 1 P 0 ;0,1=439,2=270.000000
L 3.1945 3.6563999 3.1945 3.6667498 1 P 0 ;0,1=439,2=270.000000
L 3.645 3.812 3.645 3.902 1 P 0 
L 3.645 3.902 3.601 3.902 1 P 0 
L 3.601 3.902 3.601 3.812 1 P 0 
L 3.601 3.812 3.645 3.812 1 P 0 
L 3.6905 3.81633317 3.6595 3.81633317 1 P 0 ;0,1=440,2=270.000000
L 3.6595 3.81633317 3.6595 3.82591654 1 P 0 ;0,1=440,2=270.000000
L 3.6595 3.82591654 3.66105069 3.82898327 1 P 0 ;0,1=440,2=270.000000
L 3.66105069 3.82898327 3.66311693 3.8309002 1 P 0 ;0,1=440,2=270.000000
L 3.66311693 3.8309002 3.6672503 3.83166673 1 P 0 ;0,1=440,2=270.000000
L 3.6672503 3.83166673 3.67138366 3.8309002 1 P 0 ;0,1=440,2=270.000000
L 3.67138366 3.8309002 3.67396644 3.8286 1 P 0 ;0,1=440,2=270.000000
L 3.67396644 3.8286 3.67551713 3.82591654 1 P 0 ;0,1=440,2=270.000000
L 3.67551713 3.82591654 3.67551713 3.81633317 1 P 0 ;0,1=440,2=270.000000
L 3.67551713 3.82591654 3.6905 3.83166673 1 P 0 ;0,1=440,2=270.000000
L 3.6905 3.85499961 3.6595 3.85499961 1 P 0 ;0,1=440,2=270.000000
L 3.6595 3.85499961 3.6656997 3.8503999 1 P 0 ;0,1=440,2=270.000000
L 3.6905 3.8503999 3.6905 3.85959931 1 P 0 ;0,1=440,2=270.000000
L 3.6905 3.88523307 3.68378386 3.88599961 1 P 0 ;0,1=440,2=270.000000
L 3.68378386 3.88599961 3.67810079 3.8871501 1 P 0 ;0,1=440,2=270.000000
L 3.67810079 3.8871501 3.67293337 3.88868307 1 P 0 ;0,1=440,2=270.000000
L 3.67293337 3.88868307 3.6672503 3.8906 1 P 0 ;0,1=440,2=270.000000
L 3.6672503 3.8906 3.6595 3.89366673 1 P 0 ;0,1=440,2=270.000000
L 3.6595 3.89366673 3.6595 3.87833317 1 P 0 ;0,1=440,2=270.000000
L 3.56 3.758 3.56 3.802 1 P 0 
L 3.56 3.802 3.47 3.802 1 P 0 
L 3.47 3.802 3.47 3.758 1 P 0 
L 3.47 3.758 3.56 3.758 1 P 0 
L 3.54133317 3.6745 3.54133317 3.7055 1 P 0 ;0,1=441,2=0.000000
L 3.54133317 3.7055 3.55091654 3.7055 1 P 0 ;0,1=441,2=0.000000
L 3.55091654 3.7055 3.55398327 3.70394931 1 P 0 ;0,1=441,2=0.000000
L 3.55398327 3.70394931 3.5559002 3.70188307 1 P 0 ;0,1=441,2=0.000000
L 3.5559002 3.70188307 3.55666673 3.6977497 1 P 0 ;0,1=441,2=0.000000
L 3.55666673 3.6977497 3.5559002 3.69361634 1 P 0 ;0,1=441,2=0.000000
L 3.5559002 3.69361634 3.5536 3.69103356 1 P 0 ;0,1=441,2=0.000000
L 3.5536 3.69103356 3.55091654 3.68948287 1 P 0 ;0,1=441,2=0.000000
L 3.55091654 3.68948287 3.54133317 3.68948287 1 P 0 ;0,1=441,2=0.000000
L 3.55091654 3.68948287 3.55666673 3.6745 1 P 0 ;0,1=441,2=0.000000
L 3.57156663 3.68069961 3.57386614 3.67708278 1 P 0 ;0,1=441,2=0.000000
L 3.57386614 3.67708278 3.57693287 3.67501654 1 P 0 ;0,1=441,2=0.000000
L 3.57693287 3.67501654 3.58038356 3.6745 1 P 0 ;0,1=441,2=0.000000
L 3.58038356 3.6745 3.5834503 3.67501654 1 P 0 ;0,1=441,2=0.000000
L 3.5834503 3.67501654 3.58651703 3.67759931 1 P 0 ;0,1=441,2=0.000000
L 3.58651703 3.67759931 3.58843327 3.68069961 1 P 0 ;0,1=441,2=0.000000
L 3.58843327 3.68069961 3.58881654 3.6837999 1 P 0 ;0,1=441,2=0.000000
L 3.58881654 3.6837999 3.58805 3.68741575 1 P 0 ;0,1=441,2=0.000000
L 3.58805 3.68741575 3.58536654 3.68999951 1 P 0 ;0,1=441,2=0.000000
L 3.58536654 3.68999951 3.58268307 3.69103356 1 P 0 ;0,1=441,2=0.000000
L 3.58268307 3.69103356 3.57923307 3.69103356 1 P 0 ;0,1=441,2=0.000000
L 3.58268307 3.69103356 3.58498327 3.69258317 1 P 0 ;0,1=441,2=0.000000
L 3.58498327 3.69258317 3.5869002 3.69516594 1 P 0 ;0,1=441,2=0.000000
L 3.5869002 3.69516594 3.58766673 3.69826624 1 P 0 ;0,1=441,2=0.000000
L 3.58766673 3.69826624 3.5869002 3.70136654 1 P 0 ;0,1=441,2=0.000000
L 3.5869002 3.70136654 3.58498327 3.70394931 1 P 0 ;0,1=441,2=0.000000
L 3.58498327 3.70394931 3.58153327 3.7055 1 P 0 ;0,1=441,2=0.000000
L 3.58153327 3.7055 3.57808337 3.70498337 1 P 0 ;0,1=441,2=0.000000
L 3.57808337 3.70498337 3.57463337 3.70291624 1 P 0 ;0,1=441,2=0.000000
L 3.61099961 3.6745 3.61368307 3.67501654 1 P 0 ;0,1=441,2=0.000000
L 3.61368307 3.67501654 3.6167498 3.67656614 1 P 0 ;0,1=441,2=0.000000
L 3.6167498 3.67656614 3.61866673 3.67914892 1 P 0 ;0,1=441,2=0.000000
L 3.61866673 3.67914892 3.61943327 3.68276673 1 P 0 ;0,1=441,2=0.000000
L 3.61943327 3.68276673 3.61866673 3.68638268 1 P 0 ;0,1=441,2=0.000000
L 3.61866673 3.68638268 3.61636654 3.68948287 1 P 0 ;0,1=441,2=0.000000
L 3.61636654 3.68948287 3.61291654 3.69103356 1 P 0 ;0,1=441,2=0.000000
L 3.61291654 3.69103356 3.60908337 3.69103356 1 P 0 ;0,1=441,2=0.000000
L 3.60908337 3.69103356 3.60678317 3.69206663 1 P 0 ;0,1=441,2=0.000000
L 3.60678317 3.69206663 3.60486614 3.69464941 1 P 0 ;0,1=441,2=0.000000
L 3.60486614 3.69464941 3.6040997 3.69826624 1 P 0 ;0,1=441,2=0.000000
L 3.6040997 3.69826624 3.6052501 3.70188307 1 P 0 ;0,1=441,2=0.000000
L 3.6052501 3.70188307 3.60793287 3.70446683 1 P 0 ;0,1=441,2=0.000000
L 3.60793287 3.70446683 3.61099961 3.7055 1 P 0 ;0,1=441,2=0.000000
L 3.61099961 3.7055 3.61406634 3.70446683 1 P 0 ;0,1=441,2=0.000000
L 3.61406634 3.70446683 3.6167498 3.70188307 1 P 0 ;0,1=441,2=0.000000
L 3.6167498 3.70188307 3.6179002 3.69826624 1 P 0 ;0,1=441,2=0.000000
L 3.6179002 3.69826624 3.61713307 3.69464941 1 P 0 ;0,1=441,2=0.000000
L 3.61713307 3.69464941 3.61521673 3.69206663 1 P 0 ;0,1=441,2=0.000000
L 3.61521673 3.69206663 3.61291654 3.69103356 1 P 0 ;0,1=441,2=0.000000
L 3.61291654 3.69103356 3.60908337 3.69103356 1 P 0 ;0,1=441,2=0.000000
L 3.60908337 3.69103356 3.60563337 3.68948287 1 P 0 ;0,1=441,2=0.000000
L 3.60563337 3.68948287 3.60333317 3.68638268 1 P 0 ;0,1=441,2=0.000000
L 3.60333317 3.68638268 3.60256663 3.68276673 1 P 0 ;0,1=441,2=0.000000
L 3.60256663 3.68276673 3.60333317 3.67914892 1 P 0 ;0,1=441,2=0.000000
L 3.60333317 3.67914892 3.6052501 3.67656614 1 P 0 ;0,1=441,2=0.000000
L 3.6052501 3.67656614 3.60831683 3.67501654 1 P 0 ;0,1=441,2=0.000000
L 3.60831683 3.67501654 3.61099961 3.6745 1 P 0 ;0,1=441,2=0.000000
L 3.588 3.855 3.498 3.855 1 P 0 
L 3.498 3.855 3.498 3.811 1 P 0 
L 3.498 3.811 3.588 3.811 1 P 0 
L 3.588 3.811 3.588 3.855 1 P 0 
L 3.57433317 3.7225 3.57433317 3.7535 1 P 0 ;0,1=442,2=0.000000
L 3.57433317 3.7535 3.58391654 3.7535 1 P 0 ;0,1=442,2=0.000000
L 3.58391654 3.7535 3.58698327 3.75194931 1 P 0 ;0,1=442,2=0.000000
L 3.58698327 3.75194931 3.5889002 3.74988307 1 P 0 ;0,1=442,2=0.000000
L 3.5889002 3.74988307 3.58966673 3.7457497 1 P 0 ;0,1=442,2=0.000000
L 3.58966673 3.7457497 3.5889002 3.74161634 1 P 0 ;0,1=442,2=0.000000
L 3.5889002 3.74161634 3.5866 3.73903356 1 P 0 ;0,1=442,2=0.000000
L 3.5866 3.73903356 3.58391654 3.73748287 1 P 0 ;0,1=442,2=0.000000
L 3.58391654 3.73748287 3.57433317 3.73748287 1 P 0 ;0,1=442,2=0.000000
L 3.58391654 3.73748287 3.58966673 3.7225 1 P 0 ;0,1=442,2=0.000000
L 3.6176 3.7225 3.6176 3.7535 1 P 0 ;0,1=442,2=0.000000
L 3.6176 3.7535 3.60341624 3.73128327 1 P 0 ;0,1=442,2=0.000000
L 3.60341624 3.73128327 3.62258366 3.73128327 1 P 0 ;0,1=442,2=0.000000
L 3.64399961 3.7535 3.64093287 3.75246683 1 P 0 ;0,1=442,2=0.000000
L 3.64093287 3.75246683 3.63863337 3.74988307 1 P 0 ;0,1=442,2=0.000000
L 3.63863337 3.74988307 3.6370997 3.74678376 1 P 0 ;0,1=442,2=0.000000
L 3.6370997 3.74678376 3.6359499 3.74264941 1 P 0 ;0,1=442,2=0.000000
L 3.6359499 3.74264941 3.63556663 3.73799951 1 P 0 ;0,1=442,2=0.000000
L 3.63556663 3.73799951 3.6359499 3.73334951 1 P 0 ;0,1=442,2=0.000000
L 3.6359499 3.73334951 3.6370997 3.72921614 1 P 0 ;0,1=442,2=0.000000
L 3.6370997 3.72921614 3.63863337 3.72611585 1 P 0 ;0,1=442,2=0.000000
L 3.63863337 3.72611585 3.64093287 3.72353307 1 P 0 ;0,1=442,2=0.000000
L 3.64093287 3.72353307 3.64399961 3.7225 1 P 0 ;0,1=442,2=0.000000
L 3.64399961 3.7225 3.64706634 3.72353307 1 P 0 ;0,1=442,2=0.000000
L 3.64706634 3.72353307 3.64936654 3.72611585 1 P 0 ;0,1=442,2=0.000000
L 3.64936654 3.72611585 3.6509002 3.72921614 1 P 0 ;0,1=442,2=0.000000
L 3.6509002 3.72921614 3.65205 3.73334951 1 P 0 ;0,1=442,2=0.000000
L 3.65205 3.73334951 3.65243327 3.73799951 1 P 0 ;0,1=442,2=0.000000
L 3.65243327 3.73799951 3.65205 3.74264941 1 P 0 ;0,1=442,2=0.000000
L 3.65205 3.74264941 3.6509002 3.74678376 1 P 0 ;0,1=442,2=0.000000
L 3.6509002 3.74678376 3.64936654 3.74988307 1 P 0 ;0,1=442,2=0.000000
L 3.64936654 3.74988307 3.64706634 3.75246683 1 P 0 ;0,1=442,2=0.000000
L 3.64706634 3.75246683 3.64399961 3.7535 1 P 0 ;0,1=442,2=0.000000
L 4.957 3.57 4.913 3.57 1 P 0 
L 4.957 3.48 4.957 3.57 1 P 0 
L 4.913 3.57 4.913 3.48 1 P 0 
L 4.913 3.48 4.957 3.48 1 P 0 
L 4.9505 3.33583317 4.9195 3.33583317 1 P 0 ;0,1=443,2=270.000000
L 4.9195 3.33583317 4.9195 3.34541654 1 P 0 ;0,1=443,2=270.000000
L 4.9195 3.34541654 4.92105069 3.34848327 1 P 0 ;0,1=443,2=270.000000
L 4.92105069 3.34848327 4.92311693 3.3504002 1 P 0 ;0,1=443,2=270.000000
L 4.92311693 3.3504002 4.9272503 3.35116673 1 P 0 ;0,1=443,2=270.000000
L 4.9272503 3.35116673 4.93138366 3.3504002 1 P 0 ;0,1=443,2=270.000000
L 4.93138366 3.3504002 4.93396644 3.3481 1 P 0 ;0,1=443,2=270.000000
L 4.93396644 3.3481 4.93551713 3.34541654 1 P 0 ;0,1=443,2=270.000000
L 4.93551713 3.34541654 4.93551713 3.33583317 1 P 0 ;0,1=443,2=270.000000
L 4.93551713 3.34541654 4.9505 3.35116673 1 P 0 ;0,1=443,2=270.000000
L 4.92466654 3.36721644 4.92156722 3.36951663 1 P 0 ;0,1=443,2=270.000000
L 4.92156722 3.36951663 4.92001663 3.3722001 1 P 0 ;0,1=443,2=270.000000
L 4.92001663 3.3722001 4.9195 3.37526683 1 P 0 ;0,1=443,2=270.000000
L 4.9195 3.37526683 4.92053317 3.3791 1 P 0 ;0,1=443,2=270.000000
L 4.92053317 3.3791 4.92311693 3.38178346 1 P 0 ;0,1=443,2=270.000000
L 4.92311693 3.38178346 4.92621624 3.38255 1 P 0 ;0,1=443,2=270.000000
L 4.92621624 3.38255 4.92931742 3.38216673 1 P 0 ;0,1=443,2=270.000000
L 4.92931742 3.38216673 4.9319002 3.38063307 1 P 0 ;0,1=443,2=270.000000
L 4.9319002 3.38063307 4.93706673 3.37296663 1 P 0 ;0,1=443,2=270.000000
L 4.93706673 3.37296663 4.94068356 3.36951663 1 P 0 ;0,1=443,2=270.000000
L 4.94068356 3.36951663 4.94585108 3.36721644 1 P 0 ;0,1=443,2=270.000000
L 4.94585108 3.36721644 4.9505 3.3664499 1 P 0 ;0,1=443,2=270.000000
L 4.9505 3.3664499 4.9505 3.38255 1 P 0 ;0,1=443,2=270.000000
L 4.93758425 3.39821644 4.93396644 3.4008999 1 P 0 ;0,1=443,2=270.000000
L 4.93396644 3.4008999 4.9319002 3.4032001 1 P 0 ;0,1=443,2=270.000000
L 4.9319002 3.4032001 4.93086713 3.40626683 1 P 0 ;0,1=443,2=270.000000
L 4.93086713 3.40626683 4.9319002 3.4089503 1 P 0 ;0,1=443,2=270.000000
L 4.9319002 3.4089503 4.93396644 3.41086654 1 P 0 ;0,1=443,2=270.000000
L 4.93396644 3.41086654 4.93706673 3.4124002 1 P 0 ;0,1=443,2=270.000000
L 4.93706673 3.4124002 4.94068356 3.41278346 1 P 0 ;0,1=443,2=270.000000
L 4.94068356 3.41278346 4.94378386 3.4124002 1 P 0 ;0,1=443,2=270.000000
L 4.94378386 3.4124002 4.94688415 3.41086654 1 P 0 ;0,1=443,2=270.000000
L 4.94688415 3.41086654 4.94946693 3.40856634 1 P 0 ;0,1=443,2=270.000000
L 4.94946693 3.40856634 4.9505 3.40588356 1 P 0 ;0,1=443,2=270.000000
L 4.9505 3.40588356 4.94946693 3.40281683 1 P 0 ;0,1=443,2=270.000000
L 4.94946693 3.40281683 4.94636762 3.40013337 1 P 0 ;0,1=443,2=270.000000
L 4.94636762 3.40013337 4.94171673 3.3985997 1 P 0 ;0,1=443,2=270.000000
L 4.94171673 3.3985997 4.9365502 3.39821644 1 P 0 ;0,1=443,2=270.000000
L 4.9365502 3.39821644 4.92983406 3.39898287 1 P 0 ;0,1=443,2=270.000000
L 4.92983406 3.39898287 4.92621624 3.40013337 1 P 0 ;0,1=443,2=270.000000
L 4.92621624 3.40013337 4.9226003 3.40204961 1 P 0 ;0,1=443,2=270.000000
L 4.9226003 3.40204961 4.92001663 3.40473307 1 P 0 ;0,1=443,2=270.000000
L 4.92001663 3.40473307 4.9195 3.40741654 1 P 0 ;0,1=443,2=270.000000
L 4.9195 3.40741654 4.92053317 3.4101 1 P 0 ;0,1=443,2=270.000000
L 4.92053317 3.4101 4.92311693 3.41201703 1 P 0 ;0,1=443,2=270.000000
L 4.9505 3.43649961 4.94998346 3.43918307 1 P 0 ;0,1=443,2=270.000000
L 4.94998346 3.43918307 4.94843386 3.4422498 1 P 0 ;0,1=443,2=270.000000
L 4.94843386 3.4422498 4.94585108 3.44416673 1 P 0 ;0,1=443,2=270.000000
L 4.94585108 3.44416673 4.94223327 3.44493327 1 P 0 ;0,1=443,2=270.000000
L 4.94223327 3.44493327 4.93861732 3.44416673 1 P 0 ;0,1=443,2=270.000000
L 4.93861732 3.44416673 4.93551713 3.44186654 1 P 0 ;0,1=443,2=270.000000
L 4.93551713 3.44186654 4.93396644 3.43841654 1 P 0 ;0,1=443,2=270.000000
L 4.93396644 3.43841654 4.93396644 3.43458337 1 P 0 ;0,1=443,2=270.000000
L 4.93396644 3.43458337 4.93293337 3.43228317 1 P 0 ;0,1=443,2=270.000000
L 4.93293337 3.43228317 4.93035059 3.43036614 1 P 0 ;0,1=443,2=270.000000
L 4.93035059 3.43036614 4.92673376 3.4295997 1 P 0 ;0,1=443,2=270.000000
L 4.92673376 3.4295997 4.92311693 3.4307501 1 P 0 ;0,1=443,2=270.000000
L 4.92311693 3.4307501 4.92053317 3.43343287 1 P 0 ;0,1=443,2=270.000000
L 4.92053317 3.43343287 4.9195 3.43649961 1 P 0 ;0,1=443,2=270.000000
L 4.9195 3.43649961 4.92053317 3.43956634 1 P 0 ;0,1=443,2=270.000000
L 4.92053317 3.43956634 4.92311693 3.4422498 1 P 0 ;0,1=443,2=270.000000
L 4.92311693 3.4422498 4.92673376 3.4434002 1 P 0 ;0,1=443,2=270.000000
L 4.92673376 3.4434002 4.93035059 3.44263307 1 P 0 ;0,1=443,2=270.000000
L 4.93035059 3.44263307 4.93293337 3.44071673 1 P 0 ;0,1=443,2=270.000000
L 4.93293337 3.44071673 4.93396644 3.43841654 1 P 0 ;0,1=443,2=270.000000
L 4.93396644 3.43841654 4.93396644 3.43458337 1 P 0 ;0,1=443,2=270.000000
L 4.93396644 3.43458337 4.93551713 3.43113337 1 P 0 ;0,1=443,2=270.000000
L 4.93551713 3.43113337 4.93861732 3.42883317 1 P 0 ;0,1=443,2=270.000000
L 4.93861732 3.42883317 4.94223327 3.42806663 1 P 0 ;0,1=443,2=270.000000
L 4.94223327 3.42806663 4.94585108 3.42883317 1 P 0 ;0,1=443,2=270.000000
L 4.94585108 3.42883317 4.94843386 3.4307501 1 P 0 ;0,1=443,2=270.000000
L 4.94843386 3.4307501 4.94998346 3.43381683 1 P 0 ;0,1=443,2=270.000000
L 4.94998346 3.43381683 4.9505 3.43649961 1 P 0 ;0,1=443,2=270.000000
L 5.007 3.57 4.963 3.57 1 P 0 
L 5.007 3.48 5.007 3.57 1 P 0 
L 4.963 3.57 4.963 3.48 1 P 0 
L 4.963 3.48 5.007 3.48 1 P 0 
L 5.0205 3.33583317 4.9895 3.33583317 1 P 0 ;0,1=444,2=270.000000
L 4.9895 3.33583317 4.9895 3.34541654 1 P 0 ;0,1=444,2=270.000000
L 4.9895 3.34541654 4.99105069 3.34848327 1 P 0 ;0,1=444,2=270.000000
L 4.99105069 3.34848327 4.99311693 3.3504002 1 P 0 ;0,1=444,2=270.000000
L 4.99311693 3.3504002 4.9972503 3.35116673 1 P 0 ;0,1=444,2=270.000000
L 4.9972503 3.35116673 5.00138366 3.3504002 1 P 0 ;0,1=444,2=270.000000
L 5.00138366 3.3504002 5.00396644 3.3481 1 P 0 ;0,1=444,2=270.000000
L 5.00396644 3.3481 5.00551713 3.34541654 1 P 0 ;0,1=444,2=270.000000
L 5.00551713 3.34541654 5.00551713 3.33583317 1 P 0 ;0,1=444,2=270.000000
L 5.00551713 3.34541654 5.0205 3.35116673 1 P 0 ;0,1=444,2=270.000000
L 5.0205 3.37449961 4.9895 3.37449961 1 P 0 ;0,1=444,2=270.000000
L 4.9895 3.37449961 4.9956997 3.3698999 1 P 0 ;0,1=444,2=270.000000
L 5.0205 3.3698999 5.0205 3.37909931 1 P 0 ;0,1=444,2=270.000000
L 5.0205 3.40549961 4.9895 3.40549961 1 P 0 ;0,1=444,2=270.000000
L 4.9895 3.40549961 4.9956997 3.4008999 1 P 0 ;0,1=444,2=270.000000
L 5.0205 3.4008999 5.0205 3.41009931 1 P 0 ;0,1=444,2=270.000000
L 4.99466654 3.42921644 4.99156722 3.43151663 1 P 0 ;0,1=444,2=270.000000
L 4.99156722 3.43151663 4.99001663 3.4342001 1 P 0 ;0,1=444,2=270.000000
L 4.99001663 3.4342001 4.9895 3.43726683 1 P 0 ;0,1=444,2=270.000000
L 4.9895 3.43726683 4.99053317 3.4411 1 P 0 ;0,1=444,2=270.000000
L 4.99053317 3.4411 4.99311693 3.44378346 1 P 0 ;0,1=444,2=270.000000
L 4.99311693 3.44378346 4.99621624 3.44455 1 P 0 ;0,1=444,2=270.000000
L 4.99621624 3.44455 4.99931742 3.44416673 1 P 0 ;0,1=444,2=270.000000
L 4.99931742 3.44416673 5.0019002 3.44263307 1 P 0 ;0,1=444,2=270.000000
L 5.0019002 3.44263307 5.00706673 3.43496663 1 P 0 ;0,1=444,2=270.000000
L 5.00706673 3.43496663 5.01068356 3.43151663 1 P 0 ;0,1=444,2=270.000000
L 5.01068356 3.43151663 5.01585108 3.42921644 1 P 0 ;0,1=444,2=270.000000
L 5.01585108 3.42921644 5.0205 3.4284499 1 P 0 ;0,1=444,2=270.000000
L 5.0205 3.4284499 5.0205 3.44455 1 P 0 ;0,1=444,2=270.000000
L 4.807 3.57 4.763 3.57 1 P 0 
L 4.763 3.57 4.763 3.48 1 P 0 
L 4.763 3.48 4.807 3.48 1 P 0 
L 4.807 3.48 4.807 3.57 1 P 0 
L 4.7905 3.33583317 4.7595 3.33583317 1 P 0 ;0,1=445,2=270.000000
L 4.7595 3.33583317 4.7595 3.34541654 1 P 0 ;0,1=445,2=270.000000
L 4.7595 3.34541654 4.76105069 3.34848327 1 P 0 ;0,1=445,2=270.000000
L 4.76105069 3.34848327 4.76311693 3.3504002 1 P 0 ;0,1=445,2=270.000000
L 4.76311693 3.3504002 4.7672503 3.35116673 1 P 0 ;0,1=445,2=270.000000
L 4.7672503 3.35116673 4.77138366 3.3504002 1 P 0 ;0,1=445,2=270.000000
L 4.77138366 3.3504002 4.77396644 3.3481 1 P 0 ;0,1=445,2=270.000000
L 4.77396644 3.3481 4.77551713 3.34541654 1 P 0 ;0,1=445,2=270.000000
L 4.77551713 3.34541654 4.77551713 3.33583317 1 P 0 ;0,1=445,2=270.000000
L 4.77551713 3.34541654 4.7905 3.35116673 1 P 0 ;0,1=445,2=270.000000
L 4.7905 3.37449961 4.7595 3.37449961 1 P 0 ;0,1=445,2=270.000000
L 4.7595 3.37449961 4.7656997 3.3698999 1 P 0 ;0,1=445,2=270.000000
L 4.7905 3.3698999 4.7905 3.37909931 1 P 0 ;0,1=445,2=270.000000
L 4.7905 3.40549961 4.7595 3.40549961 1 P 0 ;0,1=445,2=270.000000
L 4.7595 3.40549961 4.7656997 3.4008999 1 P 0 ;0,1=445,2=270.000000
L 4.7905 3.4008999 4.7905 3.41009931 1 P 0 ;0,1=445,2=270.000000
L 4.77758425 3.42921644 4.77396644 3.4318999 1 P 0 ;0,1=445,2=270.000000
L 4.77396644 3.4318999 4.7719002 3.4342001 1 P 0 ;0,1=445,2=270.000000
L 4.7719002 3.4342001 4.77086713 3.43726683 1 P 0 ;0,1=445,2=270.000000
L 4.77086713 3.43726683 4.7719002 3.4399503 1 P 0 ;0,1=445,2=270.000000
L 4.7719002 3.4399503 4.77396644 3.44186654 1 P 0 ;0,1=445,2=270.000000
L 4.77396644 3.44186654 4.77706673 3.4434002 1 P 0 ;0,1=445,2=270.000000
L 4.77706673 3.4434002 4.78068356 3.44378346 1 P 0 ;0,1=445,2=270.000000
L 4.78068356 3.44378346 4.78378386 3.4434002 1 P 0 ;0,1=445,2=270.000000
L 4.78378386 3.4434002 4.78688415 3.44186654 1 P 0 ;0,1=445,2=270.000000
L 4.78688415 3.44186654 4.78946693 3.43956634 1 P 0 ;0,1=445,2=270.000000
L 4.78946693 3.43956634 4.7905 3.43688356 1 P 0 ;0,1=445,2=270.000000
L 4.7905 3.43688356 4.78946693 3.43381683 1 P 0 ;0,1=445,2=270.000000
L 4.78946693 3.43381683 4.78636762 3.43113337 1 P 0 ;0,1=445,2=270.000000
L 4.78636762 3.43113337 4.78171673 3.4295997 1 P 0 ;0,1=445,2=270.000000
L 4.78171673 3.4295997 4.7765502 3.42921644 1 P 0 ;0,1=445,2=270.000000
L 4.7765502 3.42921644 4.76983406 3.42998287 1 P 0 ;0,1=445,2=270.000000
L 4.76983406 3.42998287 4.76621624 3.43113337 1 P 0 ;0,1=445,2=270.000000
L 4.76621624 3.43113337 4.7626003 3.43304961 1 P 0 ;0,1=445,2=270.000000
L 4.7626003 3.43304961 4.76001663 3.43573307 1 P 0 ;0,1=445,2=270.000000
L 4.76001663 3.43573307 4.7595 3.43841654 1 P 0 ;0,1=445,2=270.000000
L 4.7595 3.43841654 4.76053317 3.4411 1 P 0 ;0,1=445,2=270.000000
L 4.76053317 3.4411 4.76311693 3.44301703 1 P 0 ;0,1=445,2=270.000000
L 4.857 3.57 4.813 3.57 1 P 0 
L 4.813 3.57 4.813 3.48 1 P 0 
L 4.813 3.48 4.857 3.48 1 P 0 
L 4.857 3.48 4.857 3.57 1 P 0 
L 4.8605 3.33583317 4.8295 3.33583317 1 P 0 ;0,1=446,2=270.000000
L 4.8295 3.33583317 4.8295 3.34541654 1 P 0 ;0,1=446,2=270.000000
L 4.8295 3.34541654 4.83105069 3.34848327 1 P 0 ;0,1=446,2=270.000000
L 4.83105069 3.34848327 4.83311693 3.3504002 1 P 0 ;0,1=446,2=270.000000
L 4.83311693 3.3504002 4.8372503 3.35116673 1 P 0 ;0,1=446,2=270.000000
L 4.8372503 3.35116673 4.84138366 3.3504002 1 P 0 ;0,1=446,2=270.000000
L 4.84138366 3.3504002 4.84396644 3.3481 1 P 0 ;0,1=446,2=270.000000
L 4.84396644 3.3481 4.84551713 3.34541654 1 P 0 ;0,1=446,2=270.000000
L 4.84551713 3.34541654 4.84551713 3.33583317 1 P 0 ;0,1=446,2=270.000000
L 4.84551713 3.34541654 4.8605 3.35116673 1 P 0 ;0,1=446,2=270.000000
L 4.8605 3.37449961 4.8295 3.37449961 1 P 0 ;0,1=446,2=270.000000
L 4.8295 3.37449961 4.8356997 3.3698999 1 P 0 ;0,1=446,2=270.000000
L 4.8605 3.3698999 4.8605 3.37909931 1 P 0 ;0,1=446,2=270.000000
L 4.8605 3.40549961 4.8295 3.40549961 1 P 0 ;0,1=446,2=270.000000
L 4.8295 3.40549961 4.8356997 3.4008999 1 P 0 ;0,1=446,2=270.000000
L 4.8605 3.4008999 4.8605 3.41009931 1 P 0 ;0,1=446,2=270.000000
L 4.8605 3.43573307 4.85378386 3.43649961 1 P 0 ;0,1=446,2=270.000000
L 4.85378386 3.43649961 4.84810079 3.4376501 1 P 0 ;0,1=446,2=270.000000
L 4.84810079 3.4376501 4.84293337 3.43918307 1 P 0 ;0,1=446,2=270.000000
L 4.84293337 3.43918307 4.8372503 3.4411 1 P 0 ;0,1=446,2=270.000000
L 4.8372503 3.4411 4.8295 3.44416673 1 P 0 ;0,1=446,2=270.000000
L 4.8295 3.44416673 4.8295 3.42883317 1 P 0 ;0,1=446,2=270.000000
L 4.907 3.48 4.907 3.57 1 P 0 
L 4.907 3.57 4.863 3.57 1 P 0 
L 4.863 3.48 4.907 3.48 1 P 0 
L 4.863 3.57 4.863 3.48 1 P 0 
L 4.9055 3.33583317 4.8745 3.33583317 1 P 0 ;0,1=447,2=270.000000
L 4.8745 3.33583317 4.8745 3.34541654 1 P 0 ;0,1=447,2=270.000000
L 4.8745 3.34541654 4.87605069 3.34848327 1 P 0 ;0,1=447,2=270.000000
L 4.87605069 3.34848327 4.87811693 3.3504002 1 P 0 ;0,1=447,2=270.000000
L 4.87811693 3.3504002 4.8822503 3.35116673 1 P 0 ;0,1=447,2=270.000000
L 4.8822503 3.35116673 4.88638366 3.3504002 1 P 0 ;0,1=447,2=270.000000
L 4.88638366 3.3504002 4.88896644 3.3481 1 P 0 ;0,1=447,2=270.000000
L 4.88896644 3.3481 4.89051713 3.34541654 1 P 0 ;0,1=447,2=270.000000
L 4.89051713 3.34541654 4.89051713 3.33583317 1 P 0 ;0,1=447,2=270.000000
L 4.89051713 3.34541654 4.9055 3.35116673 1 P 0 ;0,1=447,2=270.000000
L 4.9055 3.37449961 4.8745 3.37449961 1 P 0 ;0,1=447,2=270.000000
L 4.8745 3.37449961 4.8806997 3.3698999 1 P 0 ;0,1=447,2=270.000000
L 4.9055 3.3698999 4.9055 3.37909931 1 P 0 ;0,1=447,2=270.000000
L 4.9055 3.40549961 4.8745 3.40549961 1 P 0 ;0,1=447,2=270.000000
L 4.8745 3.40549961 4.8806997 3.4008999 1 P 0 ;0,1=447,2=270.000000
L 4.9055 3.4008999 4.9055 3.41009931 1 P 0 ;0,1=447,2=270.000000
L 4.89930039 3.42806663 4.90291722 3.43036614 1 P 0 ;0,1=447,2=270.000000
L 4.90291722 3.43036614 4.90498346 3.43343287 1 P 0 ;0,1=447,2=270.000000
L 4.90498346 3.43343287 4.9055 3.43688356 1 P 0 ;0,1=447,2=270.000000
L 4.9055 3.43688356 4.90498346 3.4399503 1 P 0 ;0,1=447,2=270.000000
L 4.90498346 3.4399503 4.90240069 3.44301703 1 P 0 ;0,1=447,2=270.000000
L 4.90240069 3.44301703 4.89930039 3.44493327 1 P 0 ;0,1=447,2=270.000000
L 4.89930039 3.44493327 4.8962001 3.44531654 1 P 0 ;0,1=447,2=270.000000
L 4.8962001 3.44531654 4.89258425 3.44455 1 P 0 ;0,1=447,2=270.000000
L 4.89258425 3.44455 4.89000049 3.44186654 1 P 0 ;0,1=447,2=270.000000
L 4.89000049 3.44186654 4.88896644 3.43918307 1 P 0 ;0,1=447,2=270.000000
L 4.88896644 3.43918307 4.88896644 3.43573307 1 P 0 ;0,1=447,2=270.000000
L 4.88896644 3.43918307 4.88741683 3.44148327 1 P 0 ;0,1=447,2=270.000000
L 4.88741683 3.44148327 4.88483406 3.4434002 1 P 0 ;0,1=447,2=270.000000
L 4.88483406 3.4434002 4.88173376 3.44416673 1 P 0 ;0,1=447,2=270.000000
L 4.88173376 3.44416673 4.87863346 3.4434002 1 P 0 ;0,1=447,2=270.000000
L 4.87863346 3.4434002 4.87605069 3.44148327 1 P 0 ;0,1=447,2=270.000000
L 4.87605069 3.44148327 4.8745 3.43803327 1 P 0 ;0,1=447,2=270.000000
L 4.8745 3.43803327 4.87501663 3.43458337 1 P 0 ;0,1=447,2=270.000000
L 4.87501663 3.43458337 4.87708376 3.43113337 1 P 0 ;0,1=447,2=270.000000
L 4.757 3.57 4.713 3.57 1 P 0 
L 4.713 3.57 4.713 3.48 1 P 0 
L 4.713 3.48 4.757 3.48 1 P 0 
L 4.757 3.48 4.757 3.57 1 P 0 
L 4.7455 3.33583317 4.7145 3.33583317 1 P 0 ;0,1=448,2=270.000000
L 4.7145 3.33583317 4.7145 3.34541654 1 P 0 ;0,1=448,2=270.000000
L 4.7145 3.34541654 4.71605069 3.34848327 1 P 0 ;0,1=448,2=270.000000
L 4.71605069 3.34848327 4.71811693 3.3504002 1 P 0 ;0,1=448,2=270.000000
L 4.71811693 3.3504002 4.7222503 3.35116673 1 P 0 ;0,1=448,2=270.000000
L 4.7222503 3.35116673 4.72638366 3.3504002 1 P 0 ;0,1=448,2=270.000000
L 4.72638366 3.3504002 4.72896644 3.3481 1 P 0 ;0,1=448,2=270.000000
L 4.72896644 3.3481 4.73051713 3.34541654 1 P 0 ;0,1=448,2=270.000000
L 4.73051713 3.34541654 4.73051713 3.33583317 1 P 0 ;0,1=448,2=270.000000
L 4.73051713 3.34541654 4.7455 3.35116673 1 P 0 ;0,1=448,2=270.000000
L 4.7455 3.37449961 4.7145 3.37449961 1 P 0 ;0,1=448,2=270.000000
L 4.7145 3.37449961 4.7206997 3.3698999 1 P 0 ;0,1=448,2=270.000000
L 4.7455 3.3698999 4.7455 3.37909931 1 P 0 ;0,1=448,2=270.000000
L 4.7455 3.40549961 4.7145 3.40549961 1 P 0 ;0,1=448,2=270.000000
L 4.7145 3.40549961 4.7206997 3.4008999 1 P 0 ;0,1=448,2=270.000000
L 4.7455 3.4008999 4.7455 3.41009931 1 P 0 ;0,1=448,2=270.000000
L 4.7455 3.4411 4.7145 3.4411 1 P 0 ;0,1=448,2=270.000000
L 4.7145 3.4411 4.73671673 3.42691624 1 P 0 ;0,1=448,2=270.000000
L 4.73671673 3.42691624 4.73671673 3.44608366 1 P 0 ;0,1=448,2=270.000000
L 4.42 3.893 4.42 3.937 1 P 0 
L 4.42 3.937 4.33 3.937 1 P 0 
L 4.33 3.937 4.33 3.893 1 P 0 
L 4.33 3.893 4.42 3.893 1 P 0 
L 4.45083317 4.0245 4.45083317 4.0555 1 P 0 ;0,1=449,2=0.000000
L 4.45083317 4.0555 4.46041654 4.0555 1 P 0 ;0,1=449,2=0.000000
L 4.46041654 4.0555 4.46348327 4.05394931 1 P 0 ;0,1=449,2=0.000000
L 4.46348327 4.05394931 4.4654002 4.05188307 1 P 0 ;0,1=449,2=0.000000
L 4.4654002 4.05188307 4.46616673 4.0477497 1 P 0 ;0,1=449,2=0.000000
L 4.46616673 4.0477497 4.4654002 4.04361634 1 P 0 ;0,1=449,2=0.000000
L 4.4654002 4.04361634 4.4631 4.04103356 1 P 0 ;0,1=449,2=0.000000
L 4.4631 4.04103356 4.46041654 4.03948287 1 P 0 ;0,1=449,2=0.000000
L 4.46041654 4.03948287 4.45083317 4.03948287 1 P 0 ;0,1=449,2=0.000000
L 4.46041654 4.03948287 4.46616673 4.0245 1 P 0 ;0,1=449,2=0.000000
L 4.48106663 4.03069961 4.48336614 4.02708278 1 P 0 ;0,1=449,2=0.000000
L 4.48336614 4.02708278 4.48643287 4.02501654 1 P 0 ;0,1=449,2=0.000000
L 4.48643287 4.02501654 4.48988356 4.0245 1 P 0 ;0,1=449,2=0.000000
L 4.48988356 4.0245 4.4929503 4.02501654 1 P 0 ;0,1=449,2=0.000000
L 4.4929503 4.02501654 4.49601703 4.02759931 1 P 0 ;0,1=449,2=0.000000
L 4.49601703 4.02759931 4.49793327 4.03069961 1 P 0 ;0,1=449,2=0.000000
L 4.49793327 4.03069961 4.49831654 4.0337999 1 P 0 ;0,1=449,2=0.000000
L 4.49831654 4.0337999 4.49755 4.03741575 1 P 0 ;0,1=449,2=0.000000
L 4.49755 4.03741575 4.49486654 4.03999951 1 P 0 ;0,1=449,2=0.000000
L 4.49486654 4.03999951 4.49218307 4.04103356 1 P 0 ;0,1=449,2=0.000000
L 4.49218307 4.04103356 4.48873307 4.04103356 1 P 0 ;0,1=449,2=0.000000
L 4.49218307 4.04103356 4.49448327 4.04258317 1 P 0 ;0,1=449,2=0.000000
L 4.49448327 4.04258317 4.4964002 4.04516594 1 P 0 ;0,1=449,2=0.000000
L 4.4964002 4.04516594 4.49716673 4.04826624 1 P 0 ;0,1=449,2=0.000000
L 4.49716673 4.04826624 4.4964002 4.05136654 1 P 0 ;0,1=449,2=0.000000
L 4.4964002 4.05136654 4.49448327 4.05394931 1 P 0 ;0,1=449,2=0.000000
L 4.49448327 4.05394931 4.49103327 4.0555 1 P 0 ;0,1=449,2=0.000000
L 4.49103327 4.0555 4.48758337 4.05498337 1 P 0 ;0,1=449,2=0.000000
L 4.48758337 4.05498337 4.48413337 4.05291624 1 P 0 ;0,1=449,2=0.000000
L 4.51321644 4.05033346 4.51551663 4.05343278 1 P 0 ;0,1=449,2=0.000000
L 4.51551663 4.05343278 4.5182001 4.05498337 1 P 0 ;0,1=449,2=0.000000
L 4.5182001 4.05498337 4.52126683 4.0555 1 P 0 ;0,1=449,2=0.000000
L 4.52126683 4.0555 4.5251 4.05446683 1 P 0 ;0,1=449,2=0.000000
L 4.5251 4.05446683 4.52778346 4.05188307 1 P 0 ;0,1=449,2=0.000000
L 4.52778346 4.05188307 4.52855 4.04878376 1 P 0 ;0,1=449,2=0.000000
L 4.52855 4.04878376 4.52816673 4.04568258 1 P 0 ;0,1=449,2=0.000000
L 4.52816673 4.04568258 4.52663307 4.0430998 1 P 0 ;0,1=449,2=0.000000
L 4.52663307 4.0430998 4.51896663 4.03793327 1 P 0 ;0,1=449,2=0.000000
L 4.51896663 4.03793327 4.51551663 4.03431644 1 P 0 ;0,1=449,2=0.000000
L 4.51551663 4.03431644 4.51321644 4.02914892 1 P 0 ;0,1=449,2=0.000000
L 4.51321644 4.02914892 4.5124499 4.0245 1 P 0 ;0,1=449,2=0.000000
L 4.5124499 4.0245 4.52855 4.0245 1 P 0 ;0,1=449,2=0.000000
L 4.5561 4.0245 4.5561 4.0555 1 P 0 ;0,1=449,2=0.000000
L 4.5561 4.0555 4.54191624 4.03328327 1 P 0 ;0,1=449,2=0.000000
L 4.54191624 4.03328327 4.56108366 4.03328327 1 P 0 ;0,1=449,2=0.000000
L 4.42 3.993 4.42 4.037 1 P 0 
L 4.33 3.993 4.42 3.993 1 P 0 
L 4.42 4.037 4.33 4.037 1 P 0 
L 4.33 4.037 4.33 3.993 1 P 0 
L 4.44583317 4.1245 4.44583317 4.1555 1 P 0 ;0,1=450,2=0.000000
L 4.44583317 4.1555 4.45541654 4.1555 1 P 0 ;0,1=450,2=0.000000
L 4.45541654 4.1555 4.45848327 4.15394931 1 P 0 ;0,1=450,2=0.000000
L 4.45848327 4.15394931 4.4604002 4.15188307 1 P 0 ;0,1=450,2=0.000000
L 4.4604002 4.15188307 4.46116673 4.1477497 1 P 0 ;0,1=450,2=0.000000
L 4.46116673 4.1477497 4.4604002 4.14361634 1 P 0 ;0,1=450,2=0.000000
L 4.4604002 4.14361634 4.4581 4.14103356 1 P 0 ;0,1=450,2=0.000000
L 4.4581 4.14103356 4.45541654 4.13948287 1 P 0 ;0,1=450,2=0.000000
L 4.45541654 4.13948287 4.44583317 4.13948287 1 P 0 ;0,1=450,2=0.000000
L 4.45541654 4.13948287 4.46116673 4.1245 1 P 0 ;0,1=450,2=0.000000
L 4.47606663 4.13069961 4.47836614 4.12708278 1 P 0 ;0,1=450,2=0.000000
L 4.47836614 4.12708278 4.48143287 4.12501654 1 P 0 ;0,1=450,2=0.000000
L 4.48143287 4.12501654 4.48488356 4.1245 1 P 0 ;0,1=450,2=0.000000
L 4.48488356 4.1245 4.4879503 4.12501654 1 P 0 ;0,1=450,2=0.000000
L 4.4879503 4.12501654 4.49101703 4.12759931 1 P 0 ;0,1=450,2=0.000000
L 4.49101703 4.12759931 4.49293327 4.13069961 1 P 0 ;0,1=450,2=0.000000
L 4.49293327 4.13069961 4.49331654 4.1337999 1 P 0 ;0,1=450,2=0.000000
L 4.49331654 4.1337999 4.49255 4.13741575 1 P 0 ;0,1=450,2=0.000000
L 4.49255 4.13741575 4.48986654 4.13999951 1 P 0 ;0,1=450,2=0.000000
L 4.48986654 4.13999951 4.48718307 4.14103356 1 P 0 ;0,1=450,2=0.000000
L 4.48718307 4.14103356 4.48373307 4.14103356 1 P 0 ;0,1=450,2=0.000000
L 4.48718307 4.14103356 4.48948327 4.14258317 1 P 0 ;0,1=450,2=0.000000
L 4.48948327 4.14258317 4.4914002 4.14516594 1 P 0 ;0,1=450,2=0.000000
L 4.4914002 4.14516594 4.49216673 4.14826624 1 P 0 ;0,1=450,2=0.000000
L 4.49216673 4.14826624 4.4914002 4.15136654 1 P 0 ;0,1=450,2=0.000000
L 4.4914002 4.15136654 4.48948327 4.15394931 1 P 0 ;0,1=450,2=0.000000
L 4.48948327 4.15394931 4.48603327 4.1555 1 P 0 ;0,1=450,2=0.000000
L 4.48603327 4.1555 4.48258337 4.15498337 1 P 0 ;0,1=450,2=0.000000
L 4.48258337 4.15498337 4.47913337 4.15291624 1 P 0 ;0,1=450,2=0.000000
L 4.50821644 4.15033346 4.51051663 4.15343278 1 P 0 ;0,1=450,2=0.000000
L 4.51051663 4.15343278 4.5132001 4.15498337 1 P 0 ;0,1=450,2=0.000000
L 4.5132001 4.15498337 4.51626683 4.1555 1 P 0 ;0,1=450,2=0.000000
L 4.51626683 4.1555 4.5201 4.15446683 1 P 0 ;0,1=450,2=0.000000
L 4.5201 4.15446683 4.52278346 4.15188307 1 P 0 ;0,1=450,2=0.000000
L 4.52278346 4.15188307 4.52355 4.14878376 1 P 0 ;0,1=450,2=0.000000
L 4.52355 4.14878376 4.52316673 4.14568258 1 P 0 ;0,1=450,2=0.000000
L 4.52316673 4.14568258 4.52163307 4.1430998 1 P 0 ;0,1=450,2=0.000000
L 4.52163307 4.1430998 4.51396663 4.13793327 1 P 0 ;0,1=450,2=0.000000
L 4.51396663 4.13793327 4.51051663 4.13431644 1 P 0 ;0,1=450,2=0.000000
L 4.51051663 4.13431644 4.50821644 4.12914892 1 P 0 ;0,1=450,2=0.000000
L 4.50821644 4.12914892 4.5074499 4.1245 1 P 0 ;0,1=450,2=0.000000
L 4.5074499 4.1245 4.52355 4.1245 1 P 0 ;0,1=450,2=0.000000
L 4.53806663 4.13069961 4.54036614 4.12708278 1 P 0 ;0,1=450,2=0.000000
L 4.54036614 4.12708278 4.54343287 4.12501654 1 P 0 ;0,1=450,2=0.000000
L 4.54343287 4.12501654 4.54688356 4.1245 1 P 0 ;0,1=450,2=0.000000
L 4.54688356 4.1245 4.5499503 4.12501654 1 P 0 ;0,1=450,2=0.000000
L 4.5499503 4.12501654 4.55301703 4.12759931 1 P 0 ;0,1=450,2=0.000000
L 4.55301703 4.12759931 4.55493327 4.13069961 1 P 0 ;0,1=450,2=0.000000
L 4.55493327 4.13069961 4.55531654 4.1337999 1 P 0 ;0,1=450,2=0.000000
L 4.55531654 4.1337999 4.55455 4.13741575 1 P 0 ;0,1=450,2=0.000000
L 4.55455 4.13741575 4.55186654 4.13999951 1 P 0 ;0,1=450,2=0.000000
L 4.55186654 4.13999951 4.54918307 4.14103356 1 P 0 ;0,1=450,2=0.000000
L 4.54918307 4.14103356 4.54573307 4.14103356 1 P 0 ;0,1=450,2=0.000000
L 4.54918307 4.14103356 4.55148327 4.14258317 1 P 0 ;0,1=450,2=0.000000
L 4.55148327 4.14258317 4.5534002 4.14516594 1 P 0 ;0,1=450,2=0.000000
L 4.5534002 4.14516594 4.55416673 4.14826624 1 P 0 ;0,1=450,2=0.000000
L 4.55416673 4.14826624 4.5534002 4.15136654 1 P 0 ;0,1=450,2=0.000000
L 4.5534002 4.15136654 4.55148327 4.15394931 1 P 0 ;0,1=450,2=0.000000
L 4.55148327 4.15394931 4.54803327 4.1555 1 P 0 ;0,1=450,2=0.000000
L 4.54803327 4.1555 4.54458337 4.15498337 1 P 0 ;0,1=450,2=0.000000
L 4.54458337 4.15498337 4.54113337 4.15291624 1 P 0 ;0,1=450,2=0.000000
L 5.337 2.745 5.337 2.835 1 P 0 
L 5.337 2.835 5.293 2.835 1 P 0 
L 5.293 2.835 5.293 2.745 1 P 0 
L 5.293 2.745 5.337 2.745 1 P 0 
L 5.3655 2.90083317 5.3345 2.90083317 1 P 0 ;0,1=451,2=270.000000
L 5.3345 2.90083317 5.3345 2.91041654 1 P 0 ;0,1=451,2=270.000000
L 5.3345 2.91041654 5.33605069 2.91348327 1 P 0 ;0,1=451,2=270.000000
L 5.33605069 2.91348327 5.33811693 2.9154002 1 P 0 ;0,1=451,2=270.000000
L 5.33811693 2.9154002 5.3422503 2.91616673 1 P 0 ;0,1=451,2=270.000000
L 5.3422503 2.91616673 5.34638366 2.9154002 1 P 0 ;0,1=451,2=270.000000
L 5.34638366 2.9154002 5.34896644 2.9131 1 P 0 ;0,1=451,2=270.000000
L 5.34896644 2.9131 5.35051713 2.91041654 1 P 0 ;0,1=451,2=270.000000
L 5.35051713 2.91041654 5.35051713 2.90083317 1 P 0 ;0,1=451,2=270.000000
L 5.35051713 2.91041654 5.3655 2.91616673 1 P 0 ;0,1=451,2=270.000000
L 5.3655 2.93949961 5.3345 2.93949961 1 P 0 ;0,1=451,2=270.000000
L 5.3345 2.93949961 5.3406997 2.9348999 1 P 0 ;0,1=451,2=270.000000
L 5.3655 2.9348999 5.3655 2.94409931 1 P 0 ;0,1=451,2=270.000000
L 5.3655 2.97049961 5.36498346 2.97318307 1 P 0 ;0,1=451,2=270.000000
L 5.36498346 2.97318307 5.36343386 2.9762498 1 P 0 ;0,1=451,2=270.000000
L 5.36343386 2.9762498 5.36085108 2.97816673 1 P 0 ;0,1=451,2=270.000000
L 5.36085108 2.97816673 5.35723327 2.97893327 1 P 0 ;0,1=451,2=270.000000
L 5.35723327 2.97893327 5.35361732 2.97816673 1 P 0 ;0,1=451,2=270.000000
L 5.35361732 2.97816673 5.35051713 2.97586654 1 P 0 ;0,1=451,2=270.000000
L 5.35051713 2.97586654 5.34896644 2.97241654 1 P 0 ;0,1=451,2=270.000000
L 5.34896644 2.97241654 5.34896644 2.96858337 1 P 0 ;0,1=451,2=270.000000
L 5.34896644 2.96858337 5.34793337 2.96628317 1 P 0 ;0,1=451,2=270.000000
L 5.34793337 2.96628317 5.34535059 2.96436614 1 P 0 ;0,1=451,2=270.000000
L 5.34535059 2.96436614 5.34173376 2.9635997 1 P 0 ;0,1=451,2=270.000000
L 5.34173376 2.9635997 5.33811693 2.9647501 1 P 0 ;0,1=451,2=270.000000
L 5.33811693 2.9647501 5.33553317 2.96743287 1 P 0 ;0,1=451,2=270.000000
L 5.33553317 2.96743287 5.3345 2.97049961 1 P 0 ;0,1=451,2=270.000000
L 5.3345 2.97049961 5.33553317 2.97356634 1 P 0 ;0,1=451,2=270.000000
L 5.33553317 2.97356634 5.33811693 2.9762498 1 P 0 ;0,1=451,2=270.000000
L 5.33811693 2.9762498 5.34173376 2.9774002 1 P 0 ;0,1=451,2=270.000000
L 5.34173376 2.9774002 5.34535059 2.97663307 1 P 0 ;0,1=451,2=270.000000
L 5.34535059 2.97663307 5.34793337 2.97471673 1 P 0 ;0,1=451,2=270.000000
L 5.34793337 2.97471673 5.34896644 2.97241654 1 P 0 ;0,1=451,2=270.000000
L 5.34896644 2.97241654 5.34896644 2.96858337 1 P 0 ;0,1=451,2=270.000000
L 5.34896644 2.96858337 5.35051713 2.96513337 1 P 0 ;0,1=451,2=270.000000
L 5.35051713 2.96513337 5.35361732 2.96283317 1 P 0 ;0,1=451,2=270.000000
L 5.35361732 2.96283317 5.35723327 2.96206663 1 P 0 ;0,1=451,2=270.000000
L 5.35723327 2.96206663 5.36085108 2.96283317 1 P 0 ;0,1=451,2=270.000000
L 5.36085108 2.96283317 5.36343386 2.9647501 1 P 0 ;0,1=451,2=270.000000
L 5.36343386 2.9647501 5.36498346 2.96781683 1 P 0 ;0,1=451,2=270.000000
L 5.36498346 2.96781683 5.3655 2.97049961 1 P 0 ;0,1=451,2=270.000000
L 5.33966654 2.99421644 5.33656722 2.99651663 1 P 0 ;0,1=451,2=270.000000
L 5.33656722 2.99651663 5.33501663 2.9992001 1 P 0 ;0,1=451,2=270.000000
L 5.33501663 2.9992001 5.3345 3.00226683 1 P 0 ;0,1=451,2=270.000000
L 5.3345 3.00226683 5.33553317 3.0061 1 P 0 ;0,1=451,2=270.000000
L 5.33553317 3.0061 5.33811693 3.00878346 1 P 0 ;0,1=451,2=270.000000
L 5.33811693 3.00878346 5.34121624 3.00955 1 P 0 ;0,1=451,2=270.000000
L 5.34121624 3.00955 5.34431742 3.00916673 1 P 0 ;0,1=451,2=270.000000
L 5.34431742 3.00916673 5.3469002 3.00763307 1 P 0 ;0,1=451,2=270.000000
L 5.3469002 3.00763307 5.35206673 2.99996663 1 P 0 ;0,1=451,2=270.000000
L 5.35206673 2.99996663 5.35568356 2.99651663 1 P 0 ;0,1=451,2=270.000000
L 5.35568356 2.99651663 5.36085108 2.99421644 1 P 0 ;0,1=451,2=270.000000
L 5.36085108 2.99421644 5.3655 2.9934499 1 P 0 ;0,1=451,2=270.000000
L 5.3655 2.9934499 5.3655 3.00955 1 P 0 ;0,1=451,2=270.000000
L 5.248 2.835 5.248 2.745 1 P 0 
L 5.248 2.745 5.292 2.745 1 P 0 
L 5.292 2.745 5.292 2.835 1 P 0 
L 5.292 2.835 5.248 2.835 1 P 0 
L 5.3255 2.90083317 5.2945 2.90083317 1 P 0 ;0,1=452,2=270.000000
L 5.2945 2.90083317 5.2945 2.91041654 1 P 0 ;0,1=452,2=270.000000
L 5.2945 2.91041654 5.29605069 2.91348327 1 P 0 ;0,1=452,2=270.000000
L 5.29605069 2.91348327 5.29811693 2.9154002 1 P 0 ;0,1=452,2=270.000000
L 5.29811693 2.9154002 5.3022503 2.91616673 1 P 0 ;0,1=452,2=270.000000
L 5.3022503 2.91616673 5.30638366 2.9154002 1 P 0 ;0,1=452,2=270.000000
L 5.30638366 2.9154002 5.30896644 2.9131 1 P 0 ;0,1=452,2=270.000000
L 5.30896644 2.9131 5.31051713 2.91041654 1 P 0 ;0,1=452,2=270.000000
L 5.31051713 2.91041654 5.31051713 2.90083317 1 P 0 ;0,1=452,2=270.000000
L 5.31051713 2.91041654 5.3255 2.91616673 1 P 0 ;0,1=452,2=270.000000
L 5.3255 2.93949961 5.2945 2.93949961 1 P 0 ;0,1=452,2=270.000000
L 5.2945 2.93949961 5.3006997 2.9348999 1 P 0 ;0,1=452,2=270.000000
L 5.3255 2.9348999 5.3255 2.94409931 1 P 0 ;0,1=452,2=270.000000
L 5.3255 2.96973307 5.31878386 2.97049961 1 P 0 ;0,1=452,2=270.000000
L 5.31878386 2.97049961 5.31310079 2.9716501 1 P 0 ;0,1=452,2=270.000000
L 5.31310079 2.9716501 5.30793337 2.97318307 1 P 0 ;0,1=452,2=270.000000
L 5.30793337 2.97318307 5.3022503 2.9751 1 P 0 ;0,1=452,2=270.000000
L 5.3022503 2.9751 5.2945 2.97816673 1 P 0 ;0,1=452,2=270.000000
L 5.2945 2.97816673 5.2945 2.96283317 1 P 0 ;0,1=452,2=270.000000
L 5.32188415 2.99498287 5.32446693 2.99766634 1 P 0 ;0,1=452,2=270.000000
L 5.32446693 2.99766634 5.3255 3.00073307 1 P 0 ;0,1=452,2=270.000000
L 5.3255 3.00073307 5.32446693 3.0037998 1 P 0 ;0,1=452,2=270.000000
L 5.32446693 3.0037998 5.32136762 3.00648327 1 P 0 ;0,1=452,2=270.000000
L 5.32136762 3.00648327 5.31671673 3.0084002 1 P 0 ;0,1=452,2=270.000000
L 5.31671673 3.0084002 5.31206673 3.00916673 1 P 0 ;0,1=452,2=270.000000
L 5.31206673 3.00916673 5.30638366 3.00916673 1 P 0 ;0,1=452,2=270.000000
L 5.30638366 3.00916673 5.30173376 3.0084002 1 P 0 ;0,1=452,2=270.000000
L 5.30173376 3.0084002 5.2976003 3.00648327 1 P 0 ;0,1=452,2=270.000000
L 5.2976003 3.00648327 5.29553317 3.00418307 1 P 0 ;0,1=452,2=270.000000
L 5.29553317 3.00418307 5.2945 3.00149961 1 P 0 ;0,1=452,2=270.000000
L 5.2945 3.00149961 5.29553317 2.99843287 1 P 0 ;0,1=452,2=270.000000
L 5.29553317 2.99843287 5.2976003 2.99613337 1 P 0 ;0,1=452,2=270.000000
L 5.2976003 2.99613337 5.3006997 2.9945997 1 P 0 ;0,1=452,2=270.000000
L 5.3006997 2.9945997 5.30483406 2.99383317 1 P 0 ;0,1=452,2=270.000000
L 5.30483406 2.99383317 5.3084499 2.9945997 1 P 0 ;0,1=452,2=270.000000
L 5.3084499 2.9945997 5.31206673 2.99651663 1 P 0 ;0,1=452,2=270.000000
L 5.31206673 2.99651663 5.31413396 2.99881683 1 P 0 ;0,1=452,2=270.000000
L 5.31413396 2.99881683 5.31465049 3.00149961 1 P 0 ;0,1=452,2=270.000000
L 5.31465049 3.00149961 5.31361732 3.00456634 1 P 0 ;0,1=452,2=270.000000
L 5.31361732 3.00456634 5.31103366 3.00686654 1 P 0 ;0,1=452,2=270.000000
L 5.31103366 3.00686654 5.30638366 3.00916673 1 P 0 ;0,1=452,2=270.000000
L 4 2.576 3.956 2.576 1 P 0 
L 3.956 2.576 3.956 2.486 1 P 0 
L 3.956 2.486 4 2.486 1 P 0 
L 4 2.486 4 2.576 1 P 0 
L 4.0255 2.37083317 3.9945 2.37083317 1 P 0 ;0,1=453,2=270.000000
L 3.9945 2.37083317 3.9945 2.38041654 1 P 0 ;0,1=453,2=270.000000
L 3.9945 2.38041654 3.99605069 2.38348327 1 P 0 ;0,1=453,2=270.000000
L 3.99605069 2.38348327 3.99811693 2.3854002 1 P 0 ;0,1=453,2=270.000000
L 3.99811693 2.3854002 4.0022503 2.38616673 1 P 0 ;0,1=453,2=270.000000
L 4.0022503 2.38616673 4.00638366 2.3854002 1 P 0 ;0,1=453,2=270.000000
L 4.00638366 2.3854002 4.00896644 2.3831 1 P 0 ;0,1=453,2=270.000000
L 4.00896644 2.3831 4.01051713 2.38041654 1 P 0 ;0,1=453,2=270.000000
L 4.01051713 2.38041654 4.01051713 2.37083317 1 P 0 ;0,1=453,2=270.000000
L 4.01051713 2.38041654 4.0255 2.38616673 1 P 0 ;0,1=453,2=270.000000
L 4.0255 2.40949961 3.9945 2.40949961 1 P 0 ;0,1=453,2=270.000000
L 3.9945 2.40949961 4.0006997 2.4048999 1 P 0 ;0,1=453,2=270.000000
L 4.0255 2.4048999 4.0255 2.41409931 1 P 0 ;0,1=453,2=270.000000
L 4.0255 2.43973307 4.01878386 2.44049961 1 P 0 ;0,1=453,2=270.000000
L 4.01878386 2.44049961 4.01310079 2.4416501 1 P 0 ;0,1=453,2=270.000000
L 4.01310079 2.4416501 4.00793337 2.44318307 1 P 0 ;0,1=453,2=270.000000
L 4.00793337 2.44318307 4.0022503 2.4451 1 P 0 ;0,1=453,2=270.000000
L 4.0022503 2.4451 3.9945 2.44816673 1 P 0 ;0,1=453,2=270.000000
L 3.9945 2.44816673 3.9945 2.43283317 1 P 0 ;0,1=453,2=270.000000
L 3.9945 2.47149961 3.99553317 2.46843287 1 P 0 ;0,1=453,2=270.000000
L 3.99553317 2.46843287 3.99811693 2.46613337 1 P 0 ;0,1=453,2=270.000000
L 3.99811693 2.46613337 4.00121624 2.4645997 1 P 0 ;0,1=453,2=270.000000
L 4.00121624 2.4645997 4.00535059 2.4634499 1 P 0 ;0,1=453,2=270.000000
L 4.00535059 2.4634499 4.01000049 2.46306663 1 P 0 ;0,1=453,2=270.000000
L 4.01000049 2.46306663 4.01465049 2.4634499 1 P 0 ;0,1=453,2=270.000000
L 4.01465049 2.4634499 4.01878386 2.4645997 1 P 0 ;0,1=453,2=270.000000
L 4.01878386 2.4645997 4.02188415 2.46613337 1 P 0 ;0,1=453,2=270.000000
L 4.02188415 2.46613337 4.02446693 2.46843287 1 P 0 ;0,1=453,2=270.000000
L 4.02446693 2.46843287 4.0255 2.47149961 1 P 0 ;0,1=453,2=270.000000
L 4.0255 2.47149961 4.02446693 2.47456634 1 P 0 ;0,1=453,2=270.000000
L 4.02446693 2.47456634 4.02188415 2.47686654 1 P 0 ;0,1=453,2=270.000000
L 4.02188415 2.47686654 4.01878386 2.4784002 1 P 0 ;0,1=453,2=270.000000
L 4.01878386 2.4784002 4.01465049 2.47955 1 P 0 ;0,1=453,2=270.000000
L 4.01465049 2.47955 4.01000049 2.47993327 1 P 0 ;0,1=453,2=270.000000
L 4.01000049 2.47993327 4.00535059 2.47955 1 P 0 ;0,1=453,2=270.000000
L 4.00535059 2.47955 4.00121624 2.4784002 1 P 0 ;0,1=453,2=270.000000
L 4.00121624 2.4784002 3.99811693 2.47686654 1 P 0 ;0,1=453,2=270.000000
L 3.99811693 2.47686654 3.99553317 2.47456634 1 P 0 ;0,1=453,2=270.000000
L 3.99553317 2.47456634 3.9945 2.47149961 1 P 0 ;0,1=453,2=270.000000
L 3.941 2.576 3.897 2.576 1 P 0 
L 3.897 2.576 3.897 2.486 1 P 0 
L 3.897 2.486 3.941 2.486 1 P 0 
L 3.941 2.486 3.941 2.576 1 P 0 
L 3.9605 2.37083317 3.9295 2.37083317 1 P 0 ;0,1=454,2=270.000000
L 3.9295 2.37083317 3.9295 2.38041654 1 P 0 ;0,1=454,2=270.000000
L 3.9295 2.38041654 3.93105069 2.38348327 1 P 0 ;0,1=454,2=270.000000
L 3.93105069 2.38348327 3.93311693 2.3854002 1 P 0 ;0,1=454,2=270.000000
L 3.93311693 2.3854002 3.9372503 2.38616673 1 P 0 ;0,1=454,2=270.000000
L 3.9372503 2.38616673 3.94138366 2.3854002 1 P 0 ;0,1=454,2=270.000000
L 3.94138366 2.3854002 3.94396644 2.3831 1 P 0 ;0,1=454,2=270.000000
L 3.94396644 2.3831 3.94551713 2.38041654 1 P 0 ;0,1=454,2=270.000000
L 3.94551713 2.38041654 3.94551713 2.37083317 1 P 0 ;0,1=454,2=270.000000
L 3.94551713 2.38041654 3.9605 2.38616673 1 P 0 ;0,1=454,2=270.000000
L 3.9605 2.40949961 3.9295 2.40949961 1 P 0 ;0,1=454,2=270.000000
L 3.9295 2.40949961 3.9356997 2.4048999 1 P 0 ;0,1=454,2=270.000000
L 3.9605 2.4048999 3.9605 2.41409931 1 P 0 ;0,1=454,2=270.000000
L 3.9605 2.43973307 3.95378386 2.44049961 1 P 0 ;0,1=454,2=270.000000
L 3.95378386 2.44049961 3.94810079 2.4416501 1 P 0 ;0,1=454,2=270.000000
L 3.94810079 2.4416501 3.94293337 2.44318307 1 P 0 ;0,1=454,2=270.000000
L 3.94293337 2.44318307 3.9372503 2.4451 1 P 0 ;0,1=454,2=270.000000
L 3.9372503 2.4451 3.9295 2.44816673 1 P 0 ;0,1=454,2=270.000000
L 3.9295 2.44816673 3.9295 2.43283317 1 P 0 ;0,1=454,2=270.000000
L 3.93466654 2.46421644 3.93156722 2.46651663 1 P 0 ;0,1=454,2=270.000000
L 3.93156722 2.46651663 3.93001663 2.4692001 1 P 0 ;0,1=454,2=270.000000
L 3.93001663 2.4692001 3.9295 2.47226683 1 P 0 ;0,1=454,2=270.000000
L 3.9295 2.47226683 3.93053317 2.4761 1 P 0 ;0,1=454,2=270.000000
L 3.93053317 2.4761 3.93311693 2.47878346 1 P 0 ;0,1=454,2=270.000000
L 3.93311693 2.47878346 3.93621624 2.47955 1 P 0 ;0,1=454,2=270.000000
L 3.93621624 2.47955 3.93931742 2.47916673 1 P 0 ;0,1=454,2=270.000000
L 3.93931742 2.47916673 3.9419002 2.47763307 1 P 0 ;0,1=454,2=270.000000
L 3.9419002 2.47763307 3.94706673 2.46996663 1 P 0 ;0,1=454,2=270.000000
L 3.94706673 2.46996663 3.95068356 2.46651663 1 P 0 ;0,1=454,2=270.000000
L 3.95068356 2.46651663 3.95585108 2.46421644 1 P 0 ;0,1=454,2=270.000000
L 3.95585108 2.46421644 3.9605 2.4634499 1 P 0 ;0,1=454,2=270.000000
L 3.9605 2.4634499 3.9605 2.47955 1 P 0 ;0,1=454,2=270.000000
L 5.63 2.378 5.72 2.378 1 P 0 
L 5.72 2.378 5.72 2.422 1 P 0 
L 5.72 2.422 5.63 2.422 1 P 0 
L 5.63 2.422 5.63 2.378 1 P 0 
L 5.53083317 2.5245 5.53083317 2.5555 1 P 0 ;0,1=455,2=0.000000
L 5.53083317 2.5555 5.54041654 2.5555 1 P 0 ;0,1=455,2=0.000000
L 5.54041654 2.5555 5.54348327 2.55394931 1 P 0 ;0,1=455,2=0.000000
L 5.54348327 2.55394931 5.5454002 2.55188307 1 P 0 ;0,1=455,2=0.000000
L 5.5454002 2.55188307 5.54616673 2.5477497 1 P 0 ;0,1=455,2=0.000000
L 5.54616673 2.5477497 5.5454002 2.54361634 1 P 0 ;0,1=455,2=0.000000
L 5.5454002 2.54361634 5.5431 2.54103356 1 P 0 ;0,1=455,2=0.000000
L 5.5431 2.54103356 5.54041654 2.53948287 1 P 0 ;0,1=455,2=0.000000
L 5.54041654 2.53948287 5.53083317 2.53948287 1 P 0 ;0,1=455,2=0.000000
L 5.54041654 2.53948287 5.54616673 2.5245 1 P 0 ;0,1=455,2=0.000000
L 5.56221644 2.55033346 5.56451663 2.55343278 1 P 0 ;0,1=455,2=0.000000
L 5.56451663 2.55343278 5.5672001 2.55498337 1 P 0 ;0,1=455,2=0.000000
L 5.5672001 2.55498337 5.57026683 2.5555 1 P 0 ;0,1=455,2=0.000000
L 5.57026683 2.5555 5.5741 2.55446683 1 P 0 ;0,1=455,2=0.000000
L 5.5741 2.55446683 5.57678346 2.55188307 1 P 0 ;0,1=455,2=0.000000
L 5.57678346 2.55188307 5.57755 2.54878376 1 P 0 ;0,1=455,2=0.000000
L 5.57755 2.54878376 5.57716673 2.54568258 1 P 0 ;0,1=455,2=0.000000
L 5.57716673 2.54568258 5.57563307 2.5430998 1 P 0 ;0,1=455,2=0.000000
L 5.57563307 2.5430998 5.56796663 2.53793327 1 P 0 ;0,1=455,2=0.000000
L 5.56796663 2.53793327 5.56451663 2.53431644 1 P 0 ;0,1=455,2=0.000000
L 5.56451663 2.53431644 5.56221644 2.52914892 1 P 0 ;0,1=455,2=0.000000
L 5.56221644 2.52914892 5.5614499 2.5245 1 P 0 ;0,1=455,2=0.000000
L 5.5614499 2.5245 5.57755 2.5245 1 P 0 ;0,1=455,2=0.000000
L 5.59206663 2.52914892 5.59436614 2.52656614 1 P 0 ;0,1=455,2=0.000000
L 5.59436614 2.52656614 5.59704961 2.52501654 1 P 0 ;0,1=455,2=0.000000
L 5.59704961 2.52501654 5.60049961 2.5245 1 P 0 ;0,1=455,2=0.000000
L 5.60049961 2.5245 5.6039503 2.52553307 1 P 0 ;0,1=455,2=0.000000
L 5.6039503 2.52553307 5.60663307 2.52759931 1 P 0 ;0,1=455,2=0.000000
L 5.60663307 2.52759931 5.60855 2.53121614 1 P 0 ;0,1=455,2=0.000000
L 5.60855 2.53121614 5.60893327 2.53534951 1 P 0 ;0,1=455,2=0.000000
L 5.60893327 2.53534951 5.60816673 2.53948287 1 P 0 ;0,1=455,2=0.000000
L 5.60816673 2.53948287 5.6062498 2.54206663 1 P 0 ;0,1=455,2=0.000000
L 5.6062498 2.54206663 5.60356634 2.54413287 1 P 0 ;0,1=455,2=0.000000
L 5.60356634 2.54413287 5.60088356 2.54464941 1 P 0 ;0,1=455,2=0.000000
L 5.60088356 2.54464941 5.5982001 2.54413287 1 P 0 ;0,1=455,2=0.000000
L 5.5982001 2.54413287 5.5947501 2.54206663 1 P 0 ;0,1=455,2=0.000000
L 5.5947501 2.54206663 5.5958999 2.5555 1 P 0 ;0,1=455,2=0.000000
L 5.5958999 2.5555 5.6062498 2.5555 1 P 0 ;0,1=455,2=0.000000
L 5.6361 2.5245 5.6361 2.5555 1 P 0 ;0,1=455,2=0.000000
L 5.6361 2.5555 5.62191624 2.53328327 1 P 0 ;0,1=455,2=0.000000
L 5.62191624 2.53328327 5.64108366 2.53328327 1 P 0 ;0,1=455,2=0.000000
L 5.795 2.223 5.795 2.267 1 P 0 
L 5.705 2.223 5.795 2.223 1 P 0 
L 5.795 2.267 5.705 2.267 1 P 0 
L 5.705 2.267 5.705 2.223 1 P 0 
L 5.80583317 2.1395 5.80583317 2.1705 1 P 0 ;0,1=456,2=0.000000
L 5.80583317 2.1705 5.81541654 2.1705 1 P 0 ;0,1=456,2=0.000000
L 5.81541654 2.1705 5.81848327 2.16894931 1 P 0 ;0,1=456,2=0.000000
L 5.81848327 2.16894931 5.8204002 2.16688307 1 P 0 ;0,1=456,2=0.000000
L 5.8204002 2.16688307 5.82116673 2.1627497 1 P 0 ;0,1=456,2=0.000000
L 5.82116673 2.1627497 5.8204002 2.15861634 1 P 0 ;0,1=456,2=0.000000
L 5.8204002 2.15861634 5.8181 2.15603356 1 P 0 ;0,1=456,2=0.000000
L 5.8181 2.15603356 5.81541654 2.15448287 1 P 0 ;0,1=456,2=0.000000
L 5.81541654 2.15448287 5.80583317 2.15448287 1 P 0 ;0,1=456,2=0.000000
L 5.81541654 2.15448287 5.82116673 2.1395 1 P 0 ;0,1=456,2=0.000000
L 5.83721644 2.16533346 5.83951663 2.16843278 1 P 0 ;0,1=456,2=0.000000
L 5.83951663 2.16843278 5.8422001 2.16998337 1 P 0 ;0,1=456,2=0.000000
L 5.8422001 2.16998337 5.84526683 2.1705 1 P 0 ;0,1=456,2=0.000000
L 5.84526683 2.1705 5.8491 2.16946683 1 P 0 ;0,1=456,2=0.000000
L 5.8491 2.16946683 5.85178346 2.16688307 1 P 0 ;0,1=456,2=0.000000
L 5.85178346 2.16688307 5.85255 2.16378376 1 P 0 ;0,1=456,2=0.000000
L 5.85255 2.16378376 5.85216673 2.16068258 1 P 0 ;0,1=456,2=0.000000
L 5.85216673 2.16068258 5.85063307 2.1580998 1 P 0 ;0,1=456,2=0.000000
L 5.85063307 2.1580998 5.84296663 2.15293327 1 P 0 ;0,1=456,2=0.000000
L 5.84296663 2.15293327 5.83951663 2.14931644 1 P 0 ;0,1=456,2=0.000000
L 5.83951663 2.14931644 5.83721644 2.14414892 1 P 0 ;0,1=456,2=0.000000
L 5.83721644 2.14414892 5.8364499 2.1395 1 P 0 ;0,1=456,2=0.000000
L 5.8364499 2.1395 5.85255 2.1395 1 P 0 ;0,1=456,2=0.000000
L 5.8801 2.1395 5.8801 2.1705 1 P 0 ;0,1=456,2=0.000000
L 5.8801 2.1705 5.86591624 2.14828327 1 P 0 ;0,1=456,2=0.000000
L 5.86591624 2.14828327 5.88508366 2.14828327 1 P 0 ;0,1=456,2=0.000000
L 5.90649961 2.1395 5.90918307 2.14001654 1 P 0 ;0,1=456,2=0.000000
L 5.90918307 2.14001654 5.9122498 2.14156614 1 P 0 ;0,1=456,2=0.000000
L 5.9122498 2.14156614 5.91416673 2.14414892 1 P 0 ;0,1=456,2=0.000000
L 5.91416673 2.14414892 5.91493327 2.14776673 1 P 0 ;0,1=456,2=0.000000
L 5.91493327 2.14776673 5.91416673 2.15138268 1 P 0 ;0,1=456,2=0.000000
L 5.91416673 2.15138268 5.91186654 2.15448287 1 P 0 ;0,1=456,2=0.000000
L 5.91186654 2.15448287 5.90841654 2.15603356 1 P 0 ;0,1=456,2=0.000000
L 5.90841654 2.15603356 5.90458337 2.15603356 1 P 0 ;0,1=456,2=0.000000
L 5.90458337 2.15603356 5.90228317 2.15706663 1 P 0 ;0,1=456,2=0.000000
L 5.90228317 2.15706663 5.90036614 2.15964941 1 P 0 ;0,1=456,2=0.000000
L 5.90036614 2.15964941 5.8995997 2.16326624 1 P 0 ;0,1=456,2=0.000000
L 5.8995997 2.16326624 5.9007501 2.16688307 1 P 0 ;0,1=456,2=0.000000
L 5.9007501 2.16688307 5.90343287 2.16946683 1 P 0 ;0,1=456,2=0.000000
L 5.90343287 2.16946683 5.90649961 2.1705 1 P 0 ;0,1=456,2=0.000000
L 5.90649961 2.1705 5.90956634 2.16946683 1 P 0 ;0,1=456,2=0.000000
L 5.90956634 2.16946683 5.9122498 2.16688307 1 P 0 ;0,1=456,2=0.000000
L 5.9122498 2.16688307 5.9134002 2.16326624 1 P 0 ;0,1=456,2=0.000000
L 5.9134002 2.16326624 5.91263307 2.15964941 1 P 0 ;0,1=456,2=0.000000
L 5.91263307 2.15964941 5.91071673 2.15706663 1 P 0 ;0,1=456,2=0.000000
L 5.91071673 2.15706663 5.90841654 2.15603356 1 P 0 ;0,1=456,2=0.000000
L 5.90841654 2.15603356 5.90458337 2.15603356 1 P 0 ;0,1=456,2=0.000000
L 5.90458337 2.15603356 5.90113337 2.15448287 1 P 0 ;0,1=456,2=0.000000
L 5.90113337 2.15448287 5.89883317 2.15138268 1 P 0 ;0,1=456,2=0.000000
L 5.89883317 2.15138268 5.89806663 2.14776673 1 P 0 ;0,1=456,2=0.000000
L 5.89806663 2.14776673 5.89883317 2.14414892 1 P 0 ;0,1=456,2=0.000000
L 5.89883317 2.14414892 5.9007501 2.14156614 1 P 0 ;0,1=456,2=0.000000
L 5.9007501 2.14156614 5.90381683 2.14001654 1 P 0 ;0,1=456,2=0.000000
L 5.90381683 2.14001654 5.90649961 2.1395 1 P 0 ;0,1=456,2=0.000000
L 5.776 2.3 5.776 2.39 1 P 0 
L 5.776 2.39 5.732 2.39 1 P 0 
L 5.732 2.39 5.732 2.3 1 P 0 
L 5.732 2.3 5.776 2.3 1 P 0 
L 5.8405 2.25083317 5.8095 2.25083317 1 P 0 ;0,1=457,2=270.000000
L 5.8095 2.25083317 5.8095 2.26041654 1 P 0 ;0,1=457,2=270.000000
L 5.8095 2.26041654 5.81105069 2.26348327 1 P 0 ;0,1=457,2=270.000000
L 5.81105069 2.26348327 5.81311693 2.2654002 1 P 0 ;0,1=457,2=270.000000
L 5.81311693 2.2654002 5.8172503 2.26616673 1 P 0 ;0,1=457,2=270.000000
L 5.8172503 2.26616673 5.82138366 2.2654002 1 P 0 ;0,1=457,2=270.000000
L 5.82138366 2.2654002 5.82396644 2.2631 1 P 0 ;0,1=457,2=270.000000
L 5.82396644 2.2631 5.82551713 2.26041654 1 P 0 ;0,1=457,2=270.000000
L 5.82551713 2.26041654 5.82551713 2.25083317 1 P 0 ;0,1=457,2=270.000000
L 5.82551713 2.26041654 5.8405 2.26616673 1 P 0 ;0,1=457,2=270.000000
L 5.81466654 2.28221644 5.81156722 2.28451663 1 P 0 ;0,1=457,2=270.000000
L 5.81156722 2.28451663 5.81001663 2.2872001 1 P 0 ;0,1=457,2=270.000000
L 5.81001663 2.2872001 5.8095 2.29026683 1 P 0 ;0,1=457,2=270.000000
L 5.8095 2.29026683 5.81053317 2.2941 1 P 0 ;0,1=457,2=270.000000
L 5.81053317 2.2941 5.81311693 2.29678346 1 P 0 ;0,1=457,2=270.000000
L 5.81311693 2.29678346 5.81621624 2.29755 1 P 0 ;0,1=457,2=270.000000
L 5.81621624 2.29755 5.81931742 2.29716673 1 P 0 ;0,1=457,2=270.000000
L 5.81931742 2.29716673 5.8219002 2.29563307 1 P 0 ;0,1=457,2=270.000000
L 5.8219002 2.29563307 5.82706673 2.28796663 1 P 0 ;0,1=457,2=270.000000
L 5.82706673 2.28796663 5.83068356 2.28451663 1 P 0 ;0,1=457,2=270.000000
L 5.83068356 2.28451663 5.83585108 2.28221644 1 P 0 ;0,1=457,2=270.000000
L 5.83585108 2.28221644 5.8405 2.2814499 1 P 0 ;0,1=457,2=270.000000
L 5.8405 2.2814499 5.8405 2.29755 1 P 0 ;0,1=457,2=270.000000
L 5.83585108 2.31206663 5.83843386 2.31436614 1 P 0 ;0,1=457,2=270.000000
L 5.83843386 2.31436614 5.83998346 2.31704961 1 P 0 ;0,1=457,2=270.000000
L 5.83998346 2.31704961 5.8405 2.32049961 1 P 0 ;0,1=457,2=270.000000
L 5.8405 2.32049961 5.83946693 2.3239503 1 P 0 ;0,1=457,2=270.000000
L 5.83946693 2.3239503 5.83740069 2.32663307 1 P 0 ;0,1=457,2=270.000000
L 5.83740069 2.32663307 5.83378386 2.32855 1 P 0 ;0,1=457,2=270.000000
L 5.83378386 2.32855 5.82965049 2.32893327 1 P 0 ;0,1=457,2=270.000000
L 5.82965049 2.32893327 5.82551713 2.32816673 1 P 0 ;0,1=457,2=270.000000
L 5.82551713 2.32816673 5.82293337 2.3262498 1 P 0 ;0,1=457,2=270.000000
L 5.82293337 2.3262498 5.82086713 2.32356634 1 P 0 ;0,1=457,2=270.000000
L 5.82086713 2.32356634 5.82035059 2.32088356 1 P 0 ;0,1=457,2=270.000000
L 5.82035059 2.32088356 5.82086713 2.3182001 1 P 0 ;0,1=457,2=270.000000
L 5.82086713 2.3182001 5.82293337 2.3147501 1 P 0 ;0,1=457,2=270.000000
L 5.82293337 2.3147501 5.8095 2.3158999 1 P 0 ;0,1=457,2=270.000000
L 5.8095 2.3158999 5.8095 2.3262498 1 P 0 ;0,1=457,2=270.000000
L 5.83585108 2.34306663 5.83843386 2.34536614 1 P 0 ;0,1=457,2=270.000000
L 5.83843386 2.34536614 5.83998346 2.34804961 1 P 0 ;0,1=457,2=270.000000
L 5.83998346 2.34804961 5.8405 2.35149961 1 P 0 ;0,1=457,2=270.000000
L 5.8405 2.35149961 5.83946693 2.3549503 1 P 0 ;0,1=457,2=270.000000
L 5.83946693 2.3549503 5.83740069 2.35763307 1 P 0 ;0,1=457,2=270.000000
L 5.83740069 2.35763307 5.83378386 2.35955 1 P 0 ;0,1=457,2=270.000000
L 5.83378386 2.35955 5.82965049 2.35993327 1 P 0 ;0,1=457,2=270.000000
L 5.82965049 2.35993327 5.82551713 2.35916673 1 P 0 ;0,1=457,2=270.000000
L 5.82551713 2.35916673 5.82293337 2.3572498 1 P 0 ;0,1=457,2=270.000000
L 5.82293337 2.3572498 5.82086713 2.35456634 1 P 0 ;0,1=457,2=270.000000
L 5.82086713 2.35456634 5.82035059 2.35188356 1 P 0 ;0,1=457,2=270.000000
L 5.82035059 2.35188356 5.82086713 2.3492001 1 P 0 ;0,1=457,2=270.000000
L 5.82086713 2.3492001 5.82293337 2.3457501 1 P 0 ;0,1=457,2=270.000000
L 5.82293337 2.3457501 5.8095 2.3468999 1 P 0 ;0,1=457,2=270.000000
L 5.8095 2.3468999 5.8095 2.3572498 1 P 0 ;0,1=457,2=270.000000
L 5.487 2.39 5.443 2.39 1 P 0 
L 5.443 2.39 5.443 2.3 1 P 0 
L 5.443 2.3 5.487 2.3 1 P 0 
L 5.487 2.3 5.487 2.39 1 P 0 
L 5.4205 2.41083317 5.3895 2.41083317 1 P 0 ;0,1=458,2=270.000000
L 5.3895 2.41083317 5.3895 2.42041654 1 P 0 ;0,1=458,2=270.000000
L 5.3895 2.42041654 5.39105069 2.42348327 1 P 0 ;0,1=458,2=270.000000
L 5.39105069 2.42348327 5.39311693 2.4254002 1 P 0 ;0,1=458,2=270.000000
L 5.39311693 2.4254002 5.3972503 2.42616673 1 P 0 ;0,1=458,2=270.000000
L 5.3972503 2.42616673 5.40138366 2.4254002 1 P 0 ;0,1=458,2=270.000000
L 5.40138366 2.4254002 5.40396644 2.4231 1 P 0 ;0,1=458,2=270.000000
L 5.40396644 2.4231 5.40551713 2.42041654 1 P 0 ;0,1=458,2=270.000000
L 5.40551713 2.42041654 5.40551713 2.41083317 1 P 0 ;0,1=458,2=270.000000
L 5.40551713 2.42041654 5.4205 2.42616673 1 P 0 ;0,1=458,2=270.000000
L 5.39466654 2.44221644 5.39156722 2.44451663 1 P 0 ;0,1=458,2=270.000000
L 5.39156722 2.44451663 5.39001663 2.4472001 1 P 0 ;0,1=458,2=270.000000
L 5.39001663 2.4472001 5.3895 2.45026683 1 P 0 ;0,1=458,2=270.000000
L 5.3895 2.45026683 5.39053317 2.4541 1 P 0 ;0,1=458,2=270.000000
L 5.39053317 2.4541 5.39311693 2.45678346 1 P 0 ;0,1=458,2=270.000000
L 5.39311693 2.45678346 5.39621624 2.45755 1 P 0 ;0,1=458,2=270.000000
L 5.39621624 2.45755 5.39931742 2.45716673 1 P 0 ;0,1=458,2=270.000000
L 5.39931742 2.45716673 5.4019002 2.45563307 1 P 0 ;0,1=458,2=270.000000
L 5.4019002 2.45563307 5.40706673 2.44796663 1 P 0 ;0,1=458,2=270.000000
L 5.40706673 2.44796663 5.41068356 2.44451663 1 P 0 ;0,1=458,2=270.000000
L 5.41068356 2.44451663 5.41585108 2.44221644 1 P 0 ;0,1=458,2=270.000000
L 5.41585108 2.44221644 5.4205 2.4414499 1 P 0 ;0,1=458,2=270.000000
L 5.4205 2.4414499 5.4205 2.45755 1 P 0 ;0,1=458,2=270.000000
L 5.4205 2.4851 5.3895 2.4851 1 P 0 ;0,1=458,2=270.000000
L 5.3895 2.4851 5.41171673 2.47091624 1 P 0 ;0,1=458,2=270.000000
L 5.41171673 2.47091624 5.41171673 2.49008366 1 P 0 ;0,1=458,2=270.000000
L 5.41585108 2.50306663 5.41843386 2.50536614 1 P 0 ;0,1=458,2=270.000000
L 5.41843386 2.50536614 5.41998346 2.50804961 1 P 0 ;0,1=458,2=270.000000
L 5.41998346 2.50804961 5.4205 2.51149961 1 P 0 ;0,1=458,2=270.000000
L 5.4205 2.51149961 5.41946693 2.5149503 1 P 0 ;0,1=458,2=270.000000
L 5.41946693 2.5149503 5.41740069 2.51763307 1 P 0 ;0,1=458,2=270.000000
L 5.41740069 2.51763307 5.41378386 2.51955 1 P 0 ;0,1=458,2=270.000000
L 5.41378386 2.51955 5.40965049 2.51993327 1 P 0 ;0,1=458,2=270.000000
L 5.40965049 2.51993327 5.40551713 2.51916673 1 P 0 ;0,1=458,2=270.000000
L 5.40551713 2.51916673 5.40293337 2.5172498 1 P 0 ;0,1=458,2=270.000000
L 5.40293337 2.5172498 5.40086713 2.51456634 1 P 0 ;0,1=458,2=270.000000
L 5.40086713 2.51456634 5.40035059 2.51188356 1 P 0 ;0,1=458,2=270.000000
L 5.40035059 2.51188356 5.40086713 2.5092001 1 P 0 ;0,1=458,2=270.000000
L 5.40086713 2.5092001 5.40293337 2.5057501 1 P 0 ;0,1=458,2=270.000000
L 5.40293337 2.5057501 5.3895 2.5068999 1 P 0 ;0,1=458,2=270.000000
L 5.3895 2.5068999 5.3895 2.5172498 1 P 0 ;0,1=458,2=270.000000
L 6.445 1.102 6.355 1.102 1 P 0 
L 6.355 1.102 6.355 1.058 1 P 0 
L 6.355 1.058 6.445 1.058 1 P 0 
L 6.445 1.058 6.445 1.102 1 P 0 
L 6.45083317 1.0945 6.45083317 1.1255 1 P 0 ;0,1=459,2=0.000000
L 6.45083317 1.1255 6.46041654 1.1255 1 P 0 ;0,1=459,2=0.000000
L 6.46041654 1.1255 6.46348327 1.12394931 1 P 0 ;0,1=459,2=0.000000
L 6.46348327 1.12394931 6.4654002 1.12188307 1 P 0 ;0,1=459,2=0.000000
L 6.4654002 1.12188307 6.46616673 1.1177497 1 P 0 ;0,1=459,2=0.000000
L 6.46616673 1.1177497 6.4654002 1.11361634 1 P 0 ;0,1=459,2=0.000000
L 6.4654002 1.11361634 6.4631 1.11103356 1 P 0 ;0,1=459,2=0.000000
L 6.4631 1.11103356 6.46041654 1.10948287 1 P 0 ;0,1=459,2=0.000000
L 6.46041654 1.10948287 6.45083317 1.10948287 1 P 0 ;0,1=459,2=0.000000
L 6.46041654 1.10948287 6.46616673 1.0945 1 P 0 ;0,1=459,2=0.000000
L 6.4941 1.0945 6.4941 1.1255 1 P 0 ;0,1=459,2=0.000000
L 6.4941 1.1255 6.47991624 1.10328327 1 P 0 ;0,1=459,2=0.000000
L 6.47991624 1.10328327 6.49908366 1.10328327 1 P 0 ;0,1=459,2=0.000000
L 6.52049961 1.0945 6.52049961 1.1255 1 P 0 ;0,1=459,2=0.000000
L 6.52049961 1.1255 6.5158999 1.1193003 1 P 0 ;0,1=459,2=0.000000
L 6.5158999 1.0945 6.52509931 1.0945 1 P 0 ;0,1=459,2=0.000000
L 6.54498287 1.09811585 6.54766634 1.09553307 1 P 0 ;0,1=459,2=0.000000
L 6.54766634 1.09553307 6.55073307 1.0945 1 P 0 ;0,1=459,2=0.000000
L 6.55073307 1.0945 6.5537998 1.09553307 1 P 0 ;0,1=459,2=0.000000
L 6.5537998 1.09553307 6.55648327 1.09863238 1 P 0 ;0,1=459,2=0.000000
L 6.55648327 1.09863238 6.5584002 1.10328327 1 P 0 ;0,1=459,2=0.000000
L 6.5584002 1.10328327 6.55916673 1.10793327 1 P 0 ;0,1=459,2=0.000000
L 6.55916673 1.10793327 6.55916673 1.11361634 1 P 0 ;0,1=459,2=0.000000
L 6.55916673 1.11361634 6.5584002 1.11826624 1 P 0 ;0,1=459,2=0.000000
L 6.5584002 1.11826624 6.55648327 1.1223997 1 P 0 ;0,1=459,2=0.000000
L 6.55648327 1.1223997 6.55418307 1.12446683 1 P 0 ;0,1=459,2=0.000000
L 6.55418307 1.12446683 6.55149961 1.1255 1 P 0 ;0,1=459,2=0.000000
L 6.55149961 1.1255 6.54843287 1.12446683 1 P 0 ;0,1=459,2=0.000000
L 6.54843287 1.12446683 6.54613337 1.1223997 1 P 0 ;0,1=459,2=0.000000
L 6.54613337 1.1223997 6.5445997 1.1193003 1 P 0 ;0,1=459,2=0.000000
L 6.5445997 1.1193003 6.54383317 1.11516594 1 P 0 ;0,1=459,2=0.000000
L 6.54383317 1.11516594 6.5445997 1.1115501 1 P 0 ;0,1=459,2=0.000000
L 6.5445997 1.1115501 6.54651663 1.10793327 1 P 0 ;0,1=459,2=0.000000
L 6.54651663 1.10793327 6.54881683 1.10586604 1 P 0 ;0,1=459,2=0.000000
L 6.54881683 1.10586604 6.55149961 1.10534951 1 P 0 ;0,1=459,2=0.000000
L 6.55149961 1.10534951 6.55456634 1.10638268 1 P 0 ;0,1=459,2=0.000000
L 6.55456634 1.10638268 6.55686654 1.10896634 1 P 0 ;0,1=459,2=0.000000
L 6.55686654 1.10896634 6.55916673 1.11361634 1 P 0 ;0,1=459,2=0.000000
L 6.445 1.042 6.355 1.042 1 P 0 
L 6.355 1.042 6.355 0.998 1 P 0 
L 6.355 0.998 6.445 0.998 1 P 0 
L 6.445 0.998 6.445 1.042 1 P 0 
L 6.45083317 0.9745 6.45083317 1.0055 1 P 0 ;0,1=460,2=0.000000
L 6.45083317 1.0055 6.46041654 1.0055 1 P 0 ;0,1=460,2=0.000000
L 6.46041654 1.0055 6.46348327 1.00394931 1 P 0 ;0,1=460,2=0.000000
L 6.46348327 1.00394931 6.4654002 1.00188307 1 P 0 ;0,1=460,2=0.000000
L 6.4654002 1.00188307 6.46616673 0.9977497 1 P 0 ;0,1=460,2=0.000000
L 6.46616673 0.9977497 6.4654002 0.99361634 1 P 0 ;0,1=460,2=0.000000
L 6.4654002 0.99361634 6.4631 0.99103356 1 P 0 ;0,1=460,2=0.000000
L 6.4631 0.99103356 6.46041654 0.98948287 1 P 0 ;0,1=460,2=0.000000
L 6.46041654 0.98948287 6.45083317 0.98948287 1 P 0 ;0,1=460,2=0.000000
L 6.46041654 0.98948287 6.46616673 0.9745 1 P 0 ;0,1=460,2=0.000000
L 6.4941 0.9745 6.4941 1.0055 1 P 0 ;0,1=460,2=0.000000
L 6.4941 1.0055 6.47991624 0.98328327 1 P 0 ;0,1=460,2=0.000000
L 6.47991624 0.98328327 6.49908366 0.98328327 1 P 0 ;0,1=460,2=0.000000
L 6.52049961 0.9745 6.52049961 1.0055 1 P 0 ;0,1=460,2=0.000000
L 6.52049961 1.0055 6.5158999 0.9993003 1 P 0 ;0,1=460,2=0.000000
L 6.5158999 0.9745 6.52509931 0.9745 1 P 0 ;0,1=460,2=0.000000
L 6.5561 0.9745 6.5561 1.0055 1 P 0 ;0,1=460,2=0.000000
L 6.5561 1.0055 6.54191624 0.98328327 1 P 0 ;0,1=460,2=0.000000
L 6.54191624 0.98328327 6.56108366 0.98328327 1 P 0 ;0,1=460,2=0.000000
L 6.445 0.987 6.355 0.987 1 P 0 
L 6.355 0.987 6.355 0.943 1 P 0 
L 6.355 0.943 6.445 0.943 1 P 0 
L 6.445 0.943 6.445 0.987 1 P 0 
L 6.36583317 0.8895 6.36583317 0.9205 1 P 0 ;0,1=461,2=0.000000
L 6.36583317 0.9205 6.37541654 0.9205 1 P 0 ;0,1=461,2=0.000000
L 6.37541654 0.9205 6.37848327 0.91894931 1 P 0 ;0,1=461,2=0.000000
L 6.37848327 0.91894931 6.3804002 0.91688307 1 P 0 ;0,1=461,2=0.000000
L 6.3804002 0.91688307 6.38116673 0.9127497 1 P 0 ;0,1=461,2=0.000000
L 6.38116673 0.9127497 6.3804002 0.90861634 1 P 0 ;0,1=461,2=0.000000
L 6.3804002 0.90861634 6.3781 0.90603356 1 P 0 ;0,1=461,2=0.000000
L 6.3781 0.90603356 6.37541654 0.90448287 1 P 0 ;0,1=461,2=0.000000
L 6.37541654 0.90448287 6.36583317 0.90448287 1 P 0 ;0,1=461,2=0.000000
L 6.37541654 0.90448287 6.38116673 0.8895 1 P 0 ;0,1=461,2=0.000000
L 6.4091 0.8895 6.4091 0.9205 1 P 0 ;0,1=461,2=0.000000
L 6.4091 0.9205 6.39491624 0.89828327 1 P 0 ;0,1=461,2=0.000000
L 6.39491624 0.89828327 6.41408366 0.89828327 1 P 0 ;0,1=461,2=0.000000
L 6.43549961 0.8895 6.43549961 0.9205 1 P 0 ;0,1=461,2=0.000000
L 6.43549961 0.9205 6.4308999 0.9143003 1 P 0 ;0,1=461,2=0.000000
L 6.4308999 0.8895 6.44009931 0.8895 1 P 0 ;0,1=461,2=0.000000
L 6.46649961 0.9205 6.46343287 0.91946683 1 P 0 ;0,1=461,2=0.000000
L 6.46343287 0.91946683 6.46113337 0.91688307 1 P 0 ;0,1=461,2=0.000000
L 6.46113337 0.91688307 6.4595997 0.91378376 1 P 0 ;0,1=461,2=0.000000
L 6.4595997 0.91378376 6.4584499 0.90964941 1 P 0 ;0,1=461,2=0.000000
L 6.4584499 0.90964941 6.45806663 0.90499951 1 P 0 ;0,1=461,2=0.000000
L 6.45806663 0.90499951 6.4584499 0.90034951 1 P 0 ;0,1=461,2=0.000000
L 6.4584499 0.90034951 6.4595997 0.89621614 1 P 0 ;0,1=461,2=0.000000
L 6.4595997 0.89621614 6.46113337 0.89311585 1 P 0 ;0,1=461,2=0.000000
L 6.46113337 0.89311585 6.46343287 0.89053307 1 P 0 ;0,1=461,2=0.000000
L 6.46343287 0.89053307 6.46649961 0.8895 1 P 0 ;0,1=461,2=0.000000
L 6.46649961 0.8895 6.46956634 0.89053307 1 P 0 ;0,1=461,2=0.000000
L 6.46956634 0.89053307 6.47186654 0.89311585 1 P 0 ;0,1=461,2=0.000000
L 6.47186654 0.89311585 6.4734002 0.89621614 1 P 0 ;0,1=461,2=0.000000
L 6.4734002 0.89621614 6.47455 0.90034951 1 P 0 ;0,1=461,2=0.000000
L 6.47455 0.90034951 6.47493327 0.90499951 1 P 0 ;0,1=461,2=0.000000
L 6.47493327 0.90499951 6.47455 0.90964941 1 P 0 ;0,1=461,2=0.000000
L 6.47455 0.90964941 6.4734002 0.91378376 1 P 0 ;0,1=461,2=0.000000
L 6.4734002 0.91378376 6.47186654 0.91688307 1 P 0 ;0,1=461,2=0.000000
L 6.47186654 0.91688307 6.46956634 0.91946683 1 P 0 ;0,1=461,2=0.000000
L 6.46956634 0.91946683 6.46649961 0.9205 1 P 0 ;0,1=461,2=0.000000
L 5.98 0.943 5.98 0.987 1 P 0 
L 5.89 0.987 5.89 0.943 1 P 0 
L 5.98 0.987 5.89 0.987 1 P 0 
L 5.89 0.943 5.98 0.943 1 P 0 
L 5.88583317 0.8545 5.88583317 0.8855 1 P 0 ;0,1=462,2=0.000000
L 5.88583317 0.8855 5.89541654 0.8855 1 P 0 ;0,1=462,2=0.000000
L 5.89541654 0.8855 5.89848327 0.88394931 1 P 0 ;0,1=462,2=0.000000
L 5.89848327 0.88394931 5.9004002 0.88188307 1 P 0 ;0,1=462,2=0.000000
L 5.9004002 0.88188307 5.90116673 0.8777497 1 P 0 ;0,1=462,2=0.000000
L 5.90116673 0.8777497 5.9004002 0.87361634 1 P 0 ;0,1=462,2=0.000000
L 5.9004002 0.87361634 5.8981 0.87103356 1 P 0 ;0,1=462,2=0.000000
L 5.8981 0.87103356 5.89541654 0.86948287 1 P 0 ;0,1=462,2=0.000000
L 5.89541654 0.86948287 5.88583317 0.86948287 1 P 0 ;0,1=462,2=0.000000
L 5.89541654 0.86948287 5.90116673 0.8545 1 P 0 ;0,1=462,2=0.000000
L 5.9291 0.8545 5.9291 0.8855 1 P 0 ;0,1=462,2=0.000000
L 5.9291 0.8855 5.91491624 0.86328327 1 P 0 ;0,1=462,2=0.000000
L 5.91491624 0.86328327 5.93408366 0.86328327 1 P 0 ;0,1=462,2=0.000000
L 5.94821644 0.88033346 5.95051663 0.88343278 1 P 0 ;0,1=462,2=0.000000
L 5.95051663 0.88343278 5.9532001 0.88498337 1 P 0 ;0,1=462,2=0.000000
L 5.9532001 0.88498337 5.95626683 0.8855 1 P 0 ;0,1=462,2=0.000000
L 5.95626683 0.8855 5.9601 0.88446683 1 P 0 ;0,1=462,2=0.000000
L 5.9601 0.88446683 5.96278346 0.88188307 1 P 0 ;0,1=462,2=0.000000
L 5.96278346 0.88188307 5.96355 0.87878376 1 P 0 ;0,1=462,2=0.000000
L 5.96355 0.87878376 5.96316673 0.87568258 1 P 0 ;0,1=462,2=0.000000
L 5.96316673 0.87568258 5.96163307 0.8730998 1 P 0 ;0,1=462,2=0.000000
L 5.96163307 0.8730998 5.95396663 0.86793327 1 P 0 ;0,1=462,2=0.000000
L 5.95396663 0.86793327 5.95051663 0.86431644 1 P 0 ;0,1=462,2=0.000000
L 5.95051663 0.86431644 5.94821644 0.85914892 1 P 0 ;0,1=462,2=0.000000
L 5.94821644 0.85914892 5.9474499 0.8545 1 P 0 ;0,1=462,2=0.000000
L 5.9474499 0.8545 5.96355 0.8545 1 P 0 ;0,1=462,2=0.000000
L 5.97806663 0.86069961 5.98036614 0.85708278 1 P 0 ;0,1=462,2=0.000000
L 5.98036614 0.85708278 5.98343287 0.85501654 1 P 0 ;0,1=462,2=0.000000
L 5.98343287 0.85501654 5.98688356 0.8545 1 P 0 ;0,1=462,2=0.000000
L 5.98688356 0.8545 5.9899503 0.85501654 1 P 0 ;0,1=462,2=0.000000
L 5.9899503 0.85501654 5.99301703 0.85759931 1 P 0 ;0,1=462,2=0.000000
L 5.99301703 0.85759931 5.99493327 0.86069961 1 P 0 ;0,1=462,2=0.000000
L 5.99493327 0.86069961 5.99531654 0.8637999 1 P 0 ;0,1=462,2=0.000000
L 5.99531654 0.8637999 5.99455 0.86741575 1 P 0 ;0,1=462,2=0.000000
L 5.99455 0.86741575 5.99186654 0.86999951 1 P 0 ;0,1=462,2=0.000000
L 5.99186654 0.86999951 5.98918307 0.87103356 1 P 0 ;0,1=462,2=0.000000
L 5.98918307 0.87103356 5.98573307 0.87103356 1 P 0 ;0,1=462,2=0.000000
L 5.98918307 0.87103356 5.99148327 0.87258317 1 P 0 ;0,1=462,2=0.000000
L 5.99148327 0.87258317 5.9934002 0.87516594 1 P 0 ;0,1=462,2=0.000000
L 5.9934002 0.87516594 5.99416673 0.87826624 1 P 0 ;0,1=462,2=0.000000
L 5.99416673 0.87826624 5.9934002 0.88136654 1 P 0 ;0,1=462,2=0.000000
L 5.9934002 0.88136654 5.99148327 0.88394931 1 P 0 ;0,1=462,2=0.000000
L 5.99148327 0.88394931 5.98803327 0.8855 1 P 0 ;0,1=462,2=0.000000
L 5.98803327 0.8855 5.98458337 0.88498337 1 P 0 ;0,1=462,2=0.000000
L 5.98458337 0.88498337 5.98113337 0.88291624 1 P 0 ;0,1=462,2=0.000000
L 5.96553002 2.308 5.96553002 2.352 1 P 0 
L 5.96553002 2.352 5.87553002 2.352 1 P 0 
L 5.87553002 2.352 5.87553002 2.308 1 P 0 
L 5.87553002 2.308 5.96553002 2.308 1 P 0 
L 5.81083317 2.4695 5.81083317 2.5005 1 P 0 ;0,1=463,2=0.000000
L 5.81083317 2.5005 5.82041654 2.5005 1 P 0 ;0,1=463,2=0.000000
L 5.82041654 2.5005 5.82348327 2.49894931 1 P 0 ;0,1=463,2=0.000000
L 5.82348327 2.49894931 5.8254002 2.49688307 1 P 0 ;0,1=463,2=0.000000
L 5.8254002 2.49688307 5.82616673 2.4927497 1 P 0 ;0,1=463,2=0.000000
L 5.82616673 2.4927497 5.8254002 2.48861634 1 P 0 ;0,1=463,2=0.000000
L 5.8254002 2.48861634 5.8231 2.48603356 1 P 0 ;0,1=463,2=0.000000
L 5.8231 2.48603356 5.82041654 2.48448287 1 P 0 ;0,1=463,2=0.000000
L 5.82041654 2.48448287 5.81083317 2.48448287 1 P 0 ;0,1=463,2=0.000000
L 5.82041654 2.48448287 5.82616673 2.4695 1 P 0 ;0,1=463,2=0.000000
L 5.84221644 2.49533346 5.84451663 2.49843278 1 P 0 ;0,1=463,2=0.000000
L 5.84451663 2.49843278 5.8472001 2.49998337 1 P 0 ;0,1=463,2=0.000000
L 5.8472001 2.49998337 5.85026683 2.5005 1 P 0 ;0,1=463,2=0.000000
L 5.85026683 2.5005 5.8541 2.49946683 1 P 0 ;0,1=463,2=0.000000
L 5.8541 2.49946683 5.85678346 2.49688307 1 P 0 ;0,1=463,2=0.000000
L 5.85678346 2.49688307 5.85755 2.49378376 1 P 0 ;0,1=463,2=0.000000
L 5.85755 2.49378376 5.85716673 2.49068258 1 P 0 ;0,1=463,2=0.000000
L 5.85716673 2.49068258 5.85563307 2.4880998 1 P 0 ;0,1=463,2=0.000000
L 5.85563307 2.4880998 5.84796663 2.48293327 1 P 0 ;0,1=463,2=0.000000
L 5.84796663 2.48293327 5.84451663 2.47931644 1 P 0 ;0,1=463,2=0.000000
L 5.84451663 2.47931644 5.84221644 2.47414892 1 P 0 ;0,1=463,2=0.000000
L 5.84221644 2.47414892 5.8414499 2.4695 1 P 0 ;0,1=463,2=0.000000
L 5.8414499 2.4695 5.85755 2.4695 1 P 0 ;0,1=463,2=0.000000
L 5.87398287 2.47311585 5.87666634 2.47053307 1 P 0 ;0,1=463,2=0.000000
L 5.87666634 2.47053307 5.87973307 2.4695 1 P 0 ;0,1=463,2=0.000000
L 5.87973307 2.4695 5.8827998 2.47053307 1 P 0 ;0,1=463,2=0.000000
L 5.8827998 2.47053307 5.88548327 2.47363238 1 P 0 ;0,1=463,2=0.000000
L 5.88548327 2.47363238 5.8874002 2.47828327 1 P 0 ;0,1=463,2=0.000000
L 5.8874002 2.47828327 5.88816673 2.48293327 1 P 0 ;0,1=463,2=0.000000
L 5.88816673 2.48293327 5.88816673 2.48861634 1 P 0 ;0,1=463,2=0.000000
L 5.88816673 2.48861634 5.8874002 2.49326624 1 P 0 ;0,1=463,2=0.000000
L 5.8874002 2.49326624 5.88548327 2.4973997 1 P 0 ;0,1=463,2=0.000000
L 5.88548327 2.4973997 5.88318307 2.49946683 1 P 0 ;0,1=463,2=0.000000
L 5.88318307 2.49946683 5.88049961 2.5005 1 P 0 ;0,1=463,2=0.000000
L 5.88049961 2.5005 5.87743287 2.49946683 1 P 0 ;0,1=463,2=0.000000
L 5.87743287 2.49946683 5.87513337 2.4973997 1 P 0 ;0,1=463,2=0.000000
L 5.87513337 2.4973997 5.8735997 2.4943003 1 P 0 ;0,1=463,2=0.000000
L 5.8735997 2.4943003 5.87283317 2.49016594 1 P 0 ;0,1=463,2=0.000000
L 5.87283317 2.49016594 5.8735997 2.4865501 1 P 0 ;0,1=463,2=0.000000
L 5.8735997 2.4865501 5.87551663 2.48293327 1 P 0 ;0,1=463,2=0.000000
L 5.87551663 2.48293327 5.87781683 2.48086604 1 P 0 ;0,1=463,2=0.000000
L 5.87781683 2.48086604 5.88049961 2.48034951 1 P 0 ;0,1=463,2=0.000000
L 5.88049961 2.48034951 5.88356634 2.48138268 1 P 0 ;0,1=463,2=0.000000
L 5.88356634 2.48138268 5.88586654 2.48396634 1 P 0 ;0,1=463,2=0.000000
L 5.88586654 2.48396634 5.88816673 2.48861634 1 P 0 ;0,1=463,2=0.000000
L 5.91149961 2.4695 5.91418307 2.47001654 1 P 0 ;0,1=463,2=0.000000
L 5.91418307 2.47001654 5.9172498 2.47156614 1 P 0 ;0,1=463,2=0.000000
L 5.9172498 2.47156614 5.91916673 2.47414892 1 P 0 ;0,1=463,2=0.000000
L 5.91916673 2.47414892 5.91993327 2.47776673 1 P 0 ;0,1=463,2=0.000000
L 5.91993327 2.47776673 5.91916673 2.48138268 1 P 0 ;0,1=463,2=0.000000
L 5.91916673 2.48138268 5.91686654 2.48448287 1 P 0 ;0,1=463,2=0.000000
L 5.91686654 2.48448287 5.91341654 2.48603356 1 P 0 ;0,1=463,2=0.000000
L 5.91341654 2.48603356 5.90958337 2.48603356 1 P 0 ;0,1=463,2=0.000000
L 5.90958337 2.48603356 5.90728317 2.48706663 1 P 0 ;0,1=463,2=0.000000
L 5.90728317 2.48706663 5.90536614 2.48964941 1 P 0 ;0,1=463,2=0.000000
L 5.90536614 2.48964941 5.9045997 2.49326624 1 P 0 ;0,1=463,2=0.000000
L 5.9045997 2.49326624 5.9057501 2.49688307 1 P 0 ;0,1=463,2=0.000000
L 5.9057501 2.49688307 5.90843287 2.49946683 1 P 0 ;0,1=463,2=0.000000
L 5.90843287 2.49946683 5.91149961 2.5005 1 P 0 ;0,1=463,2=0.000000
L 5.91149961 2.5005 5.91456634 2.49946683 1 P 0 ;0,1=463,2=0.000000
L 5.91456634 2.49946683 5.9172498 2.49688307 1 P 0 ;0,1=463,2=0.000000
L 5.9172498 2.49688307 5.9184002 2.49326624 1 P 0 ;0,1=463,2=0.000000
L 5.9184002 2.49326624 5.91763307 2.48964941 1 P 0 ;0,1=463,2=0.000000
L 5.91763307 2.48964941 5.91571673 2.48706663 1 P 0 ;0,1=463,2=0.000000
L 5.91571673 2.48706663 5.91341654 2.48603356 1 P 0 ;0,1=463,2=0.000000
L 5.91341654 2.48603356 5.90958337 2.48603356 1 P 0 ;0,1=463,2=0.000000
L 5.90958337 2.48603356 5.90613337 2.48448287 1 P 0 ;0,1=463,2=0.000000
L 5.90613337 2.48448287 5.90383317 2.48138268 1 P 0 ;0,1=463,2=0.000000
L 5.90383317 2.48138268 5.90306663 2.47776673 1 P 0 ;0,1=463,2=0.000000
L 5.90306663 2.47776673 5.90383317 2.47414892 1 P 0 ;0,1=463,2=0.000000
L 5.90383317 2.47414892 5.9057501 2.47156614 1 P 0 ;0,1=463,2=0.000000
L 5.9057501 2.47156614 5.90881683 2.47001654 1 P 0 ;0,1=463,2=0.000000
L 5.90881683 2.47001654 5.91149961 2.4695 1 P 0 ;0,1=463,2=0.000000
L 5.96553002 2.26201998 5.96553002 2.30601998 1 P 0 
L 5.96553002 2.30601998 5.87553002 2.30601998 1 P 0 
L 5.87553002 2.30601998 5.87553002 2.26201998 1 P 0 
L 5.87553002 2.26201998 5.96553002 2.26201998 1 P 0 
L 5.81083317 2.4095 5.81083317 2.4405 1 P 0 ;0,1=464,2=0.000000
L 5.81083317 2.4405 5.82041654 2.4405 1 P 0 ;0,1=464,2=0.000000
L 5.82041654 2.4405 5.82348327 2.43894931 1 P 0 ;0,1=464,2=0.000000
L 5.82348327 2.43894931 5.8254002 2.43688307 1 P 0 ;0,1=464,2=0.000000
L 5.8254002 2.43688307 5.82616673 2.4327497 1 P 0 ;0,1=464,2=0.000000
L 5.82616673 2.4327497 5.8254002 2.42861634 1 P 0 ;0,1=464,2=0.000000
L 5.8254002 2.42861634 5.8231 2.42603356 1 P 0 ;0,1=464,2=0.000000
L 5.8231 2.42603356 5.82041654 2.42448287 1 P 0 ;0,1=464,2=0.000000
L 5.82041654 2.42448287 5.81083317 2.42448287 1 P 0 ;0,1=464,2=0.000000
L 5.82041654 2.42448287 5.82616673 2.4095 1 P 0 ;0,1=464,2=0.000000
L 5.84221644 2.43533346 5.84451663 2.43843278 1 P 0 ;0,1=464,2=0.000000
L 5.84451663 2.43843278 5.8472001 2.43998337 1 P 0 ;0,1=464,2=0.000000
L 5.8472001 2.43998337 5.85026683 2.4405 1 P 0 ;0,1=464,2=0.000000
L 5.85026683 2.4405 5.8541 2.43946683 1 P 0 ;0,1=464,2=0.000000
L 5.8541 2.43946683 5.85678346 2.43688307 1 P 0 ;0,1=464,2=0.000000
L 5.85678346 2.43688307 5.85755 2.43378376 1 P 0 ;0,1=464,2=0.000000
L 5.85755 2.43378376 5.85716673 2.43068258 1 P 0 ;0,1=464,2=0.000000
L 5.85716673 2.43068258 5.85563307 2.4280998 1 P 0 ;0,1=464,2=0.000000
L 5.85563307 2.4280998 5.84796663 2.42293327 1 P 0 ;0,1=464,2=0.000000
L 5.84796663 2.42293327 5.84451663 2.41931644 1 P 0 ;0,1=464,2=0.000000
L 5.84451663 2.41931644 5.84221644 2.41414892 1 P 0 ;0,1=464,2=0.000000
L 5.84221644 2.41414892 5.8414499 2.4095 1 P 0 ;0,1=464,2=0.000000
L 5.8414499 2.4095 5.85755 2.4095 1 P 0 ;0,1=464,2=0.000000
L 5.87398287 2.41311585 5.87666634 2.41053307 1 P 0 ;0,1=464,2=0.000000
L 5.87666634 2.41053307 5.87973307 2.4095 1 P 0 ;0,1=464,2=0.000000
L 5.87973307 2.4095 5.8827998 2.41053307 1 P 0 ;0,1=464,2=0.000000
L 5.8827998 2.41053307 5.88548327 2.41363238 1 P 0 ;0,1=464,2=0.000000
L 5.88548327 2.41363238 5.8874002 2.41828327 1 P 0 ;0,1=464,2=0.000000
L 5.8874002 2.41828327 5.88816673 2.42293327 1 P 0 ;0,1=464,2=0.000000
L 5.88816673 2.42293327 5.88816673 2.42861634 1 P 0 ;0,1=464,2=0.000000
L 5.88816673 2.42861634 5.8874002 2.43326624 1 P 0 ;0,1=464,2=0.000000
L 5.8874002 2.43326624 5.88548327 2.4373997 1 P 0 ;0,1=464,2=0.000000
L 5.88548327 2.4373997 5.88318307 2.43946683 1 P 0 ;0,1=464,2=0.000000
L 5.88318307 2.43946683 5.88049961 2.4405 1 P 0 ;0,1=464,2=0.000000
L 5.88049961 2.4405 5.87743287 2.43946683 1 P 0 ;0,1=464,2=0.000000
L 5.87743287 2.43946683 5.87513337 2.4373997 1 P 0 ;0,1=464,2=0.000000
L 5.87513337 2.4373997 5.8735997 2.4343003 1 P 0 ;0,1=464,2=0.000000
L 5.8735997 2.4343003 5.87283317 2.43016594 1 P 0 ;0,1=464,2=0.000000
L 5.87283317 2.43016594 5.8735997 2.4265501 1 P 0 ;0,1=464,2=0.000000
L 5.8735997 2.4265501 5.87551663 2.42293327 1 P 0 ;0,1=464,2=0.000000
L 5.87551663 2.42293327 5.87781683 2.42086604 1 P 0 ;0,1=464,2=0.000000
L 5.87781683 2.42086604 5.88049961 2.42034951 1 P 0 ;0,1=464,2=0.000000
L 5.88049961 2.42034951 5.88356634 2.42138268 1 P 0 ;0,1=464,2=0.000000
L 5.88356634 2.42138268 5.88586654 2.42396634 1 P 0 ;0,1=464,2=0.000000
L 5.88586654 2.42396634 5.88816673 2.42861634 1 P 0 ;0,1=464,2=0.000000
L 5.91073307 2.4095 5.91149961 2.41621614 1 P 0 ;0,1=464,2=0.000000
L 5.91149961 2.41621614 5.9126501 2.42189921 1 P 0 ;0,1=464,2=0.000000
L 5.9126501 2.42189921 5.91418307 2.42706663 1 P 0 ;0,1=464,2=0.000000
L 5.91418307 2.42706663 5.9161 2.4327497 1 P 0 ;0,1=464,2=0.000000
L 5.9161 2.4327497 5.91916673 2.4405 1 P 0 ;0,1=464,2=0.000000
L 5.91916673 2.4405 5.90383317 2.4405 1 P 0 ;0,1=464,2=0.000000
L 5.96553002 2.217 5.96553002 2.261 1 P 0 
L 5.87553002 2.217 5.96553002 2.217 1 P 0 
L 5.96553002 2.261 5.87553002 2.261 1 P 0 
L 5.87553002 2.261 5.87553002 2.217 1 P 0 
L 5.81083317 2.3695 5.81083317 2.4005 1 P 0 ;0,1=465,2=0.000000
L 5.81083317 2.4005 5.82041654 2.4005 1 P 0 ;0,1=465,2=0.000000
L 5.82041654 2.4005 5.82348327 2.39894931 1 P 0 ;0,1=465,2=0.000000
L 5.82348327 2.39894931 5.8254002 2.39688307 1 P 0 ;0,1=465,2=0.000000
L 5.8254002 2.39688307 5.82616673 2.3927497 1 P 0 ;0,1=465,2=0.000000
L 5.82616673 2.3927497 5.8254002 2.38861634 1 P 0 ;0,1=465,2=0.000000
L 5.8254002 2.38861634 5.8231 2.38603356 1 P 0 ;0,1=465,2=0.000000
L 5.8231 2.38603356 5.82041654 2.38448287 1 P 0 ;0,1=465,2=0.000000
L 5.82041654 2.38448287 5.81083317 2.38448287 1 P 0 ;0,1=465,2=0.000000
L 5.82041654 2.38448287 5.82616673 2.3695 1 P 0 ;0,1=465,2=0.000000
L 5.84221644 2.39533346 5.84451663 2.39843278 1 P 0 ;0,1=465,2=0.000000
L 5.84451663 2.39843278 5.8472001 2.39998337 1 P 0 ;0,1=465,2=0.000000
L 5.8472001 2.39998337 5.85026683 2.4005 1 P 0 ;0,1=465,2=0.000000
L 5.85026683 2.4005 5.8541 2.39946683 1 P 0 ;0,1=465,2=0.000000
L 5.8541 2.39946683 5.85678346 2.39688307 1 P 0 ;0,1=465,2=0.000000
L 5.85678346 2.39688307 5.85755 2.39378376 1 P 0 ;0,1=465,2=0.000000
L 5.85755 2.39378376 5.85716673 2.39068258 1 P 0 ;0,1=465,2=0.000000
L 5.85716673 2.39068258 5.85563307 2.3880998 1 P 0 ;0,1=465,2=0.000000
L 5.85563307 2.3880998 5.84796663 2.38293327 1 P 0 ;0,1=465,2=0.000000
L 5.84796663 2.38293327 5.84451663 2.37931644 1 P 0 ;0,1=465,2=0.000000
L 5.84451663 2.37931644 5.84221644 2.37414892 1 P 0 ;0,1=465,2=0.000000
L 5.84221644 2.37414892 5.8414499 2.3695 1 P 0 ;0,1=465,2=0.000000
L 5.8414499 2.3695 5.85755 2.3695 1 P 0 ;0,1=465,2=0.000000
L 5.87398287 2.37311585 5.87666634 2.37053307 1 P 0 ;0,1=465,2=0.000000
L 5.87666634 2.37053307 5.87973307 2.3695 1 P 0 ;0,1=465,2=0.000000
L 5.87973307 2.3695 5.8827998 2.37053307 1 P 0 ;0,1=465,2=0.000000
L 5.8827998 2.37053307 5.88548327 2.37363238 1 P 0 ;0,1=465,2=0.000000
L 5.88548327 2.37363238 5.8874002 2.37828327 1 P 0 ;0,1=465,2=0.000000
L 5.8874002 2.37828327 5.88816673 2.38293327 1 P 0 ;0,1=465,2=0.000000
L 5.88816673 2.38293327 5.88816673 2.38861634 1 P 0 ;0,1=465,2=0.000000
L 5.88816673 2.38861634 5.8874002 2.39326624 1 P 0 ;0,1=465,2=0.000000
L 5.8874002 2.39326624 5.88548327 2.3973997 1 P 0 ;0,1=465,2=0.000000
L 5.88548327 2.3973997 5.88318307 2.39946683 1 P 0 ;0,1=465,2=0.000000
L 5.88318307 2.39946683 5.88049961 2.4005 1 P 0 ;0,1=465,2=0.000000
L 5.88049961 2.4005 5.87743287 2.39946683 1 P 0 ;0,1=465,2=0.000000
L 5.87743287 2.39946683 5.87513337 2.3973997 1 P 0 ;0,1=465,2=0.000000
L 5.87513337 2.3973997 5.8735997 2.3943003 1 P 0 ;0,1=465,2=0.000000
L 5.8735997 2.3943003 5.87283317 2.39016594 1 P 0 ;0,1=465,2=0.000000
L 5.87283317 2.39016594 5.8735997 2.3865501 1 P 0 ;0,1=465,2=0.000000
L 5.8735997 2.3865501 5.87551663 2.38293327 1 P 0 ;0,1=465,2=0.000000
L 5.87551663 2.38293327 5.87781683 2.38086604 1 P 0 ;0,1=465,2=0.000000
L 5.87781683 2.38086604 5.88049961 2.38034951 1 P 0 ;0,1=465,2=0.000000
L 5.88049961 2.38034951 5.88356634 2.38138268 1 P 0 ;0,1=465,2=0.000000
L 5.88356634 2.38138268 5.88586654 2.38396634 1 P 0 ;0,1=465,2=0.000000
L 5.88586654 2.38396634 5.88816673 2.38861634 1 P 0 ;0,1=465,2=0.000000
L 5.90421644 2.38241575 5.9068999 2.38603356 1 P 0 ;0,1=465,2=0.000000
L 5.9068999 2.38603356 5.9092001 2.3880998 1 P 0 ;0,1=465,2=0.000000
L 5.9092001 2.3880998 5.91226683 2.38913287 1 P 0 ;0,1=465,2=0.000000
L 5.91226683 2.38913287 5.9149503 2.3880998 1 P 0 ;0,1=465,2=0.000000
L 5.9149503 2.3880998 5.91686654 2.38603356 1 P 0 ;0,1=465,2=0.000000
L 5.91686654 2.38603356 5.9184002 2.38293327 1 P 0 ;0,1=465,2=0.000000
L 5.9184002 2.38293327 5.91878346 2.37931644 1 P 0 ;0,1=465,2=0.000000
L 5.91878346 2.37931644 5.9184002 2.37621614 1 P 0 ;0,1=465,2=0.000000
L 5.9184002 2.37621614 5.91686654 2.37311585 1 P 0 ;0,1=465,2=0.000000
L 5.91686654 2.37311585 5.91456634 2.37053307 1 P 0 ;0,1=465,2=0.000000
L 5.91456634 2.37053307 5.91188356 2.3695 1 P 0 ;0,1=465,2=0.000000
L 5.91188356 2.3695 5.90881683 2.37053307 1 P 0 ;0,1=465,2=0.000000
L 5.90881683 2.37053307 5.90613337 2.37363238 1 P 0 ;0,1=465,2=0.000000
L 5.90613337 2.37363238 5.9045997 2.37828327 1 P 0 ;0,1=465,2=0.000000
L 5.9045997 2.37828327 5.90421644 2.3834498 1 P 0 ;0,1=465,2=0.000000
L 5.90421644 2.3834498 5.90498287 2.39016594 1 P 0 ;0,1=465,2=0.000000
L 5.90498287 2.39016594 5.90613337 2.39378376 1 P 0 ;0,1=465,2=0.000000
L 5.90613337 2.39378376 5.90804961 2.3973997 1 P 0 ;0,1=465,2=0.000000
L 5.90804961 2.3973997 5.91073307 2.39998337 1 P 0 ;0,1=465,2=0.000000
L 5.91073307 2.39998337 5.91341654 2.4005 1 P 0 ;0,1=465,2=0.000000
L 5.91341654 2.4005 5.9161 2.39946683 1 P 0 ;0,1=465,2=0.000000
L 5.9161 2.39946683 5.91801703 2.39688307 1 P 0 ;0,1=465,2=0.000000
L 5.99701998 1.97465 5.99701998 1.88465 1 P 0 
L 5.99701998 1.88465 6.04101998 1.88465 1 P 0 
L 6.04101998 1.88465 6.04101998 1.97465 1 P 0 
L 6.04101998 1.97465 5.99701998 1.97465 1 P 0 
L 6.1455 1.87083317 6.1145 1.87083317 1 P 0 ;0,1=466,2=270.000000
L 6.1145 1.87083317 6.1145 1.88041654 1 P 0 ;0,1=466,2=270.000000
L 6.1145 1.88041654 6.11605069 1.88348327 1 P 0 ;0,1=466,2=270.000000
L 6.11605069 1.88348327 6.11811693 1.8854002 1 P 0 ;0,1=466,2=270.000000
L 6.11811693 1.8854002 6.1222503 1.88616673 1 P 0 ;0,1=466,2=270.000000
L 6.1222503 1.88616673 6.12638366 1.8854002 1 P 0 ;0,1=466,2=270.000000
L 6.12638366 1.8854002 6.12896644 1.8831 1 P 0 ;0,1=466,2=270.000000
L 6.12896644 1.8831 6.13051713 1.88041654 1 P 0 ;0,1=466,2=270.000000
L 6.13051713 1.88041654 6.13051713 1.87083317 1 P 0 ;0,1=466,2=270.000000
L 6.13051713 1.88041654 6.1455 1.88616673 1 P 0 ;0,1=466,2=270.000000
L 6.11966654 1.90221644 6.11656722 1.90451663 1 P 0 ;0,1=466,2=270.000000
L 6.11656722 1.90451663 6.11501663 1.9072001 1 P 0 ;0,1=466,2=270.000000
L 6.11501663 1.9072001 6.1145 1.91026683 1 P 0 ;0,1=466,2=270.000000
L 6.1145 1.91026683 6.11553317 1.9141 1 P 0 ;0,1=466,2=270.000000
L 6.11553317 1.9141 6.11811693 1.91678346 1 P 0 ;0,1=466,2=270.000000
L 6.11811693 1.91678346 6.12121624 1.91755 1 P 0 ;0,1=466,2=270.000000
L 6.12121624 1.91755 6.12431742 1.91716673 1 P 0 ;0,1=466,2=270.000000
L 6.12431742 1.91716673 6.1269002 1.91563307 1 P 0 ;0,1=466,2=270.000000
L 6.1269002 1.91563307 6.13206673 1.90796663 1 P 0 ;0,1=466,2=270.000000
L 6.13206673 1.90796663 6.13568356 1.90451663 1 P 0 ;0,1=466,2=270.000000
L 6.13568356 1.90451663 6.14085108 1.90221644 1 P 0 ;0,1=466,2=270.000000
L 6.14085108 1.90221644 6.1455 1.9014499 1 P 0 ;0,1=466,2=270.000000
L 6.1455 1.9014499 6.1455 1.91755 1 P 0 ;0,1=466,2=270.000000
L 6.14188415 1.93398287 6.14446693 1.93666634 1 P 0 ;0,1=466,2=270.000000
L 6.14446693 1.93666634 6.1455 1.93973307 1 P 0 ;0,1=466,2=270.000000
L 6.1455 1.93973307 6.14446693 1.9427998 1 P 0 ;0,1=466,2=270.000000
L 6.14446693 1.9427998 6.14136762 1.94548327 1 P 0 ;0,1=466,2=270.000000
L 6.14136762 1.94548327 6.13671673 1.9474002 1 P 0 ;0,1=466,2=270.000000
L 6.13671673 1.9474002 6.13206673 1.94816673 1 P 0 ;0,1=466,2=270.000000
L 6.13206673 1.94816673 6.12638366 1.94816673 1 P 0 ;0,1=466,2=270.000000
L 6.12638366 1.94816673 6.12173376 1.9474002 1 P 0 ;0,1=466,2=270.000000
L 6.12173376 1.9474002 6.1176003 1.94548327 1 P 0 ;0,1=466,2=270.000000
L 6.1176003 1.94548327 6.11553317 1.94318307 1 P 0 ;0,1=466,2=270.000000
L 6.11553317 1.94318307 6.1145 1.94049961 1 P 0 ;0,1=466,2=270.000000
L 6.1145 1.94049961 6.11553317 1.93743287 1 P 0 ;0,1=466,2=270.000000
L 6.11553317 1.93743287 6.1176003 1.93513337 1 P 0 ;0,1=466,2=270.000000
L 6.1176003 1.93513337 6.1206997 1.9335997 1 P 0 ;0,1=466,2=270.000000
L 6.1206997 1.9335997 6.12483406 1.93283317 1 P 0 ;0,1=466,2=270.000000
L 6.12483406 1.93283317 6.1284499 1.9335997 1 P 0 ;0,1=466,2=270.000000
L 6.1284499 1.9335997 6.13206673 1.93551663 1 P 0 ;0,1=466,2=270.000000
L 6.13206673 1.93551663 6.13413396 1.93781683 1 P 0 ;0,1=466,2=270.000000
L 6.13413396 1.93781683 6.13465049 1.94049961 1 P 0 ;0,1=466,2=270.000000
L 6.13465049 1.94049961 6.13361732 1.94356634 1 P 0 ;0,1=466,2=270.000000
L 6.13361732 1.94356634 6.13103366 1.94586654 1 P 0 ;0,1=466,2=270.000000
L 6.13103366 1.94586654 6.12638366 1.94816673 1 P 0 ;0,1=466,2=270.000000
L 6.14188415 1.96498287 6.14446693 1.96766634 1 P 0 ;0,1=466,2=270.000000
L 6.14446693 1.96766634 6.1455 1.97073307 1 P 0 ;0,1=466,2=270.000000
L 6.1455 1.97073307 6.14446693 1.9737998 1 P 0 ;0,1=466,2=270.000000
L 6.14446693 1.9737998 6.14136762 1.97648327 1 P 0 ;0,1=466,2=270.000000
L 6.14136762 1.97648327 6.13671673 1.9784002 1 P 0 ;0,1=466,2=270.000000
L 6.13671673 1.9784002 6.13206673 1.97916673 1 P 0 ;0,1=466,2=270.000000
L 6.13206673 1.97916673 6.12638366 1.97916673 1 P 0 ;0,1=466,2=270.000000
L 6.12638366 1.97916673 6.12173376 1.9784002 1 P 0 ;0,1=466,2=270.000000
L 6.12173376 1.9784002 6.1176003 1.97648327 1 P 0 ;0,1=466,2=270.000000
L 6.1176003 1.97648327 6.11553317 1.97418307 1 P 0 ;0,1=466,2=270.000000
L 6.11553317 1.97418307 6.1145 1.97149961 1 P 0 ;0,1=466,2=270.000000
L 6.1145 1.97149961 6.11553317 1.96843287 1 P 0 ;0,1=466,2=270.000000
L 6.11553317 1.96843287 6.1176003 1.96613337 1 P 0 ;0,1=466,2=270.000000
L 6.1176003 1.96613337 6.1206997 1.9645997 1 P 0 ;0,1=466,2=270.000000
L 6.1206997 1.9645997 6.12483406 1.96383317 1 P 0 ;0,1=466,2=270.000000
L 6.12483406 1.96383317 6.1284499 1.9645997 1 P 0 ;0,1=466,2=270.000000
L 6.1284499 1.9645997 6.13206673 1.96651663 1 P 0 ;0,1=466,2=270.000000
L 6.13206673 1.96651663 6.13413396 1.96881683 1 P 0 ;0,1=466,2=270.000000
L 6.13413396 1.96881683 6.13465049 1.97149961 1 P 0 ;0,1=466,2=270.000000
L 6.13465049 1.97149961 6.13361732 1.97456634 1 P 0 ;0,1=466,2=270.000000
L 6.13361732 1.97456634 6.13103366 1.97686654 1 P 0 ;0,1=466,2=270.000000
L 6.13103366 1.97686654 6.12638366 1.97916673 1 P 0 ;0,1=466,2=270.000000
L 6.09101998 1.88465 6.09101998 1.97465 1 P 0 
L 6.09101998 1.97465 6.04701998 1.97465 1 P 0 
L 6.04701998 1.97465 6.04701998 1.88465 1 P 0 
L 6.04701998 1.88465 6.09101998 1.88465 1 P 0 
L 6.1855 1.89133317 6.1545 1.89133317 1 P 0 ;0,1=467,2=270.000000
L 6.1545 1.89133317 6.1545 1.90091654 1 P 0 ;0,1=467,2=270.000000
L 6.1545 1.90091654 6.15605069 1.90398327 1 P 0 ;0,1=467,2=270.000000
L 6.15605069 1.90398327 6.15811693 1.9059002 1 P 0 ;0,1=467,2=270.000000
L 6.15811693 1.9059002 6.1622503 1.90666673 1 P 0 ;0,1=467,2=270.000000
L 6.1622503 1.90666673 6.16638366 1.9059002 1 P 0 ;0,1=467,2=270.000000
L 6.16638366 1.9059002 6.16896644 1.9036 1 P 0 ;0,1=467,2=270.000000
L 6.16896644 1.9036 6.17051713 1.90091654 1 P 0 ;0,1=467,2=270.000000
L 6.17051713 1.90091654 6.17051713 1.89133317 1 P 0 ;0,1=467,2=270.000000
L 6.17051713 1.90091654 6.1855 1.90666673 1 P 0 ;0,1=467,2=270.000000
L 6.17258425 1.92271644 6.16896644 1.9253999 1 P 0 ;0,1=467,2=270.000000
L 6.16896644 1.9253999 6.1669002 1.9277001 1 P 0 ;0,1=467,2=270.000000
L 6.1669002 1.9277001 6.16586713 1.93076683 1 P 0 ;0,1=467,2=270.000000
L 6.16586713 1.93076683 6.1669002 1.9334503 1 P 0 ;0,1=467,2=270.000000
L 6.1669002 1.9334503 6.16896644 1.93536654 1 P 0 ;0,1=467,2=270.000000
L 6.16896644 1.93536654 6.17206673 1.9369002 1 P 0 ;0,1=467,2=270.000000
L 6.17206673 1.9369002 6.17568356 1.93728346 1 P 0 ;0,1=467,2=270.000000
L 6.17568356 1.93728346 6.17878386 1.9369002 1 P 0 ;0,1=467,2=270.000000
L 6.17878386 1.9369002 6.18188415 1.93536654 1 P 0 ;0,1=467,2=270.000000
L 6.18188415 1.93536654 6.18446693 1.93306634 1 P 0 ;0,1=467,2=270.000000
L 6.18446693 1.93306634 6.1855 1.93038356 1 P 0 ;0,1=467,2=270.000000
L 6.1855 1.93038356 6.18446693 1.92731683 1 P 0 ;0,1=467,2=270.000000
L 6.18446693 1.92731683 6.18136762 1.92463337 1 P 0 ;0,1=467,2=270.000000
L 6.18136762 1.92463337 6.17671673 1.9230997 1 P 0 ;0,1=467,2=270.000000
L 6.17671673 1.9230997 6.1715502 1.92271644 1 P 0 ;0,1=467,2=270.000000
L 6.1715502 1.92271644 6.16483406 1.92348287 1 P 0 ;0,1=467,2=270.000000
L 6.16483406 1.92348287 6.16121624 1.92463337 1 P 0 ;0,1=467,2=270.000000
L 6.16121624 1.92463337 6.1576003 1.92654961 1 P 0 ;0,1=467,2=270.000000
L 6.1576003 1.92654961 6.15501663 1.92923307 1 P 0 ;0,1=467,2=270.000000
L 6.15501663 1.92923307 6.1545 1.93191654 1 P 0 ;0,1=467,2=270.000000
L 6.1545 1.93191654 6.15553317 1.9346 1 P 0 ;0,1=467,2=270.000000
L 6.15553317 1.9346 6.15811693 1.93651703 1 P 0 ;0,1=467,2=270.000000
L 6.1855 1.96023307 6.17878386 1.96099961 1 P 0 ;0,1=467,2=270.000000
L 6.17878386 1.96099961 6.17310079 1.9621501 1 P 0 ;0,1=467,2=270.000000
L 6.17310079 1.9621501 6.16793337 1.96368307 1 P 0 ;0,1=467,2=270.000000
L 6.16793337 1.96368307 6.1622503 1.9656 1 P 0 ;0,1=467,2=270.000000
L 6.1622503 1.9656 6.1545 1.96866673 1 P 0 ;0,1=467,2=270.000000
L 6.1545 1.96866673 6.1545 1.95333317 1 P 0 ;0,1=467,2=270.000000
L 5.99101998 1.88465 5.99101998 1.97465 1 P 0 
L 5.99101998 1.97465 5.94701998 1.97465 1 P 0 
L 5.94701998 1.97465 5.94701998 1.88465 1 P 0 
L 5.94701998 1.88465 5.99101998 1.88465 1 P 0 
L 5.8695 1.89103317 5.8385 1.89103317 1 P 0 ;0,1=468,2=270.000000
L 5.8385 1.89103317 5.8385 1.90061654 1 P 0 ;0,1=468,2=270.000000
L 5.8385 1.90061654 5.84005069 1.90368327 1 P 0 ;0,1=468,2=270.000000
L 5.84005069 1.90368327 5.84211693 1.9056002 1 P 0 ;0,1=468,2=270.000000
L 5.84211693 1.9056002 5.8462503 1.90636673 1 P 0 ;0,1=468,2=270.000000
L 5.8462503 1.90636673 5.85038366 1.9056002 1 P 0 ;0,1=468,2=270.000000
L 5.85038366 1.9056002 5.85296644 1.9033 1 P 0 ;0,1=468,2=270.000000
L 5.85296644 1.9033 5.85451713 1.90061654 1 P 0 ;0,1=468,2=270.000000
L 5.85451713 1.90061654 5.85451713 1.89103317 1 P 0 ;0,1=468,2=270.000000
L 5.85451713 1.90061654 5.8695 1.90636673 1 P 0 ;0,1=468,2=270.000000
L 5.85658425 1.92241644 5.85296644 1.9250999 1 P 0 ;0,1=468,2=270.000000
L 5.85296644 1.9250999 5.8509002 1.9274001 1 P 0 ;0,1=468,2=270.000000
L 5.8509002 1.9274001 5.84986713 1.93046683 1 P 0 ;0,1=468,2=270.000000
L 5.84986713 1.93046683 5.8509002 1.9331503 1 P 0 ;0,1=468,2=270.000000
L 5.8509002 1.9331503 5.85296644 1.93506654 1 P 0 ;0,1=468,2=270.000000
L 5.85296644 1.93506654 5.85606673 1.9366002 1 P 0 ;0,1=468,2=270.000000
L 5.85606673 1.9366002 5.85968356 1.93698346 1 P 0 ;0,1=468,2=270.000000
L 5.85968356 1.93698346 5.86278386 1.9366002 1 P 0 ;0,1=468,2=270.000000
L 5.86278386 1.9366002 5.86588415 1.93506654 1 P 0 ;0,1=468,2=270.000000
L 5.86588415 1.93506654 5.86846693 1.93276634 1 P 0 ;0,1=468,2=270.000000
L 5.86846693 1.93276634 5.8695 1.93008356 1 P 0 ;0,1=468,2=270.000000
L 5.8695 1.93008356 5.86846693 1.92701683 1 P 0 ;0,1=468,2=270.000000
L 5.86846693 1.92701683 5.86536762 1.92433337 1 P 0 ;0,1=468,2=270.000000
L 5.86536762 1.92433337 5.86071673 1.9227997 1 P 0 ;0,1=468,2=270.000000
L 5.86071673 1.9227997 5.8555502 1.92241644 1 P 0 ;0,1=468,2=270.000000
L 5.8555502 1.92241644 5.84883406 1.92318287 1 P 0 ;0,1=468,2=270.000000
L 5.84883406 1.92318287 5.84521624 1.92433337 1 P 0 ;0,1=468,2=270.000000
L 5.84521624 1.92433337 5.8416003 1.92624961 1 P 0 ;0,1=468,2=270.000000
L 5.8416003 1.92624961 5.83901663 1.92893307 1 P 0 ;0,1=468,2=270.000000
L 5.83901663 1.92893307 5.8385 1.93161654 1 P 0 ;0,1=468,2=270.000000
L 5.8385 1.93161654 5.83953317 1.9343 1 P 0 ;0,1=468,2=270.000000
L 5.83953317 1.9343 5.84211693 1.93621703 1 P 0 ;0,1=468,2=270.000000
L 5.8695 1.96069961 5.86898346 1.96338307 1 P 0 ;0,1=468,2=270.000000
L 5.86898346 1.96338307 5.86743386 1.9664498 1 P 0 ;0,1=468,2=270.000000
L 5.86743386 1.9664498 5.86485108 1.96836673 1 P 0 ;0,1=468,2=270.000000
L 5.86485108 1.96836673 5.86123327 1.96913327 1 P 0 ;0,1=468,2=270.000000
L 5.86123327 1.96913327 5.85761732 1.96836673 1 P 0 ;0,1=468,2=270.000000
L 5.85761732 1.96836673 5.85451713 1.96606654 1 P 0 ;0,1=468,2=270.000000
L 5.85451713 1.96606654 5.85296644 1.96261654 1 P 0 ;0,1=468,2=270.000000
L 5.85296644 1.96261654 5.85296644 1.95878337 1 P 0 ;0,1=468,2=270.000000
L 5.85296644 1.95878337 5.85193337 1.95648317 1 P 0 ;0,1=468,2=270.000000
L 5.85193337 1.95648317 5.84935059 1.95456614 1 P 0 ;0,1=468,2=270.000000
L 5.84935059 1.95456614 5.84573376 1.9537997 1 P 0 ;0,1=468,2=270.000000
L 5.84573376 1.9537997 5.84211693 1.9549501 1 P 0 ;0,1=468,2=270.000000
L 5.84211693 1.9549501 5.83953317 1.95763287 1 P 0 ;0,1=468,2=270.000000
L 5.83953317 1.95763287 5.8385 1.96069961 1 P 0 ;0,1=468,2=270.000000
L 5.8385 1.96069961 5.83953317 1.96376634 1 P 0 ;0,1=468,2=270.000000
L 5.83953317 1.96376634 5.84211693 1.9664498 1 P 0 ;0,1=468,2=270.000000
L 5.84211693 1.9664498 5.84573376 1.9676002 1 P 0 ;0,1=468,2=270.000000
L 5.84573376 1.9676002 5.84935059 1.96683307 1 P 0 ;0,1=468,2=270.000000
L 5.84935059 1.96683307 5.85193337 1.96491673 1 P 0 ;0,1=468,2=270.000000
L 5.85193337 1.96491673 5.85296644 1.96261654 1 P 0 ;0,1=468,2=270.000000
L 5.85296644 1.96261654 5.85296644 1.95878337 1 P 0 ;0,1=468,2=270.000000
L 5.85296644 1.95878337 5.85451713 1.95533337 1 P 0 ;0,1=468,2=270.000000
L 5.85451713 1.95533337 5.85761732 1.95303317 1 P 0 ;0,1=468,2=270.000000
L 5.85761732 1.95303317 5.86123327 1.95226663 1 P 0 ;0,1=468,2=270.000000
L 5.86123327 1.95226663 5.86485108 1.95303317 1 P 0 ;0,1=468,2=270.000000
L 5.86485108 1.95303317 5.86743386 1.9549501 1 P 0 ;0,1=468,2=270.000000
L 5.86743386 1.9549501 5.86898346 1.95801683 1 P 0 ;0,1=468,2=270.000000
L 5.86898346 1.95801683 5.8695 1.96069961 1 P 0 ;0,1=468,2=270.000000
L 5.94101998 1.88465 5.94101998 1.97465 1 P 0 
L 5.94101998 1.97465 5.89701998 1.97465 1 P 0 
L 5.89701998 1.97465 5.89701998 1.88465 1 P 0 
L 5.89701998 1.88465 5.94101998 1.88465 1 P 0 
L 5.8055 1.89133317 5.7745 1.89133317 1 P 0 ;0,1=469,2=270.000000
L 5.7745 1.89133317 5.7745 1.90091654 1 P 0 ;0,1=469,2=270.000000
L 5.7745 1.90091654 5.77605069 1.90398327 1 P 0 ;0,1=469,2=270.000000
L 5.77605069 1.90398327 5.77811693 1.9059002 1 P 0 ;0,1=469,2=270.000000
L 5.77811693 1.9059002 5.7822503 1.90666673 1 P 0 ;0,1=469,2=270.000000
L 5.7822503 1.90666673 5.78638366 1.9059002 1 P 0 ;0,1=469,2=270.000000
L 5.78638366 1.9059002 5.78896644 1.9036 1 P 0 ;0,1=469,2=270.000000
L 5.78896644 1.9036 5.79051713 1.90091654 1 P 0 ;0,1=469,2=270.000000
L 5.79051713 1.90091654 5.79051713 1.89133317 1 P 0 ;0,1=469,2=270.000000
L 5.79051713 1.90091654 5.8055 1.90666673 1 P 0 ;0,1=469,2=270.000000
L 5.79258425 1.92271644 5.78896644 1.9253999 1 P 0 ;0,1=469,2=270.000000
L 5.78896644 1.9253999 5.7869002 1.9277001 1 P 0 ;0,1=469,2=270.000000
L 5.7869002 1.9277001 5.78586713 1.93076683 1 P 0 ;0,1=469,2=270.000000
L 5.78586713 1.93076683 5.7869002 1.9334503 1 P 0 ;0,1=469,2=270.000000
L 5.7869002 1.9334503 5.78896644 1.93536654 1 P 0 ;0,1=469,2=270.000000
L 5.78896644 1.93536654 5.79206673 1.9369002 1 P 0 ;0,1=469,2=270.000000
L 5.79206673 1.9369002 5.79568356 1.93728346 1 P 0 ;0,1=469,2=270.000000
L 5.79568356 1.93728346 5.79878386 1.9369002 1 P 0 ;0,1=469,2=270.000000
L 5.79878386 1.9369002 5.80188415 1.93536654 1 P 0 ;0,1=469,2=270.000000
L 5.80188415 1.93536654 5.80446693 1.93306634 1 P 0 ;0,1=469,2=270.000000
L 5.80446693 1.93306634 5.8055 1.93038356 1 P 0 ;0,1=469,2=270.000000
L 5.8055 1.93038356 5.80446693 1.92731683 1 P 0 ;0,1=469,2=270.000000
L 5.80446693 1.92731683 5.80136762 1.92463337 1 P 0 ;0,1=469,2=270.000000
L 5.80136762 1.92463337 5.79671673 1.9230997 1 P 0 ;0,1=469,2=270.000000
L 5.79671673 1.9230997 5.7915502 1.92271644 1 P 0 ;0,1=469,2=270.000000
L 5.7915502 1.92271644 5.78483406 1.92348287 1 P 0 ;0,1=469,2=270.000000
L 5.78483406 1.92348287 5.78121624 1.92463337 1 P 0 ;0,1=469,2=270.000000
L 5.78121624 1.92463337 5.7776003 1.92654961 1 P 0 ;0,1=469,2=270.000000
L 5.7776003 1.92654961 5.77501663 1.92923307 1 P 0 ;0,1=469,2=270.000000
L 5.77501663 1.92923307 5.7745 1.93191654 1 P 0 ;0,1=469,2=270.000000
L 5.7745 1.93191654 5.77553317 1.9346 1 P 0 ;0,1=469,2=270.000000
L 5.77553317 1.9346 5.77811693 1.93651703 1 P 0 ;0,1=469,2=270.000000
L 5.79258425 1.95371644 5.78896644 1.9563999 1 P 0 ;0,1=469,2=270.000000
L 5.78896644 1.9563999 5.7869002 1.9587001 1 P 0 ;0,1=469,2=270.000000
L 5.7869002 1.9587001 5.78586713 1.96176683 1 P 0 ;0,1=469,2=270.000000
L 5.78586713 1.96176683 5.7869002 1.9644503 1 P 0 ;0,1=469,2=270.000000
L 5.7869002 1.9644503 5.78896644 1.96636654 1 P 0 ;0,1=469,2=270.000000
L 5.78896644 1.96636654 5.79206673 1.9679002 1 P 0 ;0,1=469,2=270.000000
L 5.79206673 1.9679002 5.79568356 1.96828346 1 P 0 ;0,1=469,2=270.000000
L 5.79568356 1.96828346 5.79878386 1.9679002 1 P 0 ;0,1=469,2=270.000000
L 5.79878386 1.9679002 5.80188415 1.96636654 1 P 0 ;0,1=469,2=270.000000
L 5.80188415 1.96636654 5.80446693 1.96406634 1 P 0 ;0,1=469,2=270.000000
L 5.80446693 1.96406634 5.8055 1.96138356 1 P 0 ;0,1=469,2=270.000000
L 5.8055 1.96138356 5.80446693 1.95831683 1 P 0 ;0,1=469,2=270.000000
L 5.80446693 1.95831683 5.80136762 1.95563337 1 P 0 ;0,1=469,2=270.000000
L 5.80136762 1.95563337 5.79671673 1.9540997 1 P 0 ;0,1=469,2=270.000000
L 5.79671673 1.9540997 5.7915502 1.95371644 1 P 0 ;0,1=469,2=270.000000
L 5.7915502 1.95371644 5.78483406 1.95448287 1 P 0 ;0,1=469,2=270.000000
L 5.78483406 1.95448287 5.78121624 1.95563337 1 P 0 ;0,1=469,2=270.000000
L 5.78121624 1.95563337 5.7776003 1.95754961 1 P 0 ;0,1=469,2=270.000000
L 5.7776003 1.95754961 5.77501663 1.96023307 1 P 0 ;0,1=469,2=270.000000
L 5.77501663 1.96023307 5.7745 1.96291654 1 P 0 ;0,1=469,2=270.000000
L 5.7745 1.96291654 5.77553317 1.9656 1 P 0 ;0,1=469,2=270.000000
L 5.77553317 1.9656 5.77811693 1.96751703 1 P 0 ;0,1=469,2=270.000000
L 5.98 1.058 5.98 1.102 1 P 0 
L 5.98 1.102 5.89 1.102 1 P 0 
L 5.89 1.058 5.98 1.058 1 P 0 
L 5.89 1.102 5.89 1.058 1 P 0 
L 5.85083317 1.1495 5.85083317 1.1805 1 P 0 ;0,1=470,2=0.000000
L 5.85083317 1.1805 5.86041654 1.1805 1 P 0 ;0,1=470,2=0.000000
L 5.86041654 1.1805 5.86348327 1.17894931 1 P 0 ;0,1=470,2=0.000000
L 5.86348327 1.17894931 5.8654002 1.17688307 1 P 0 ;0,1=470,2=0.000000
L 5.8654002 1.17688307 5.86616673 1.1727497 1 P 0 ;0,1=470,2=0.000000
L 5.86616673 1.1727497 5.8654002 1.16861634 1 P 0 ;0,1=470,2=0.000000
L 5.8654002 1.16861634 5.8631 1.16603356 1 P 0 ;0,1=470,2=0.000000
L 5.8631 1.16603356 5.86041654 1.16448287 1 P 0 ;0,1=470,2=0.000000
L 5.86041654 1.16448287 5.85083317 1.16448287 1 P 0 ;0,1=470,2=0.000000
L 5.86041654 1.16448287 5.86616673 1.1495 1 P 0 ;0,1=470,2=0.000000
L 5.8941 1.1495 5.8941 1.1805 1 P 0 ;0,1=470,2=0.000000
L 5.8941 1.1805 5.87991624 1.15828327 1 P 0 ;0,1=470,2=0.000000
L 5.87991624 1.15828327 5.89908366 1.15828327 1 P 0 ;0,1=470,2=0.000000
L 5.92049961 1.1805 5.91743287 1.17946683 1 P 0 ;0,1=470,2=0.000000
L 5.91743287 1.17946683 5.91513337 1.17688307 1 P 0 ;0,1=470,2=0.000000
L 5.91513337 1.17688307 5.9135997 1.17378376 1 P 0 ;0,1=470,2=0.000000
L 5.9135997 1.17378376 5.9124499 1.16964941 1 P 0 ;0,1=470,2=0.000000
L 5.9124499 1.16964941 5.91206663 1.16499951 1 P 0 ;0,1=470,2=0.000000
L 5.91206663 1.16499951 5.9124499 1.16034951 1 P 0 ;0,1=470,2=0.000000
L 5.9124499 1.16034951 5.9135997 1.15621614 1 P 0 ;0,1=470,2=0.000000
L 5.9135997 1.15621614 5.91513337 1.15311585 1 P 0 ;0,1=470,2=0.000000
L 5.91513337 1.15311585 5.91743287 1.15053307 1 P 0 ;0,1=470,2=0.000000
L 5.91743287 1.15053307 5.92049961 1.1495 1 P 0 ;0,1=470,2=0.000000
L 5.92049961 1.1495 5.92356634 1.15053307 1 P 0 ;0,1=470,2=0.000000
L 5.92356634 1.15053307 5.92586654 1.15311585 1 P 0 ;0,1=470,2=0.000000
L 5.92586654 1.15311585 5.9274002 1.15621614 1 P 0 ;0,1=470,2=0.000000
L 5.9274002 1.15621614 5.92855 1.16034951 1 P 0 ;0,1=470,2=0.000000
L 5.92855 1.16034951 5.92893327 1.16499951 1 P 0 ;0,1=470,2=0.000000
L 5.92893327 1.16499951 5.92855 1.16964941 1 P 0 ;0,1=470,2=0.000000
L 5.92855 1.16964941 5.9274002 1.17378376 1 P 0 ;0,1=470,2=0.000000
L 5.9274002 1.17378376 5.92586654 1.17688307 1 P 0 ;0,1=470,2=0.000000
L 5.92586654 1.17688307 5.92356634 1.17946683 1 P 0 ;0,1=470,2=0.000000
L 5.92356634 1.17946683 5.92049961 1.1805 1 P 0 ;0,1=470,2=0.000000
L 5.95073307 1.1495 5.95149961 1.15621614 1 P 0 ;0,1=470,2=0.000000
L 5.95149961 1.15621614 5.9526501 1.16189921 1 P 0 ;0,1=470,2=0.000000
L 5.9526501 1.16189921 5.95418307 1.16706663 1 P 0 ;0,1=470,2=0.000000
L 5.95418307 1.16706663 5.9561 1.1727497 1 P 0 ;0,1=470,2=0.000000
L 5.9561 1.1727497 5.95916673 1.1805 1 P 0 ;0,1=470,2=0.000000
L 5.95916673 1.1805 5.94383317 1.1805 1 P 0 ;0,1=470,2=0.000000
L 4.059 2.576 4.015 2.576 1 P 0 
L 4.015 2.576 4.015 2.486 1 P 0 
L 4.015 2.486 4.059 2.486 1 P 0 
L 4.059 2.486 4.059 2.576 1 P 0 
L 4.0805 2.36583317 4.0495 2.36583317 1 P 0 ;0,1=471,2=270.000000
L 4.0495 2.36583317 4.0495 2.37541654 1 P 0 ;0,1=471,2=270.000000
L 4.0495 2.37541654 4.05105069 2.37848327 1 P 0 ;0,1=471,2=270.000000
L 4.05105069 2.37848327 4.05311693 2.3804002 1 P 0 ;0,1=471,2=270.000000
L 4.05311693 2.3804002 4.0572503 2.38116673 1 P 0 ;0,1=471,2=270.000000
L 4.0572503 2.38116673 4.06138366 2.3804002 1 P 0 ;0,1=471,2=270.000000
L 4.06138366 2.3804002 4.06396644 2.3781 1 P 0 ;0,1=471,2=270.000000
L 4.06396644 2.3781 4.06551713 2.37541654 1 P 0 ;0,1=471,2=270.000000
L 4.06551713 2.37541654 4.06551713 2.36583317 1 P 0 ;0,1=471,2=270.000000
L 4.06551713 2.37541654 4.0805 2.38116673 1 P 0 ;0,1=471,2=270.000000
L 4.05466654 2.39721644 4.05156722 2.39951663 1 P 0 ;0,1=471,2=270.000000
L 4.05156722 2.39951663 4.05001663 2.4022001 1 P 0 ;0,1=471,2=270.000000
L 4.05001663 2.4022001 4.0495 2.40526683 1 P 0 ;0,1=471,2=270.000000
L 4.0495 2.40526683 4.05053317 2.4091 1 P 0 ;0,1=471,2=270.000000
L 4.05053317 2.4091 4.05311693 2.41178346 1 P 0 ;0,1=471,2=270.000000
L 4.05311693 2.41178346 4.05621624 2.41255 1 P 0 ;0,1=471,2=270.000000
L 4.05621624 2.41255 4.05931742 2.41216673 1 P 0 ;0,1=471,2=270.000000
L 4.05931742 2.41216673 4.0619002 2.41063307 1 P 0 ;0,1=471,2=270.000000
L 4.0619002 2.41063307 4.06706673 2.40296663 1 P 0 ;0,1=471,2=270.000000
L 4.06706673 2.40296663 4.07068356 2.39951663 1 P 0 ;0,1=471,2=270.000000
L 4.07068356 2.39951663 4.07585108 2.39721644 1 P 0 ;0,1=471,2=270.000000
L 4.07585108 2.39721644 4.0805 2.3964499 1 P 0 ;0,1=471,2=270.000000
L 4.0805 2.3964499 4.0805 2.41255 1 P 0 ;0,1=471,2=270.000000
L 4.07688415 2.42898287 4.07946693 2.43166634 1 P 0 ;0,1=471,2=270.000000
L 4.07946693 2.43166634 4.0805 2.43473307 1 P 0 ;0,1=471,2=270.000000
L 4.0805 2.43473307 4.07946693 2.4377998 1 P 0 ;0,1=471,2=270.000000
L 4.07946693 2.4377998 4.07636762 2.44048327 1 P 0 ;0,1=471,2=270.000000
L 4.07636762 2.44048327 4.07171673 2.4424002 1 P 0 ;0,1=471,2=270.000000
L 4.07171673 2.4424002 4.06706673 2.44316673 1 P 0 ;0,1=471,2=270.000000
L 4.06706673 2.44316673 4.06138366 2.44316673 1 P 0 ;0,1=471,2=270.000000
L 4.06138366 2.44316673 4.05673376 2.4424002 1 P 0 ;0,1=471,2=270.000000
L 4.05673376 2.4424002 4.0526003 2.44048327 1 P 0 ;0,1=471,2=270.000000
L 4.0526003 2.44048327 4.05053317 2.43818307 1 P 0 ;0,1=471,2=270.000000
L 4.05053317 2.43818307 4.0495 2.43549961 1 P 0 ;0,1=471,2=270.000000
L 4.0495 2.43549961 4.05053317 2.43243287 1 P 0 ;0,1=471,2=270.000000
L 4.05053317 2.43243287 4.0526003 2.43013337 1 P 0 ;0,1=471,2=270.000000
L 4.0526003 2.43013337 4.0556997 2.4285997 1 P 0 ;0,1=471,2=270.000000
L 4.0556997 2.4285997 4.05983406 2.42783317 1 P 0 ;0,1=471,2=270.000000
L 4.05983406 2.42783317 4.0634499 2.4285997 1 P 0 ;0,1=471,2=270.000000
L 4.0634499 2.4285997 4.06706673 2.43051663 1 P 0 ;0,1=471,2=270.000000
L 4.06706673 2.43051663 4.06913396 2.43281683 1 P 0 ;0,1=471,2=270.000000
L 4.06913396 2.43281683 4.06965049 2.43549961 1 P 0 ;0,1=471,2=270.000000
L 4.06965049 2.43549961 4.06861732 2.43856634 1 P 0 ;0,1=471,2=270.000000
L 4.06861732 2.43856634 4.06603366 2.44086654 1 P 0 ;0,1=471,2=270.000000
L 4.06603366 2.44086654 4.06138366 2.44316673 1 P 0 ;0,1=471,2=270.000000
L 4.05466654 2.45921644 4.05156722 2.46151663 1 P 0 ;0,1=471,2=270.000000
L 4.05156722 2.46151663 4.05001663 2.4642001 1 P 0 ;0,1=471,2=270.000000
L 4.05001663 2.4642001 4.0495 2.46726683 1 P 0 ;0,1=471,2=270.000000
L 4.0495 2.46726683 4.05053317 2.4711 1 P 0 ;0,1=471,2=270.000000
L 4.05053317 2.4711 4.05311693 2.47378346 1 P 0 ;0,1=471,2=270.000000
L 4.05311693 2.47378346 4.05621624 2.47455 1 P 0 ;0,1=471,2=270.000000
L 4.05621624 2.47455 4.05931742 2.47416673 1 P 0 ;0,1=471,2=270.000000
L 4.05931742 2.47416673 4.0619002 2.47263307 1 P 0 ;0,1=471,2=270.000000
L 4.0619002 2.47263307 4.06706673 2.46496663 1 P 0 ;0,1=471,2=270.000000
L 4.06706673 2.46496663 4.07068356 2.46151663 1 P 0 ;0,1=471,2=270.000000
L 4.07068356 2.46151663 4.07585108 2.45921644 1 P 0 ;0,1=471,2=270.000000
L 4.07585108 2.45921644 4.0805 2.4584499 1 P 0 ;0,1=471,2=270.000000
L 4.0805 2.4584499 4.0805 2.47455 1 P 0 ;0,1=471,2=270.000000
L 3.307 2.487 3.307 2.577 1 P 0 
L 3.307 2.577 3.263 2.577 1 P 0 
L 3.263 2.577 3.263 2.487 1 P 0 
L 3.263 2.487 3.307 2.487 1 P 0 
L 2.9155 3.00583317 2.8845 3.00583317 1 P 0 ;0,1=472,2=270.000000
L 2.8845 3.00583317 2.8845 3.01541654 1 P 0 ;0,1=472,2=270.000000
L 2.8845 3.01541654 2.88605069 3.01848327 1 P 0 ;0,1=472,2=270.000000
L 2.88605069 3.01848327 2.88811693 3.0204002 1 P 0 ;0,1=472,2=270.000000
L 2.88811693 3.0204002 2.8922503 3.02116673 1 P 0 ;0,1=472,2=270.000000
L 2.8922503 3.02116673 2.89638366 3.0204002 1 P 0 ;0,1=472,2=270.000000
L 2.89638366 3.0204002 2.89896644 3.0181 1 P 0 ;0,1=472,2=270.000000
L 2.89896644 3.0181 2.90051713 3.01541654 1 P 0 ;0,1=472,2=270.000000
L 2.90051713 3.01541654 2.90051713 3.00583317 1 P 0 ;0,1=472,2=270.000000
L 2.90051713 3.01541654 2.9155 3.02116673 1 P 0 ;0,1=472,2=270.000000
L 2.90930039 3.03606663 2.91291722 3.03836614 1 P 0 ;0,1=472,2=270.000000
L 2.91291722 3.03836614 2.91498346 3.04143287 1 P 0 ;0,1=472,2=270.000000
L 2.91498346 3.04143287 2.9155 3.04488356 1 P 0 ;0,1=472,2=270.000000
L 2.9155 3.04488356 2.91498346 3.0479503 1 P 0 ;0,1=472,2=270.000000
L 2.91498346 3.0479503 2.91240069 3.05101703 1 P 0 ;0,1=472,2=270.000000
L 2.91240069 3.05101703 2.90930039 3.05293327 1 P 0 ;0,1=472,2=270.000000
L 2.90930039 3.05293327 2.9062001 3.05331654 1 P 0 ;0,1=472,2=270.000000
L 2.9062001 3.05331654 2.90258425 3.05255 1 P 0 ;0,1=472,2=270.000000
L 2.90258425 3.05255 2.90000049 3.04986654 1 P 0 ;0,1=472,2=270.000000
L 2.90000049 3.04986654 2.89896644 3.04718307 1 P 0 ;0,1=472,2=270.000000
L 2.89896644 3.04718307 2.89896644 3.04373307 1 P 0 ;0,1=472,2=270.000000
L 2.89896644 3.04718307 2.89741683 3.04948327 1 P 0 ;0,1=472,2=270.000000
L 2.89741683 3.04948327 2.89483406 3.0514002 1 P 0 ;0,1=472,2=270.000000
L 2.89483406 3.0514002 2.89173376 3.05216673 1 P 0 ;0,1=472,2=270.000000
L 2.89173376 3.05216673 2.88863346 3.0514002 1 P 0 ;0,1=472,2=270.000000
L 2.88863346 3.0514002 2.88605069 3.04948327 1 P 0 ;0,1=472,2=270.000000
L 2.88605069 3.04948327 2.8845 3.04603327 1 P 0 ;0,1=472,2=270.000000
L 2.8845 3.04603327 2.88501663 3.04258337 1 P 0 ;0,1=472,2=270.000000
L 2.88501663 3.04258337 2.88708376 3.03913337 1 P 0 ;0,1=472,2=270.000000
L 2.8845 3.07549961 2.88553317 3.07243287 1 P 0 ;0,1=472,2=270.000000
L 2.88553317 3.07243287 2.88811693 3.07013337 1 P 0 ;0,1=472,2=270.000000
L 2.88811693 3.07013337 2.89121624 3.0685997 1 P 0 ;0,1=472,2=270.000000
L 2.89121624 3.0685997 2.89535059 3.0674499 1 P 0 ;0,1=472,2=270.000000
L 2.89535059 3.0674499 2.90000049 3.06706663 1 P 0 ;0,1=472,2=270.000000
L 2.90000049 3.06706663 2.90465049 3.0674499 1 P 0 ;0,1=472,2=270.000000
L 2.90465049 3.0674499 2.90878386 3.0685997 1 P 0 ;0,1=472,2=270.000000
L 2.90878386 3.0685997 2.91188415 3.07013337 1 P 0 ;0,1=472,2=270.000000
L 2.91188415 3.07013337 2.91446693 3.07243287 1 P 0 ;0,1=472,2=270.000000
L 2.91446693 3.07243287 2.9155 3.07549961 1 P 0 ;0,1=472,2=270.000000
L 2.9155 3.07549961 2.91446693 3.07856634 1 P 0 ;0,1=472,2=270.000000
L 2.91446693 3.07856634 2.91188415 3.08086654 1 P 0 ;0,1=472,2=270.000000
L 2.91188415 3.08086654 2.90878386 3.0824002 1 P 0 ;0,1=472,2=270.000000
L 2.90878386 3.0824002 2.90465049 3.08355 1 P 0 ;0,1=472,2=270.000000
L 2.90465049 3.08355 2.90000049 3.08393327 1 P 0 ;0,1=472,2=270.000000
L 2.90000049 3.08393327 2.89535059 3.08355 1 P 0 ;0,1=472,2=270.000000
L 2.89535059 3.08355 2.89121624 3.0824002 1 P 0 ;0,1=472,2=270.000000
L 2.89121624 3.0824002 2.88811693 3.08086654 1 P 0 ;0,1=472,2=270.000000
L 2.88811693 3.08086654 2.88553317 3.07856634 1 P 0 ;0,1=472,2=270.000000
L 2.88553317 3.07856634 2.8845 3.07549961 1 P 0 ;0,1=472,2=270.000000
L 2.90930039 3.09806663 2.91291722 3.10036614 1 P 0 ;0,1=472,2=270.000000
L 2.91291722 3.10036614 2.91498346 3.10343287 1 P 0 ;0,1=472,2=270.000000
L 2.91498346 3.10343287 2.9155 3.10688356 1 P 0 ;0,1=472,2=270.000000
L 2.9155 3.10688356 2.91498346 3.1099503 1 P 0 ;0,1=472,2=270.000000
L 2.91498346 3.1099503 2.91240069 3.11301703 1 P 0 ;0,1=472,2=270.000000
L 2.91240069 3.11301703 2.90930039 3.11493327 1 P 0 ;0,1=472,2=270.000000
L 2.90930039 3.11493327 2.9062001 3.11531654 1 P 0 ;0,1=472,2=270.000000
L 2.9062001 3.11531654 2.90258425 3.11455 1 P 0 ;0,1=472,2=270.000000
L 2.90258425 3.11455 2.90000049 3.11186654 1 P 0 ;0,1=472,2=270.000000
L 2.90000049 3.11186654 2.89896644 3.10918307 1 P 0 ;0,1=472,2=270.000000
L 2.89896644 3.10918307 2.89896644 3.10573307 1 P 0 ;0,1=472,2=270.000000
L 2.89896644 3.10918307 2.89741683 3.11148327 1 P 0 ;0,1=472,2=270.000000
L 2.89741683 3.11148327 2.89483406 3.1134002 1 P 0 ;0,1=472,2=270.000000
L 2.89483406 3.1134002 2.89173376 3.11416673 1 P 0 ;0,1=472,2=270.000000
L 2.89173376 3.11416673 2.88863346 3.1134002 1 P 0 ;0,1=472,2=270.000000
L 2.88863346 3.1134002 2.88605069 3.11148327 1 P 0 ;0,1=472,2=270.000000
L 2.88605069 3.11148327 2.8845 3.10803327 1 P 0 ;0,1=472,2=270.000000
L 2.8845 3.10803327 2.88501663 3.10458337 1 P 0 ;0,1=472,2=270.000000
L 2.88501663 3.10458337 2.88708376 3.10113337 1 P 0 ;0,1=472,2=270.000000
L 3.357 2.577 3.313 2.577 1 P 0 
L 3.313 2.577 3.313 2.487 1 P 0 
L 3.313 2.487 3.357 2.487 1 P 0 
L 3.357 2.487 3.357 2.577 1 P 0 
L 2.9555 3.00583317 2.9245 3.00583317 1 P 0 ;0,1=473,2=270.000000
L 2.9245 3.00583317 2.9245 3.01541654 1 P 0 ;0,1=473,2=270.000000
L 2.9245 3.01541654 2.92605069 3.01848327 1 P 0 ;0,1=473,2=270.000000
L 2.92605069 3.01848327 2.92811693 3.0204002 1 P 0 ;0,1=473,2=270.000000
L 2.92811693 3.0204002 2.9322503 3.02116673 1 P 0 ;0,1=473,2=270.000000
L 2.9322503 3.02116673 2.93638366 3.0204002 1 P 0 ;0,1=473,2=270.000000
L 2.93638366 3.0204002 2.93896644 3.0181 1 P 0 ;0,1=473,2=270.000000
L 2.93896644 3.0181 2.94051713 3.01541654 1 P 0 ;0,1=473,2=270.000000
L 2.94051713 3.01541654 2.94051713 3.00583317 1 P 0 ;0,1=473,2=270.000000
L 2.94051713 3.01541654 2.9555 3.02116673 1 P 0 ;0,1=473,2=270.000000
L 2.94930039 3.03606663 2.95291722 3.03836614 1 P 0 ;0,1=473,2=270.000000
L 2.95291722 3.03836614 2.95498346 3.04143287 1 P 0 ;0,1=473,2=270.000000
L 2.95498346 3.04143287 2.9555 3.04488356 1 P 0 ;0,1=473,2=270.000000
L 2.9555 3.04488356 2.95498346 3.0479503 1 P 0 ;0,1=473,2=270.000000
L 2.95498346 3.0479503 2.95240069 3.05101703 1 P 0 ;0,1=473,2=270.000000
L 2.95240069 3.05101703 2.94930039 3.05293327 1 P 0 ;0,1=473,2=270.000000
L 2.94930039 3.05293327 2.9462001 3.05331654 1 P 0 ;0,1=473,2=270.000000
L 2.9462001 3.05331654 2.94258425 3.05255 1 P 0 ;0,1=473,2=270.000000
L 2.94258425 3.05255 2.94000049 3.04986654 1 P 0 ;0,1=473,2=270.000000
L 2.94000049 3.04986654 2.93896644 3.04718307 1 P 0 ;0,1=473,2=270.000000
L 2.93896644 3.04718307 2.93896644 3.04373307 1 P 0 ;0,1=473,2=270.000000
L 2.93896644 3.04718307 2.93741683 3.04948327 1 P 0 ;0,1=473,2=270.000000
L 2.93741683 3.04948327 2.93483406 3.0514002 1 P 0 ;0,1=473,2=270.000000
L 2.93483406 3.0514002 2.93173376 3.05216673 1 P 0 ;0,1=473,2=270.000000
L 2.93173376 3.05216673 2.92863346 3.0514002 1 P 0 ;0,1=473,2=270.000000
L 2.92863346 3.0514002 2.92605069 3.04948327 1 P 0 ;0,1=473,2=270.000000
L 2.92605069 3.04948327 2.9245 3.04603327 1 P 0 ;0,1=473,2=270.000000
L 2.9245 3.04603327 2.92501663 3.04258337 1 P 0 ;0,1=473,2=270.000000
L 2.92501663 3.04258337 2.92708376 3.03913337 1 P 0 ;0,1=473,2=270.000000
L 2.9245 3.07549961 2.92553317 3.07243287 1 P 0 ;0,1=473,2=270.000000
L 2.92553317 3.07243287 2.92811693 3.07013337 1 P 0 ;0,1=473,2=270.000000
L 2.92811693 3.07013337 2.93121624 3.0685997 1 P 0 ;0,1=473,2=270.000000
L 2.93121624 3.0685997 2.93535059 3.0674499 1 P 0 ;0,1=473,2=270.000000
L 2.93535059 3.0674499 2.94000049 3.06706663 1 P 0 ;0,1=473,2=270.000000
L 2.94000049 3.06706663 2.94465049 3.0674499 1 P 0 ;0,1=473,2=270.000000
L 2.94465049 3.0674499 2.94878386 3.0685997 1 P 0 ;0,1=473,2=270.000000
L 2.94878386 3.0685997 2.95188415 3.07013337 1 P 0 ;0,1=473,2=270.000000
L 2.95188415 3.07013337 2.95446693 3.07243287 1 P 0 ;0,1=473,2=270.000000
L 2.95446693 3.07243287 2.9555 3.07549961 1 P 0 ;0,1=473,2=270.000000
L 2.9555 3.07549961 2.95446693 3.07856634 1 P 0 ;0,1=473,2=270.000000
L 2.95446693 3.07856634 2.95188415 3.08086654 1 P 0 ;0,1=473,2=270.000000
L 2.95188415 3.08086654 2.94878386 3.0824002 1 P 0 ;0,1=473,2=270.000000
L 2.94878386 3.0824002 2.94465049 3.08355 1 P 0 ;0,1=473,2=270.000000
L 2.94465049 3.08355 2.94000049 3.08393327 1 P 0 ;0,1=473,2=270.000000
L 2.94000049 3.08393327 2.93535059 3.08355 1 P 0 ;0,1=473,2=270.000000
L 2.93535059 3.08355 2.93121624 3.0824002 1 P 0 ;0,1=473,2=270.000000
L 2.93121624 3.0824002 2.92811693 3.08086654 1 P 0 ;0,1=473,2=270.000000
L 2.92811693 3.08086654 2.92553317 3.07856634 1 P 0 ;0,1=473,2=270.000000
L 2.92553317 3.07856634 2.9245 3.07549961 1 P 0 ;0,1=473,2=270.000000
L 2.9555 3.1111 2.9245 3.1111 1 P 0 ;0,1=473,2=270.000000
L 2.9245 3.1111 2.94671673 3.09691624 1 P 0 ;0,1=473,2=270.000000
L 2.94671673 3.09691624 2.94671673 3.11608366 1 P 0 ;0,1=473,2=270.000000
L 1.55 2.928 1.55 2.972 1 P 0 
L 1.55 2.972 1.46 2.972 1 P 0 
L 1.46 2.972 1.46 2.928 1 P 0 
L 1.46 2.928 1.55 2.928 1 P 0 
L 1.47083317 2.8845 1.47083317 2.9155 1 P 0 ;0,1=474,2=0.000000
L 1.47083317 2.9155 1.48041654 2.9155 1 P 0 ;0,1=474,2=0.000000
L 1.48041654 2.9155 1.48348327 2.91394931 1 P 0 ;0,1=474,2=0.000000
L 1.48348327 2.91394931 1.4854002 2.91188307 1 P 0 ;0,1=474,2=0.000000
L 1.4854002 2.91188307 1.48616673 2.9077497 1 P 0 ;0,1=474,2=0.000000
L 1.48616673 2.9077497 1.4854002 2.90361634 1 P 0 ;0,1=474,2=0.000000
L 1.4854002 2.90361634 1.4831 2.90103356 1 P 0 ;0,1=474,2=0.000000
L 1.4831 2.90103356 1.48041654 2.89948287 1 P 0 ;0,1=474,2=0.000000
L 1.48041654 2.89948287 1.47083317 2.89948287 1 P 0 ;0,1=474,2=0.000000
L 1.48041654 2.89948287 1.48616673 2.8845 1 P 0 ;0,1=474,2=0.000000
L 1.5141 2.8845 1.5141 2.9155 1 P 0 ;0,1=474,2=0.000000
L 1.5141 2.9155 1.49991624 2.89328327 1 P 0 ;0,1=474,2=0.000000
L 1.49991624 2.89328327 1.51908366 2.89328327 1 P 0 ;0,1=474,2=0.000000
L 1.54049961 2.8845 1.54318307 2.88501654 1 P 0 ;0,1=474,2=0.000000
L 1.54318307 2.88501654 1.5462498 2.88656614 1 P 0 ;0,1=474,2=0.000000
L 1.5462498 2.88656614 1.54816673 2.88914892 1 P 0 ;0,1=474,2=0.000000
L 1.54816673 2.88914892 1.54893327 2.89276673 1 P 0 ;0,1=474,2=0.000000
L 1.54893327 2.89276673 1.54816673 2.89638268 1 P 0 ;0,1=474,2=0.000000
L 1.54816673 2.89638268 1.54586654 2.89948287 1 P 0 ;0,1=474,2=0.000000
L 1.54586654 2.89948287 1.54241654 2.90103356 1 P 0 ;0,1=474,2=0.000000
L 1.54241654 2.90103356 1.53858337 2.90103356 1 P 0 ;0,1=474,2=0.000000
L 1.53858337 2.90103356 1.53628317 2.90206663 1 P 0 ;0,1=474,2=0.000000
L 1.53628317 2.90206663 1.53436614 2.90464941 1 P 0 ;0,1=474,2=0.000000
L 1.53436614 2.90464941 1.5335997 2.90826624 1 P 0 ;0,1=474,2=0.000000
L 1.5335997 2.90826624 1.5347501 2.91188307 1 P 0 ;0,1=474,2=0.000000
L 1.5347501 2.91188307 1.53743287 2.91446683 1 P 0 ;0,1=474,2=0.000000
L 1.53743287 2.91446683 1.54049961 2.9155 1 P 0 ;0,1=474,2=0.000000
L 1.54049961 2.9155 1.54356634 2.91446683 1 P 0 ;0,1=474,2=0.000000
L 1.54356634 2.91446683 1.5462498 2.91188307 1 P 0 ;0,1=474,2=0.000000
L 1.5462498 2.91188307 1.5474002 2.90826624 1 P 0 ;0,1=474,2=0.000000
L 1.5474002 2.90826624 1.54663307 2.90464941 1 P 0 ;0,1=474,2=0.000000
L 1.54663307 2.90464941 1.54471673 2.90206663 1 P 0 ;0,1=474,2=0.000000
L 1.54471673 2.90206663 1.54241654 2.90103356 1 P 0 ;0,1=474,2=0.000000
L 1.54241654 2.90103356 1.53858337 2.90103356 1 P 0 ;0,1=474,2=0.000000
L 1.53858337 2.90103356 1.53513337 2.89948287 1 P 0 ;0,1=474,2=0.000000
L 1.53513337 2.89948287 1.53283317 2.89638268 1 P 0 ;0,1=474,2=0.000000
L 1.53283317 2.89638268 1.53206663 2.89276673 1 P 0 ;0,1=474,2=0.000000
L 1.53206663 2.89276673 1.53283317 2.88914892 1 P 0 ;0,1=474,2=0.000000
L 1.53283317 2.88914892 1.5347501 2.88656614 1 P 0 ;0,1=474,2=0.000000
L 1.5347501 2.88656614 1.53781683 2.88501654 1 P 0 ;0,1=474,2=0.000000
L 1.53781683 2.88501654 1.54049961 2.8845 1 P 0 ;0,1=474,2=0.000000
L 1.56498287 2.88811585 1.56766634 2.88553307 1 P 0 ;0,1=474,2=0.000000
L 1.56766634 2.88553307 1.57073307 2.8845 1 P 0 ;0,1=474,2=0.000000
L 1.57073307 2.8845 1.5737998 2.88553307 1 P 0 ;0,1=474,2=0.000000
L 1.5737998 2.88553307 1.57648327 2.88863238 1 P 0 ;0,1=474,2=0.000000
L 1.57648327 2.88863238 1.5784002 2.89328327 1 P 0 ;0,1=474,2=0.000000
L 1.5784002 2.89328327 1.57916673 2.89793327 1 P 0 ;0,1=474,2=0.000000
L 1.57916673 2.89793327 1.57916673 2.90361634 1 P 0 ;0,1=474,2=0.000000
L 1.57916673 2.90361634 1.5784002 2.90826624 1 P 0 ;0,1=474,2=0.000000
L 1.5784002 2.90826624 1.57648327 2.9123997 1 P 0 ;0,1=474,2=0.000000
L 1.57648327 2.9123997 1.57418307 2.91446683 1 P 0 ;0,1=474,2=0.000000
L 1.57418307 2.91446683 1.57149961 2.9155 1 P 0 ;0,1=474,2=0.000000
L 1.57149961 2.9155 1.56843287 2.91446683 1 P 0 ;0,1=474,2=0.000000
L 1.56843287 2.91446683 1.56613337 2.9123997 1 P 0 ;0,1=474,2=0.000000
L 1.56613337 2.9123997 1.5645997 2.9093003 1 P 0 ;0,1=474,2=0.000000
L 1.5645997 2.9093003 1.56383317 2.90516594 1 P 0 ;0,1=474,2=0.000000
L 1.56383317 2.90516594 1.5645997 2.9015501 1 P 0 ;0,1=474,2=0.000000
L 1.5645997 2.9015501 1.56651663 2.89793327 1 P 0 ;0,1=474,2=0.000000
L 1.56651663 2.89793327 1.56881683 2.89586604 1 P 0 ;0,1=474,2=0.000000
L 1.56881683 2.89586604 1.57149961 2.89534951 1 P 0 ;0,1=474,2=0.000000
L 1.57149961 2.89534951 1.57456634 2.89638268 1 P 0 ;0,1=474,2=0.000000
L 1.57456634 2.89638268 1.57686654 2.89896634 1 P 0 ;0,1=474,2=0.000000
L 1.57686654 2.89896634 1.57916673 2.90361634 1 P 0 ;0,1=474,2=0.000000
L 5.625 3.893 5.625 3.937 1 P 0 
L 5.625 3.937 5.535 3.937 1 P 0 
L 5.535 3.893 5.625 3.893 1 P 0 
L 5.535 3.937 5.535 3.893 1 P 0 
L 5.63266654 3.8675 5.63266654 3.8925 1 P 0 ;0,1=475,2=0.000000
L 5.63266654 3.8925 5.63933327 3.8925 1 P 0 ;0,1=475,2=0.000000
L 5.63933327 3.8925 5.64146663 3.89124941 1 P 0 ;0,1=475,2=0.000000
L 5.64146663 3.89124941 5.6428001 3.88958317 1 P 0 ;0,1=475,2=0.000000
L 5.6428001 3.88958317 5.64333337 3.8862498 1 P 0 ;0,1=475,2=0.000000
L 5.64333337 3.8862498 5.6428001 3.88291634 1 P 0 ;0,1=475,2=0.000000
L 5.6428001 3.88291634 5.6412 3.88083346 1 P 0 ;0,1=475,2=0.000000
L 5.6412 3.88083346 5.63933327 3.87958297 1 P 0 ;0,1=475,2=0.000000
L 5.63933327 3.87958297 5.63266654 3.87958297 1 P 0 ;0,1=475,2=0.000000
L 5.63933327 3.87958297 5.64333337 3.8675 1 P 0 ;0,1=475,2=0.000000
L 5.6599997 3.8675 5.6599997 3.8925 1 P 0 ;0,1=475,2=0.000000
L 5.6599997 3.8925 5.6567999 3.8875003 1 P 0 ;0,1=475,2=0.000000
L 5.6567999 3.8675 5.66319951 3.8675 1 P 0 ;0,1=475,2=0.000000
L 5.6852 3.8675 5.6852 3.8925 1 P 0 ;0,1=475,2=0.000000
L 5.6852 3.8925 5.67533297 3.87458327 1 P 0 ;0,1=475,2=0.000000
L 5.67533297 3.87458327 5.68866693 3.87458327 1 P 0 ;0,1=475,2=0.000000
L 5.47 0.668 5.47 0.712 1 P 0 
L 5.38 0.668 5.47 0.668 1 P 0 
L 5.47 0.712 5.38 0.712 1 P 0 
L 5.38 0.712 5.38 0.668 1 P 0 
L 5.31583317 0.6145 5.31583317 0.6455 1 P 0 ;0,1=476,2=0.000000
L 5.31583317 0.6455 5.32541654 0.6455 1 P 0 ;0,1=476,2=0.000000
L 5.32541654 0.6455 5.32848327 0.64394931 1 P 0 ;0,1=476,2=0.000000
L 5.32848327 0.64394931 5.3304002 0.64188307 1 P 0 ;0,1=476,2=0.000000
L 5.3304002 0.64188307 5.33116673 0.6377497 1 P 0 ;0,1=476,2=0.000000
L 5.33116673 0.6377497 5.3304002 0.63361634 1 P 0 ;0,1=476,2=0.000000
L 5.3304002 0.63361634 5.3281 0.63103356 1 P 0 ;0,1=476,2=0.000000
L 5.3281 0.63103356 5.32541654 0.62948287 1 P 0 ;0,1=476,2=0.000000
L 5.32541654 0.62948287 5.31583317 0.62948287 1 P 0 ;0,1=476,2=0.000000
L 5.32541654 0.62948287 5.33116673 0.6145 1 P 0 ;0,1=476,2=0.000000
L 5.34721644 0.64033346 5.34951663 0.64343278 1 P 0 ;0,1=476,2=0.000000
L 5.34951663 0.64343278 5.3522001 0.64498337 1 P 0 ;0,1=476,2=0.000000
L 5.3522001 0.64498337 5.35526683 0.6455 1 P 0 ;0,1=476,2=0.000000
L 5.35526683 0.6455 5.3591 0.64446683 1 P 0 ;0,1=476,2=0.000000
L 5.3591 0.64446683 5.36178346 0.64188307 1 P 0 ;0,1=476,2=0.000000
L 5.36178346 0.64188307 5.36255 0.63878376 1 P 0 ;0,1=476,2=0.000000
L 5.36255 0.63878376 5.36216673 0.63568258 1 P 0 ;0,1=476,2=0.000000
L 5.36216673 0.63568258 5.36063307 0.6330998 1 P 0 ;0,1=476,2=0.000000
L 5.36063307 0.6330998 5.35296663 0.62793327 1 P 0 ;0,1=476,2=0.000000
L 5.35296663 0.62793327 5.34951663 0.62431644 1 P 0 ;0,1=476,2=0.000000
L 5.34951663 0.62431644 5.34721644 0.61914892 1 P 0 ;0,1=476,2=0.000000
L 5.34721644 0.61914892 5.3464499 0.6145 1 P 0 ;0,1=476,2=0.000000
L 5.3464499 0.6145 5.36255 0.6145 1 P 0 ;0,1=476,2=0.000000
L 5.37706663 0.62069961 5.37936614 0.61708278 1 P 0 ;0,1=476,2=0.000000
L 5.37936614 0.61708278 5.38243287 0.61501654 1 P 0 ;0,1=476,2=0.000000
L 5.38243287 0.61501654 5.38588356 0.6145 1 P 0 ;0,1=476,2=0.000000
L 5.38588356 0.6145 5.3889503 0.61501654 1 P 0 ;0,1=476,2=0.000000
L 5.3889503 0.61501654 5.39201703 0.61759931 1 P 0 ;0,1=476,2=0.000000
L 5.39201703 0.61759931 5.39393327 0.62069961 1 P 0 ;0,1=476,2=0.000000
L 5.39393327 0.62069961 5.39431654 0.6237999 1 P 0 ;0,1=476,2=0.000000
L 5.39431654 0.6237999 5.39355 0.62741575 1 P 0 ;0,1=476,2=0.000000
L 5.39355 0.62741575 5.39086654 0.62999951 1 P 0 ;0,1=476,2=0.000000
L 5.39086654 0.62999951 5.38818307 0.63103356 1 P 0 ;0,1=476,2=0.000000
L 5.38818307 0.63103356 5.38473307 0.63103356 1 P 0 ;0,1=476,2=0.000000
L 5.38818307 0.63103356 5.39048327 0.63258317 1 P 0 ;0,1=476,2=0.000000
L 5.39048327 0.63258317 5.3924002 0.63516594 1 P 0 ;0,1=476,2=0.000000
L 5.3924002 0.63516594 5.39316673 0.63826624 1 P 0 ;0,1=476,2=0.000000
L 5.39316673 0.63826624 5.3924002 0.64136654 1 P 0 ;0,1=476,2=0.000000
L 5.3924002 0.64136654 5.39048327 0.64394931 1 P 0 ;0,1=476,2=0.000000
L 5.39048327 0.64394931 5.38703327 0.6455 1 P 0 ;0,1=476,2=0.000000
L 5.38703327 0.6455 5.38358337 0.64498337 1 P 0 ;0,1=476,2=0.000000
L 5.38358337 0.64498337 5.38013337 0.64291624 1 P 0 ;0,1=476,2=0.000000
L 5.41649961 0.6145 5.41649961 0.6455 1 P 0 ;0,1=476,2=0.000000
L 5.41649961 0.6455 5.4118999 0.6393003 1 P 0 ;0,1=476,2=0.000000
L 5.4118999 0.6145 5.42109931 0.6145 1 P 0 ;0,1=476,2=0.000000
L 5.797 0.73 5.797 0.82 1 P 0 
L 5.797 0.82 5.753 0.82 1 P 0 
L 5.753 0.82 5.753 0.73 1 P 0 
L 5.753 0.73 5.797 0.73 1 P 0 
L 5.82583317 0.6345 5.82583317 0.6655 1 P 0 ;0,1=477,2=0.000000
L 5.82583317 0.6655 5.83541654 0.6655 1 P 0 ;0,1=477,2=0.000000
L 5.83541654 0.6655 5.83848327 0.66394931 1 P 0 ;0,1=477,2=0.000000
L 5.83848327 0.66394931 5.8404002 0.66188307 1 P 0 ;0,1=477,2=0.000000
L 5.8404002 0.66188307 5.84116673 0.6577497 1 P 0 ;0,1=477,2=0.000000
L 5.84116673 0.6577497 5.8404002 0.65361634 1 P 0 ;0,1=477,2=0.000000
L 5.8404002 0.65361634 5.8381 0.65103356 1 P 0 ;0,1=477,2=0.000000
L 5.8381 0.65103356 5.83541654 0.64948287 1 P 0 ;0,1=477,2=0.000000
L 5.83541654 0.64948287 5.82583317 0.64948287 1 P 0 ;0,1=477,2=0.000000
L 5.83541654 0.64948287 5.84116673 0.6345 1 P 0 ;0,1=477,2=0.000000
L 5.85721644 0.66033346 5.85951663 0.66343278 1 P 0 ;0,1=477,2=0.000000
L 5.85951663 0.66343278 5.8622001 0.66498337 1 P 0 ;0,1=477,2=0.000000
L 5.8622001 0.66498337 5.86526683 0.6655 1 P 0 ;0,1=477,2=0.000000
L 5.86526683 0.6655 5.8691 0.66446683 1 P 0 ;0,1=477,2=0.000000
L 5.8691 0.66446683 5.87178346 0.66188307 1 P 0 ;0,1=477,2=0.000000
L 5.87178346 0.66188307 5.87255 0.65878376 1 P 0 ;0,1=477,2=0.000000
L 5.87255 0.65878376 5.87216673 0.65568258 1 P 0 ;0,1=477,2=0.000000
L 5.87216673 0.65568258 5.87063307 0.6530998 1 P 0 ;0,1=477,2=0.000000
L 5.87063307 0.6530998 5.86296663 0.64793327 1 P 0 ;0,1=477,2=0.000000
L 5.86296663 0.64793327 5.85951663 0.64431644 1 P 0 ;0,1=477,2=0.000000
L 5.85951663 0.64431644 5.85721644 0.63914892 1 P 0 ;0,1=477,2=0.000000
L 5.85721644 0.63914892 5.8564499 0.6345 1 P 0 ;0,1=477,2=0.000000
L 5.8564499 0.6345 5.87255 0.6345 1 P 0 ;0,1=477,2=0.000000
L 5.88821644 0.66033346 5.89051663 0.66343278 1 P 0 ;0,1=477,2=0.000000
L 5.89051663 0.66343278 5.8932001 0.66498337 1 P 0 ;0,1=477,2=0.000000
L 5.8932001 0.66498337 5.89626683 0.6655 1 P 0 ;0,1=477,2=0.000000
L 5.89626683 0.6655 5.9001 0.66446683 1 P 0 ;0,1=477,2=0.000000
L 5.9001 0.66446683 5.90278346 0.66188307 1 P 0 ;0,1=477,2=0.000000
L 5.90278346 0.66188307 5.90355 0.65878376 1 P 0 ;0,1=477,2=0.000000
L 5.90355 0.65878376 5.90316673 0.65568258 1 P 0 ;0,1=477,2=0.000000
L 5.90316673 0.65568258 5.90163307 0.6530998 1 P 0 ;0,1=477,2=0.000000
L 5.90163307 0.6530998 5.89396663 0.64793327 1 P 0 ;0,1=477,2=0.000000
L 5.89396663 0.64793327 5.89051663 0.64431644 1 P 0 ;0,1=477,2=0.000000
L 5.89051663 0.64431644 5.88821644 0.63914892 1 P 0 ;0,1=477,2=0.000000
L 5.88821644 0.63914892 5.8874499 0.6345 1 P 0 ;0,1=477,2=0.000000
L 5.8874499 0.6345 5.90355 0.6345 1 P 0 ;0,1=477,2=0.000000
L 5.92649961 0.6345 5.92918307 0.63501654 1 P 0 ;0,1=477,2=0.000000
L 5.92918307 0.63501654 5.9322498 0.63656614 1 P 0 ;0,1=477,2=0.000000
L 5.9322498 0.63656614 5.93416673 0.63914892 1 P 0 ;0,1=477,2=0.000000
L 5.93416673 0.63914892 5.93493327 0.64276673 1 P 0 ;0,1=477,2=0.000000
L 5.93493327 0.64276673 5.93416673 0.64638268 1 P 0 ;0,1=477,2=0.000000
L 5.93416673 0.64638268 5.93186654 0.64948287 1 P 0 ;0,1=477,2=0.000000
L 5.93186654 0.64948287 5.92841654 0.65103356 1 P 0 ;0,1=477,2=0.000000
L 5.92841654 0.65103356 5.92458337 0.65103356 1 P 0 ;0,1=477,2=0.000000
L 5.92458337 0.65103356 5.92228317 0.65206663 1 P 0 ;0,1=477,2=0.000000
L 5.92228317 0.65206663 5.92036614 0.65464941 1 P 0 ;0,1=477,2=0.000000
L 5.92036614 0.65464941 5.9195997 0.65826624 1 P 0 ;0,1=477,2=0.000000
L 5.9195997 0.65826624 5.9207501 0.66188307 1 P 0 ;0,1=477,2=0.000000
L 5.9207501 0.66188307 5.92343287 0.66446683 1 P 0 ;0,1=477,2=0.000000
L 5.92343287 0.66446683 5.92649961 0.6655 1 P 0 ;0,1=477,2=0.000000
L 5.92649961 0.6655 5.92956634 0.66446683 1 P 0 ;0,1=477,2=0.000000
L 5.92956634 0.66446683 5.9322498 0.66188307 1 P 0 ;0,1=477,2=0.000000
L 5.9322498 0.66188307 5.9334002 0.65826624 1 P 0 ;0,1=477,2=0.000000
L 5.9334002 0.65826624 5.93263307 0.65464941 1 P 0 ;0,1=477,2=0.000000
L 5.93263307 0.65464941 5.93071673 0.65206663 1 P 0 ;0,1=477,2=0.000000
L 5.93071673 0.65206663 5.92841654 0.65103356 1 P 0 ;0,1=477,2=0.000000
L 5.92841654 0.65103356 5.92458337 0.65103356 1 P 0 ;0,1=477,2=0.000000
L 5.92458337 0.65103356 5.92113337 0.64948287 1 P 0 ;0,1=477,2=0.000000
L 5.92113337 0.64948287 5.91883317 0.64638268 1 P 0 ;0,1=477,2=0.000000
L 5.91883317 0.64638268 5.91806663 0.64276673 1 P 0 ;0,1=477,2=0.000000
L 5.91806663 0.64276673 5.91883317 0.63914892 1 P 0 ;0,1=477,2=0.000000
L 5.91883317 0.63914892 5.9207501 0.63656614 1 P 0 ;0,1=477,2=0.000000
L 5.9207501 0.63656614 5.92381683 0.63501654 1 P 0 ;0,1=477,2=0.000000
L 5.92381683 0.63501654 5.92649961 0.6345 1 P 0 ;0,1=477,2=0.000000
L 3.882 2.753 3.882 2.797 1 P 0 
L 3.792 2.753 3.882 2.753 1 P 0 
L 3.882 2.797 3.792 2.797 1 P 0 
L 3.792 2.797 3.792 2.753 1 P 0 
L 2.67583317 3.4995 2.67583317 3.5305 1 P 0 ;0,1=478,2=0.000000
L 2.67583317 3.5305 2.68541654 3.5305 1 P 0 ;0,1=478,2=0.000000
L 2.68541654 3.5305 2.68848327 3.52894931 1 P 0 ;0,1=478,2=0.000000
L 2.68848327 3.52894931 2.6904002 3.52688307 1 P 0 ;0,1=478,2=0.000000
L 2.6904002 3.52688307 2.69116673 3.5227497 1 P 0 ;0,1=478,2=0.000000
L 2.69116673 3.5227497 2.6904002 3.51861634 1 P 0 ;0,1=478,2=0.000000
L 2.6904002 3.51861634 2.6881 3.51603356 1 P 0 ;0,1=478,2=0.000000
L 2.6881 3.51603356 2.68541654 3.51448287 1 P 0 ;0,1=478,2=0.000000
L 2.68541654 3.51448287 2.67583317 3.51448287 1 P 0 ;0,1=478,2=0.000000
L 2.68541654 3.51448287 2.69116673 3.4995 1 P 0 ;0,1=478,2=0.000000
L 2.71449961 3.4995 2.71449961 3.5305 1 P 0 ;0,1=478,2=0.000000
L 2.71449961 3.5305 2.7098999 3.5243003 1 P 0 ;0,1=478,2=0.000000
L 2.7098999 3.4995 2.71909931 3.4995 1 P 0 ;0,1=478,2=0.000000
L 2.74549961 3.4995 2.74818307 3.50001654 1 P 0 ;0,1=478,2=0.000000
L 2.74818307 3.50001654 2.7512498 3.50156614 1 P 0 ;0,1=478,2=0.000000
L 2.7512498 3.50156614 2.75316673 3.50414892 1 P 0 ;0,1=478,2=0.000000
L 2.75316673 3.50414892 2.75393327 3.50776673 1 P 0 ;0,1=478,2=0.000000
L 2.75393327 3.50776673 2.75316673 3.51138268 1 P 0 ;0,1=478,2=0.000000
L 2.75316673 3.51138268 2.75086654 3.51448287 1 P 0 ;0,1=478,2=0.000000
L 2.75086654 3.51448287 2.74741654 3.51603356 1 P 0 ;0,1=478,2=0.000000
L 2.74741654 3.51603356 2.74358337 3.51603356 1 P 0 ;0,1=478,2=0.000000
L 2.74358337 3.51603356 2.74128317 3.51706663 1 P 0 ;0,1=478,2=0.000000
L 2.74128317 3.51706663 2.73936614 3.51964941 1 P 0 ;0,1=478,2=0.000000
L 2.73936614 3.51964941 2.7385997 3.52326624 1 P 0 ;0,1=478,2=0.000000
L 2.7385997 3.52326624 2.7397501 3.52688307 1 P 0 ;0,1=478,2=0.000000
L 2.7397501 3.52688307 2.74243287 3.52946683 1 P 0 ;0,1=478,2=0.000000
L 2.74243287 3.52946683 2.74549961 3.5305 1 P 0 ;0,1=478,2=0.000000
L 2.74549961 3.5305 2.74856634 3.52946683 1 P 0 ;0,1=478,2=0.000000
L 2.74856634 3.52946683 2.7512498 3.52688307 1 P 0 ;0,1=478,2=0.000000
L 2.7512498 3.52688307 2.7524002 3.52326624 1 P 0 ;0,1=478,2=0.000000
L 2.7524002 3.52326624 2.75163307 3.51964941 1 P 0 ;0,1=478,2=0.000000
L 2.75163307 3.51964941 2.74971673 3.51706663 1 P 0 ;0,1=478,2=0.000000
L 2.74971673 3.51706663 2.74741654 3.51603356 1 P 0 ;0,1=478,2=0.000000
L 2.74741654 3.51603356 2.74358337 3.51603356 1 P 0 ;0,1=478,2=0.000000
L 2.74358337 3.51603356 2.74013337 3.51448287 1 P 0 ;0,1=478,2=0.000000
L 2.74013337 3.51448287 2.73783317 3.51138268 1 P 0 ;0,1=478,2=0.000000
L 2.73783317 3.51138268 2.73706663 3.50776673 1 P 0 ;0,1=478,2=0.000000
L 2.73706663 3.50776673 2.73783317 3.50414892 1 P 0 ;0,1=478,2=0.000000
L 2.73783317 3.50414892 2.7397501 3.50156614 1 P 0 ;0,1=478,2=0.000000
L 2.7397501 3.50156614 2.74281683 3.50001654 1 P 0 ;0,1=478,2=0.000000
L 2.74281683 3.50001654 2.74549961 3.4995 1 P 0 ;0,1=478,2=0.000000
L 2.76806663 3.50414892 2.77036614 3.50156614 1 P 0 ;0,1=478,2=0.000000
L 2.77036614 3.50156614 2.77304961 3.50001654 1 P 0 ;0,1=478,2=0.000000
L 2.77304961 3.50001654 2.77649961 3.4995 1 P 0 ;0,1=478,2=0.000000
L 2.77649961 3.4995 2.7799503 3.50053307 1 P 0 ;0,1=478,2=0.000000
L 2.7799503 3.50053307 2.78263307 3.50259931 1 P 0 ;0,1=478,2=0.000000
L 2.78263307 3.50259931 2.78455 3.50621614 1 P 0 ;0,1=478,2=0.000000
L 2.78455 3.50621614 2.78493327 3.51034951 1 P 0 ;0,1=478,2=0.000000
L 2.78493327 3.51034951 2.78416673 3.51448287 1 P 0 ;0,1=478,2=0.000000
L 2.78416673 3.51448287 2.7822498 3.51706663 1 P 0 ;0,1=478,2=0.000000
L 2.7822498 3.51706663 2.77956634 3.51913287 1 P 0 ;0,1=478,2=0.000000
L 2.77956634 3.51913287 2.77688356 3.51964941 1 P 0 ;0,1=478,2=0.000000
L 2.77688356 3.51964941 2.7742001 3.51913287 1 P 0 ;0,1=478,2=0.000000
L 2.7742001 3.51913287 2.7707501 3.51706663 1 P 0 ;0,1=478,2=0.000000
L 2.7707501 3.51706663 2.7718999 3.5305 1 P 0 ;0,1=478,2=0.000000
L 2.7718999 3.5305 2.7822498 3.5305 1 P 0 ;0,1=478,2=0.000000
L 4.982 2.57 4.982 2.66 1 P 0 
L 4.982 2.66 4.938 2.66 1 P 0 
L 4.938 2.66 4.938 2.57 1 P 0 
L 4.938 2.57 4.982 2.57 1 P 0 
L 4.91083317 2.8145 4.91083317 2.8455 1 P 0 ;0,1=479,2=0.000000
L 4.91083317 2.8455 4.92041654 2.8455 1 P 0 ;0,1=479,2=0.000000
L 4.92041654 2.8455 4.92348327 2.84394931 1 P 0 ;0,1=479,2=0.000000
L 4.92348327 2.84394931 4.9254002 2.84188307 1 P 0 ;0,1=479,2=0.000000
L 4.9254002 2.84188307 4.92616673 2.8377497 1 P 0 ;0,1=479,2=0.000000
L 4.92616673 2.8377497 4.9254002 2.83361634 1 P 0 ;0,1=479,2=0.000000
L 4.9254002 2.83361634 4.9231 2.83103356 1 P 0 ;0,1=479,2=0.000000
L 4.9231 2.83103356 4.92041654 2.82948287 1 P 0 ;0,1=479,2=0.000000
L 4.92041654 2.82948287 4.91083317 2.82948287 1 P 0 ;0,1=479,2=0.000000
L 4.92041654 2.82948287 4.92616673 2.8145 1 P 0 ;0,1=479,2=0.000000
L 4.94949961 2.8145 4.94949961 2.8455 1 P 0 ;0,1=479,2=0.000000
L 4.94949961 2.8455 4.9448999 2.8393003 1 P 0 ;0,1=479,2=0.000000
L 4.9448999 2.8145 4.95409931 2.8145 1 P 0 ;0,1=479,2=0.000000
L 4.97321644 2.82741575 4.9758999 2.83103356 1 P 0 ;0,1=479,2=0.000000
L 4.9758999 2.83103356 4.9782001 2.8330998 1 P 0 ;0,1=479,2=0.000000
L 4.9782001 2.8330998 4.98126683 2.83413287 1 P 0 ;0,1=479,2=0.000000
L 4.98126683 2.83413287 4.9839503 2.8330998 1 P 0 ;0,1=479,2=0.000000
L 4.9839503 2.8330998 4.98586654 2.83103356 1 P 0 ;0,1=479,2=0.000000
L 4.98586654 2.83103356 4.9874002 2.82793327 1 P 0 ;0,1=479,2=0.000000
L 4.9874002 2.82793327 4.98778346 2.82431644 1 P 0 ;0,1=479,2=0.000000
L 4.98778346 2.82431644 4.9874002 2.82121614 1 P 0 ;0,1=479,2=0.000000
L 4.9874002 2.82121614 4.98586654 2.81811585 1 P 0 ;0,1=479,2=0.000000
L 4.98586654 2.81811585 4.98356634 2.81553307 1 P 0 ;0,1=479,2=0.000000
L 4.98356634 2.81553307 4.98088356 2.8145 1 P 0 ;0,1=479,2=0.000000
L 4.98088356 2.8145 4.97781683 2.81553307 1 P 0 ;0,1=479,2=0.000000
L 4.97781683 2.81553307 4.97513337 2.81863238 1 P 0 ;0,1=479,2=0.000000
L 4.97513337 2.81863238 4.9735997 2.82328327 1 P 0 ;0,1=479,2=0.000000
L 4.9735997 2.82328327 4.97321644 2.8284498 1 P 0 ;0,1=479,2=0.000000
L 4.97321644 2.8284498 4.97398287 2.83516594 1 P 0 ;0,1=479,2=0.000000
L 4.97398287 2.83516594 4.97513337 2.83878376 1 P 0 ;0,1=479,2=0.000000
L 4.97513337 2.83878376 4.97704961 2.8423997 1 P 0 ;0,1=479,2=0.000000
L 4.97704961 2.8423997 4.97973307 2.84498337 1 P 0 ;0,1=479,2=0.000000
L 4.97973307 2.84498337 4.98241654 2.8455 1 P 0 ;0,1=479,2=0.000000
L 4.98241654 2.8455 4.9851 2.84446683 1 P 0 ;0,1=479,2=0.000000
L 4.9851 2.84446683 4.98701703 2.84188307 1 P 0 ;0,1=479,2=0.000000
L 5.00421644 2.82741575 5.0068999 2.83103356 1 P 0 ;0,1=479,2=0.000000
L 5.0068999 2.83103356 5.0092001 2.8330998 1 P 0 ;0,1=479,2=0.000000
L 5.0092001 2.8330998 5.01226683 2.83413287 1 P 0 ;0,1=479,2=0.000000
L 5.01226683 2.83413287 5.0149503 2.8330998 1 P 0 ;0,1=479,2=0.000000
L 5.0149503 2.8330998 5.01686654 2.83103356 1 P 0 ;0,1=479,2=0.000000
L 5.01686654 2.83103356 5.0184002 2.82793327 1 P 0 ;0,1=479,2=0.000000
L 5.0184002 2.82793327 5.01878346 2.82431644 1 P 0 ;0,1=479,2=0.000000
L 5.01878346 2.82431644 5.0184002 2.82121614 1 P 0 ;0,1=479,2=0.000000
L 5.0184002 2.82121614 5.01686654 2.81811585 1 P 0 ;0,1=479,2=0.000000
L 5.01686654 2.81811585 5.01456634 2.81553307 1 P 0 ;0,1=479,2=0.000000
L 5.01456634 2.81553307 5.01188356 2.8145 1 P 0 ;0,1=479,2=0.000000
L 5.01188356 2.8145 5.00881683 2.81553307 1 P 0 ;0,1=479,2=0.000000
L 5.00881683 2.81553307 5.00613337 2.81863238 1 P 0 ;0,1=479,2=0.000000
L 5.00613337 2.81863238 5.0045997 2.82328327 1 P 0 ;0,1=479,2=0.000000
L 5.0045997 2.82328327 5.00421644 2.8284498 1 P 0 ;0,1=479,2=0.000000
L 5.00421644 2.8284498 5.00498287 2.83516594 1 P 0 ;0,1=479,2=0.000000
L 5.00498287 2.83516594 5.00613337 2.83878376 1 P 0 ;0,1=479,2=0.000000
L 5.00613337 2.83878376 5.00804961 2.8423997 1 P 0 ;0,1=479,2=0.000000
L 5.00804961 2.8423997 5.01073307 2.84498337 1 P 0 ;0,1=479,2=0.000000
L 5.01073307 2.84498337 5.01341654 2.8455 1 P 0 ;0,1=479,2=0.000000
L 5.01341654 2.8455 5.0161 2.84446683 1 P 0 ;0,1=479,2=0.000000
L 5.0161 2.84446683 5.01801703 2.84188307 1 P 0 ;0,1=479,2=0.000000
L 5.3 2.677 5.256 2.677 1 P 0 
L 5.3 2.587 5.3 2.677 1 P 0 
L 5.256 2.677 5.256 2.587 1 P 0 
L 5.256 2.587 5.3 2.587 1 P 0 
L 5.3155 2.38583317 5.2845 2.38583317 1 P 0 ;0,1=480,2=270.000000
L 5.2845 2.38583317 5.2845 2.39541654 1 P 0 ;0,1=480,2=270.000000
L 5.2845 2.39541654 5.28605069 2.39848327 1 P 0 ;0,1=480,2=270.000000
L 5.28605069 2.39848327 5.28811693 2.4004002 1 P 0 ;0,1=480,2=270.000000
L 5.28811693 2.4004002 5.2922503 2.40116673 1 P 0 ;0,1=480,2=270.000000
L 5.2922503 2.40116673 5.29638366 2.4004002 1 P 0 ;0,1=480,2=270.000000
L 5.29638366 2.4004002 5.29896644 2.3981 1 P 0 ;0,1=480,2=270.000000
L 5.29896644 2.3981 5.30051713 2.39541654 1 P 0 ;0,1=480,2=270.000000
L 5.30051713 2.39541654 5.30051713 2.38583317 1 P 0 ;0,1=480,2=270.000000
L 5.30051713 2.39541654 5.3155 2.40116673 1 P 0 ;0,1=480,2=270.000000
L 5.3155 2.42449961 5.2845 2.42449961 1 P 0 ;0,1=480,2=270.000000
L 5.2845 2.42449961 5.2906997 2.4198999 1 P 0 ;0,1=480,2=270.000000
L 5.3155 2.4198999 5.3155 2.42909931 1 P 0 ;0,1=480,2=270.000000
L 5.3155 2.45549961 5.31498346 2.45818307 1 P 0 ;0,1=480,2=270.000000
L 5.31498346 2.45818307 5.31343386 2.4612498 1 P 0 ;0,1=480,2=270.000000
L 5.31343386 2.4612498 5.31085108 2.46316673 1 P 0 ;0,1=480,2=270.000000
L 5.31085108 2.46316673 5.30723327 2.46393327 1 P 0 ;0,1=480,2=270.000000
L 5.30723327 2.46393327 5.30361732 2.46316673 1 P 0 ;0,1=480,2=270.000000
L 5.30361732 2.46316673 5.30051713 2.46086654 1 P 0 ;0,1=480,2=270.000000
L 5.30051713 2.46086654 5.29896644 2.45741654 1 P 0 ;0,1=480,2=270.000000
L 5.29896644 2.45741654 5.29896644 2.45358337 1 P 0 ;0,1=480,2=270.000000
L 5.29896644 2.45358337 5.29793337 2.45128317 1 P 0 ;0,1=480,2=270.000000
L 5.29793337 2.45128317 5.29535059 2.44936614 1 P 0 ;0,1=480,2=270.000000
L 5.29535059 2.44936614 5.29173376 2.4485997 1 P 0 ;0,1=480,2=270.000000
L 5.29173376 2.4485997 5.28811693 2.4497501 1 P 0 ;0,1=480,2=270.000000
L 5.28811693 2.4497501 5.28553317 2.45243287 1 P 0 ;0,1=480,2=270.000000
L 5.28553317 2.45243287 5.2845 2.45549961 1 P 0 ;0,1=480,2=270.000000
L 5.2845 2.45549961 5.28553317 2.45856634 1 P 0 ;0,1=480,2=270.000000
L 5.28553317 2.45856634 5.28811693 2.4612498 1 P 0 ;0,1=480,2=270.000000
L 5.28811693 2.4612498 5.29173376 2.4624002 1 P 0 ;0,1=480,2=270.000000
L 5.29173376 2.4624002 5.29535059 2.46163307 1 P 0 ;0,1=480,2=270.000000
L 5.29535059 2.46163307 5.29793337 2.45971673 1 P 0 ;0,1=480,2=270.000000
L 5.29793337 2.45971673 5.29896644 2.45741654 1 P 0 ;0,1=480,2=270.000000
L 5.29896644 2.45741654 5.29896644 2.45358337 1 P 0 ;0,1=480,2=270.000000
L 5.29896644 2.45358337 5.30051713 2.45013337 1 P 0 ;0,1=480,2=270.000000
L 5.30051713 2.45013337 5.30361732 2.44783317 1 P 0 ;0,1=480,2=270.000000
L 5.30361732 2.44783317 5.30723327 2.44706663 1 P 0 ;0,1=480,2=270.000000
L 5.30723327 2.44706663 5.31085108 2.44783317 1 P 0 ;0,1=480,2=270.000000
L 5.31085108 2.44783317 5.31343386 2.4497501 1 P 0 ;0,1=480,2=270.000000
L 5.31343386 2.4497501 5.31498346 2.45281683 1 P 0 ;0,1=480,2=270.000000
L 5.31498346 2.45281683 5.3155 2.45549961 1 P 0 ;0,1=480,2=270.000000
L 5.3155 2.48573307 5.30878386 2.48649961 1 P 0 ;0,1=480,2=270.000000
L 5.30878386 2.48649961 5.30310079 2.4876501 1 P 0 ;0,1=480,2=270.000000
L 5.30310079 2.4876501 5.29793337 2.48918307 1 P 0 ;0,1=480,2=270.000000
L 5.29793337 2.48918307 5.2922503 2.4911 1 P 0 ;0,1=480,2=270.000000
L 5.2922503 2.4911 5.2845 2.49416673 1 P 0 ;0,1=480,2=270.000000
L 5.2845 2.49416673 5.2845 2.47883317 1 P 0 ;0,1=480,2=270.000000
L 6.11598002 4.16328996 6.17141998 4.16328996 1 P 0 
L 6.17141998 4.16328996 6.17141998 4.05325 1 P 0 
L 6.17141998 4.05325 6.11598002 4.05325 1 P 0 
L 6.11598002 4.05325 6.11598002 4.16328996 1 P 0 
L 6.0857 4.14526998 6.0857 4.19526998 1 P 0 
L 6.1107 4.17026998 6.0607 4.17026998 1 P 0 
S P 0
OB 6.115980019685 4.05325 I
OS 6.171419980315 4.05325
OS 6.171419980315 4.03325
OS 6.115980019685 4.03325
OS 6.115980019685 4.05325
OE
SE
L 6.18333297 4.1325 6.1899997 4.1575 1 P 0 ;0,1=1,2=0.000000
L 6.1899997 4.1575 6.19666693 4.1325 1 P 0 ;0,1=1,2=0.000000
L 6.19426644 4.14124961 6.18573297 4.14124961 1 P 0 ;0,1=1,2=0.000000
L 6.19086663 4.02541634 6.18926644 4.02666683 1 P 0 ;0,1=22,2=0.000000
L 6.18926644 4.02666683 6.1874002 4.0275 1 P 0 ;0,1=22,2=0.000000
L 6.1874002 4.0275 6.18526683 4.0275 1 P 0 ;0,1=22,2=0.000000
L 6.18526683 4.0275 6.18286634 4.02624941 1 P 0 ;0,1=22,2=0.000000
L 6.18286634 4.02624941 6.1810001 4.02416654 1 P 0 ;0,1=22,2=0.000000
L 6.1810001 4.02416654 6.17966654 4.02166634 1 P 0 ;0,1=22,2=0.000000
L 6.17966654 4.02166634 6.17859961 4.0174998 1 P 0 ;0,1=22,2=0.000000
L 6.17859961 4.0174998 6.17833297 4.0137498 1 P 0 ;0,1=22,2=0.000000
L 6.17833297 4.0137498 6.17886673 4.0099999 1 P 0 ;0,1=22,2=0.000000
L 6.17886673 4.0099999 6.17966654 4.00749961 1 P 0 ;0,1=22,2=0.000000
L 6.17966654 4.00749961 6.18126663 4.00499941 1 P 0 ;0,1=22,2=0.000000
L 6.18126663 4.00499941 6.18313346 4.00333307 1 P 0 ;0,1=22,2=0.000000
L 6.18313346 4.00333307 6.1849997 4.0025 1 P 0 ;0,1=22,2=0.000000
L 6.1849997 4.0025 6.18686644 4.0025 1 P 0 ;0,1=22,2=0.000000
L 6.18686644 4.0025 6.18873327 4.00333307 1 P 0 ;0,1=22,2=0.000000
L 6.18873327 4.00333307 6.19033337 4.00458287 1 P 0 ;0,1=22,2=0.000000
L 6.19033337 4.00458287 6.19166693 4.00624911 1 P 0 ;0,1=22,2=0.000000
L 6.2455 4.03006663 6.2145 4.03006663 1 P 0 ;0,1=481,2=270.000000
L 6.2145 4.03006663 6.2145 4.03773307 1 P 0 ;0,1=481,2=270.000000
L 6.2145 4.03773307 6.21605069 4.0407998 1 P 0 ;0,1=481,2=270.000000
L 6.21605069 4.0407998 6.21811693 4.0431 1 P 0 ;0,1=481,2=270.000000
L 6.21811693 4.0431 6.22121624 4.04501703 1 P 0 ;0,1=481,2=270.000000
L 6.22121624 4.04501703 6.22483406 4.04655 1 P 0 ;0,1=481,2=270.000000
L 6.22483406 4.04655 6.23000049 4.04693327 1 P 0 ;0,1=481,2=270.000000
L 6.23000049 4.04693327 6.23516703 4.04655 1 P 0 ;0,1=481,2=270.000000
L 6.23516703 4.04655 6.23878386 4.04501703 1 P 0 ;0,1=481,2=270.000000
L 6.23878386 4.04501703 6.24188415 4.0431 1 P 0 ;0,1=481,2=270.000000
L 6.24188415 4.0431 6.24395039 4.0407998 1 P 0 ;0,1=481,2=270.000000
L 6.24395039 4.0407998 6.2455 4.03773307 1 P 0 ;0,1=481,2=270.000000
L 6.2455 4.03773307 6.2455 4.03006663 1 P 0 ;0,1=481,2=270.000000
L 6.24136762 4.0614499 6.24395039 4.06451663 1 P 0 ;0,1=481,2=270.000000
L 6.24395039 4.06451663 6.2455 4.06796663 1 P 0 ;0,1=481,2=270.000000
L 6.2455 4.06796663 6.2455 4.07103327 1 P 0 ;0,1=481,2=270.000000
L 6.2455 4.07103327 6.24395039 4.0741 1 P 0 ;0,1=481,2=270.000000
L 6.24395039 4.0741 6.24136762 4.0764002 1 P 0 ;0,1=481,2=270.000000
L 6.24136762 4.0764002 6.2377498 4.07755 1 P 0 ;0,1=481,2=270.000000
L 6.2377498 4.07755 6.23413396 4.07678346 1 P 0 ;0,1=481,2=270.000000
L 6.23413396 4.07678346 6.23103366 4.07486654 1 P 0 ;0,1=481,2=270.000000
L 6.23103366 4.07486654 6.22896644 4.07141654 1 P 0 ;0,1=481,2=270.000000
L 6.22896644 4.07141654 6.22793337 4.06681683 1 P 0 ;0,1=481,2=270.000000
L 6.22793337 4.06681683 6.22586713 4.06413337 1 P 0 ;0,1=481,2=270.000000
L 6.22586713 4.06413337 6.2222503 4.06298287 1 P 0 ;0,1=481,2=270.000000
L 6.2222503 4.06298287 6.21863346 4.0637501 1 P 0 ;0,1=481,2=270.000000
L 6.21863346 4.0637501 6.21605069 4.06566634 1 P 0 ;0,1=481,2=270.000000
L 6.21605069 4.06566634 6.2145 4.0683498 1 P 0 ;0,1=481,2=270.000000
L 6.2145 4.0683498 6.2145 4.07103327 1 P 0 ;0,1=481,2=270.000000
L 6.2145 4.07103327 6.21553317 4.07371673 1 P 0 ;0,1=481,2=270.000000
L 6.21553317 4.07371673 6.21811693 4.07601703 1 P 0 ;0,1=481,2=270.000000
L 6.2455 4.10049961 6.2145 4.10049961 1 P 0 ;0,1=481,2=270.000000
L 6.2145 4.10049961 6.2206997 4.0958999 1 P 0 ;0,1=481,2=270.000000
L 6.2455 4.0958999 6.2455 4.10509931 1 P 0 ;0,1=481,2=270.000000
L 6.21966654 4.12421644 6.21656722 4.12651663 1 P 0 ;0,1=481,2=270.000000
L 6.21656722 4.12651663 6.21501663 4.1292001 1 P 0 ;0,1=481,2=270.000000
L 6.21501663 4.1292001 6.2145 4.13226683 1 P 0 ;0,1=481,2=270.000000
L 6.2145 4.13226683 6.21553317 4.1361 1 P 0 ;0,1=481,2=270.000000
L 6.21553317 4.1361 6.21811693 4.13878346 1 P 0 ;0,1=481,2=270.000000
L 6.21811693 4.13878346 6.22121624 4.13955 1 P 0 ;0,1=481,2=270.000000
L 6.22121624 4.13955 6.22431742 4.13916673 1 P 0 ;0,1=481,2=270.000000
L 6.22431742 4.13916673 6.2269002 4.13763307 1 P 0 ;0,1=481,2=270.000000
L 6.2269002 4.13763307 6.23206673 4.12996663 1 P 0 ;0,1=481,2=270.000000
L 6.23206673 4.12996663 6.23568356 4.12651663 1 P 0 ;0,1=481,2=270.000000
L 6.23568356 4.12651663 6.24085108 4.12421644 1 P 0 ;0,1=481,2=270.000000
L 6.24085108 4.12421644 6.2455 4.1234499 1 P 0 ;0,1=481,2=270.000000
L 6.2455 4.1234499 6.2455 4.13955 1 P 0 ;0,1=481,2=270.000000
L 5.99786998 4.16328996 6.05331004 4.16328996 1 P 0 
L 5.95758996 4.15526998 5.95758996 4.20526998 1 P 0 
L 5.98258996 4.18026998 5.93258996 4.18026998 1 P 0 
L 6.05331004 4.16328996 6.05331004 4.05325 1 P 0 
L 6.05331004 4.05325 5.99786998 4.05325 1 P 0 
L 5.99786998 4.05325 5.99786998 4.16328996 1 P 0 
S P 0
OB 5.997869980315 4.05325 I
OS 6.05331003937 4.05325
OS 6.05331003937 4.03325
OS 5.997869980315 4.03325
OS 5.997869980315 4.05325
OE
SE
L 6.06833297 4.1375 6.0749997 4.1625 1 P 0 ;0,1=1,2=0.000000
L 6.0749997 4.1625 6.08166693 4.1375 1 P 0 ;0,1=1,2=0.000000
L 6.07926644 4.14624961 6.07073297 4.14624961 1 P 0 ;0,1=1,2=0.000000
L 6.02086663 4.02041634 6.01926644 4.02166683 1 P 0 ;0,1=22,2=0.000000
L 6.01926644 4.02166683 6.0174002 4.0225 1 P 0 ;0,1=22,2=0.000000
L 6.0174002 4.0225 6.01526683 4.0225 1 P 0 ;0,1=22,2=0.000000
L 6.01526683 4.0225 6.01286634 4.02124941 1 P 0 ;0,1=22,2=0.000000
L 6.01286634 4.02124941 6.0110001 4.01916654 1 P 0 ;0,1=22,2=0.000000
L 6.0110001 4.01916654 6.00966654 4.01666634 1 P 0 ;0,1=22,2=0.000000
L 6.00966654 4.01666634 6.00859961 4.0124998 1 P 0 ;0,1=22,2=0.000000
L 6.00859961 4.0124998 6.00833297 4.0087498 1 P 0 ;0,1=22,2=0.000000
L 6.00833297 4.0087498 6.00886673 4.0049999 1 P 0 ;0,1=22,2=0.000000
L 6.00886673 4.0049999 6.00966654 4.00249961 1 P 0 ;0,1=22,2=0.000000
L 6.00966654 4.00249961 6.01126663 3.99999941 1 P 0 ;0,1=22,2=0.000000
L 6.01126663 3.99999941 6.01313346 3.99833307 1 P 0 ;0,1=22,2=0.000000
L 6.01313346 3.99833307 6.0149997 3.9975 1 P 0 ;0,1=22,2=0.000000
L 6.0149997 3.9975 6.01686644 3.9975 1 P 0 ;0,1=22,2=0.000000
L 6.01686644 3.9975 6.01873327 3.99833307 1 P 0 ;0,1=22,2=0.000000
L 6.01873327 3.99833307 6.02033337 3.99958287 1 P 0 ;0,1=22,2=0.000000
L 6.02033337 3.99958287 6.02166693 4.00124911 1 P 0 ;0,1=22,2=0.000000
L 6.1005 4.01006663 6.0695 4.01006663 1 P 0 ;0,1=482,2=270.000000
L 6.0695 4.01006663 6.0695 4.01773307 1 P 0 ;0,1=482,2=270.000000
L 6.0695 4.01773307 6.07105069 4.0207998 1 P 0 ;0,1=482,2=270.000000
L 6.07105069 4.0207998 6.07311693 4.0231 1 P 0 ;0,1=482,2=270.000000
L 6.07311693 4.0231 6.07621624 4.02501703 1 P 0 ;0,1=482,2=270.000000
L 6.07621624 4.02501703 6.07983406 4.02655 1 P 0 ;0,1=482,2=270.000000
L 6.07983406 4.02655 6.08500049 4.02693327 1 P 0 ;0,1=482,2=270.000000
L 6.08500049 4.02693327 6.09016703 4.02655 1 P 0 ;0,1=482,2=270.000000
L 6.09016703 4.02655 6.09378386 4.02501703 1 P 0 ;0,1=482,2=270.000000
L 6.09378386 4.02501703 6.09688415 4.0231 1 P 0 ;0,1=482,2=270.000000
L 6.09688415 4.0231 6.09895039 4.0207998 1 P 0 ;0,1=482,2=270.000000
L 6.09895039 4.0207998 6.1005 4.01773307 1 P 0 ;0,1=482,2=270.000000
L 6.1005 4.01773307 6.1005 4.01006663 1 P 0 ;0,1=482,2=270.000000
L 6.09636762 4.0414499 6.09895039 4.04451663 1 P 0 ;0,1=482,2=270.000000
L 6.09895039 4.04451663 6.1005 4.04796663 1 P 0 ;0,1=482,2=270.000000
L 6.1005 4.04796663 6.1005 4.05103327 1 P 0 ;0,1=482,2=270.000000
L 6.1005 4.05103327 6.09895039 4.0541 1 P 0 ;0,1=482,2=270.000000
L 6.09895039 4.0541 6.09636762 4.0564002 1 P 0 ;0,1=482,2=270.000000
L 6.09636762 4.0564002 6.0927498 4.05755 1 P 0 ;0,1=482,2=270.000000
L 6.0927498 4.05755 6.08913396 4.05678346 1 P 0 ;0,1=482,2=270.000000
L 6.08913396 4.05678346 6.08603366 4.05486654 1 P 0 ;0,1=482,2=270.000000
L 6.08603366 4.05486654 6.08396644 4.05141654 1 P 0 ;0,1=482,2=270.000000
L 6.08396644 4.05141654 6.08293337 4.04681683 1 P 0 ;0,1=482,2=270.000000
L 6.08293337 4.04681683 6.08086713 4.04413337 1 P 0 ;0,1=482,2=270.000000
L 6.08086713 4.04413337 6.0772503 4.04298287 1 P 0 ;0,1=482,2=270.000000
L 6.0772503 4.04298287 6.07363346 4.0437501 1 P 0 ;0,1=482,2=270.000000
L 6.07363346 4.0437501 6.07105069 4.04566634 1 P 0 ;0,1=482,2=270.000000
L 6.07105069 4.04566634 6.0695 4.0483498 1 P 0 ;0,1=482,2=270.000000
L 6.0695 4.0483498 6.0695 4.05103327 1 P 0 ;0,1=482,2=270.000000
L 6.0695 4.05103327 6.07053317 4.05371673 1 P 0 ;0,1=482,2=270.000000
L 6.07053317 4.05371673 6.07311693 4.05601703 1 P 0 ;0,1=482,2=270.000000
L 6.07466654 4.07321644 6.07156722 4.07551663 1 P 0 ;0,1=482,2=270.000000
L 6.07156722 4.07551663 6.07001663 4.0782001 1 P 0 ;0,1=482,2=270.000000
L 6.07001663 4.0782001 6.0695 4.08126683 1 P 0 ;0,1=482,2=270.000000
L 6.0695 4.08126683 6.07053317 4.0851 1 P 0 ;0,1=482,2=270.000000
L 6.07053317 4.0851 6.07311693 4.08778346 1 P 0 ;0,1=482,2=270.000000
L 6.07311693 4.08778346 6.07621624 4.08855 1 P 0 ;0,1=482,2=270.000000
L 6.07621624 4.08855 6.07931742 4.08816673 1 P 0 ;0,1=482,2=270.000000
L 6.07931742 4.08816673 6.0819002 4.08663307 1 P 0 ;0,1=482,2=270.000000
L 6.0819002 4.08663307 6.08706673 4.07896663 1 P 0 ;0,1=482,2=270.000000
L 6.08706673 4.07896663 6.09068356 4.07551663 1 P 0 ;0,1=482,2=270.000000
L 6.09068356 4.07551663 6.09585108 4.07321644 1 P 0 ;0,1=482,2=270.000000
L 6.09585108 4.07321644 6.1005 4.0724499 1 P 0 ;0,1=482,2=270.000000
L 6.1005 4.0724499 6.1005 4.08855 1 P 0 ;0,1=482,2=270.000000
L 6.0695 4.11149961 6.07053317 4.10843287 1 P 0 ;0,1=482,2=270.000000
L 6.07053317 4.10843287 6.07311693 4.10613337 1 P 0 ;0,1=482,2=270.000000
L 6.07311693 4.10613337 6.07621624 4.1045997 1 P 0 ;0,1=482,2=270.000000
L 6.07621624 4.1045997 6.08035059 4.1034499 1 P 0 ;0,1=482,2=270.000000
L 6.08035059 4.1034499 6.08500049 4.10306663 1 P 0 ;0,1=482,2=270.000000
L 6.08500049 4.10306663 6.08965049 4.1034499 1 P 0 ;0,1=482,2=270.000000
L 6.08965049 4.1034499 6.09378386 4.1045997 1 P 0 ;0,1=482,2=270.000000
L 6.09378386 4.1045997 6.09688415 4.10613337 1 P 0 ;0,1=482,2=270.000000
L 6.09688415 4.10613337 6.09946693 4.10843287 1 P 0 ;0,1=482,2=270.000000
L 6.09946693 4.10843287 6.1005 4.11149961 1 P 0 ;0,1=482,2=270.000000
L 6.1005 4.11149961 6.09946693 4.11456634 1 P 0 ;0,1=482,2=270.000000
L 6.09946693 4.11456634 6.09688415 4.11686654 1 P 0 ;0,1=482,2=270.000000
L 6.09688415 4.11686654 6.09378386 4.1184002 1 P 0 ;0,1=482,2=270.000000
L 6.09378386 4.1184002 6.08965049 4.11955 1 P 0 ;0,1=482,2=270.000000
L 6.08965049 4.11955 6.08500049 4.11993327 1 P 0 ;0,1=482,2=270.000000
L 6.08500049 4.11993327 6.08035059 4.11955 1 P 0 ;0,1=482,2=270.000000
L 6.08035059 4.11955 6.07621624 4.1184002 1 P 0 ;0,1=482,2=270.000000
L 6.07621624 4.1184002 6.07311693 4.11686654 1 P 0 ;0,1=482,2=270.000000
L 6.07311693 4.11686654 6.07053317 4.11456634 1 P 0 ;0,1=482,2=270.000000
L 6.07053317 4.11456634 6.0695 4.11149961 1 P 0 ;0,1=482,2=270.000000
L 5.9352 4.16328996 5.9352 4.05325 1 P 0 
L 5.87976004 4.16328996 5.9352 4.16328996 1 P 0 
L 5.90448002 4.20026998 5.90448002 4.25026998 1 P 0 
L 5.92948002 4.22526998 5.87948002 4.22526998 1 P 0 
L 5.9352 4.05325 5.87976004 4.05325 1 P 0 
L 5.87976004 4.05325 5.87976004 4.16328996 1 P 0 
S P 0
OB 5.87976003937 4.05325 I
OS 5.9352 4.05325
OS 5.9352 4.03325
OS 5.87976003937 4.03325
OS 5.87976003937 4.05325
OE
SE
L 5.9775 4.02006663 5.9465 4.02006663 1 P 0 ;0,1=483,2=270.000000
L 5.9465 4.02006663 5.9465 4.02773307 1 P 0 ;0,1=483,2=270.000000
L 5.9465 4.02773307 5.94805069 4.0307998 1 P 0 ;0,1=483,2=270.000000
L 5.94805069 4.0307998 5.95011693 4.0331 1 P 0 ;0,1=483,2=270.000000
L 5.95011693 4.0331 5.95321624 4.03501703 1 P 0 ;0,1=483,2=270.000000
L 5.95321624 4.03501703 5.95683406 4.03655 1 P 0 ;0,1=483,2=270.000000
L 5.95683406 4.03655 5.96200049 4.03693327 1 P 0 ;0,1=483,2=270.000000
L 5.96200049 4.03693327 5.96716703 4.03655 1 P 0 ;0,1=483,2=270.000000
L 5.96716703 4.03655 5.97078386 4.03501703 1 P 0 ;0,1=483,2=270.000000
L 5.97078386 4.03501703 5.97388415 4.0331 1 P 0 ;0,1=483,2=270.000000
L 5.97388415 4.0331 5.97595039 4.0307998 1 P 0 ;0,1=483,2=270.000000
L 5.97595039 4.0307998 5.9775 4.02773307 1 P 0 ;0,1=483,2=270.000000
L 5.9775 4.02773307 5.9775 4.02006663 1 P 0 ;0,1=483,2=270.000000
L 5.97336762 4.0514499 5.97595039 4.05451663 1 P 0 ;0,1=483,2=270.000000
L 5.97595039 4.05451663 5.9775 4.05796663 1 P 0 ;0,1=483,2=270.000000
L 5.9775 4.05796663 5.9775 4.06103327 1 P 0 ;0,1=483,2=270.000000
L 5.9775 4.06103327 5.97595039 4.0641 1 P 0 ;0,1=483,2=270.000000
L 5.97595039 4.0641 5.97336762 4.0664002 1 P 0 ;0,1=483,2=270.000000
L 5.97336762 4.0664002 5.9697498 4.06755 1 P 0 ;0,1=483,2=270.000000
L 5.9697498 4.06755 5.96613396 4.06678346 1 P 0 ;0,1=483,2=270.000000
L 5.96613396 4.06678346 5.96303366 4.06486654 1 P 0 ;0,1=483,2=270.000000
L 5.96303366 4.06486654 5.96096644 4.06141654 1 P 0 ;0,1=483,2=270.000000
L 5.96096644 4.06141654 5.95993337 4.05681683 1 P 0 ;0,1=483,2=270.000000
L 5.95993337 4.05681683 5.95786713 4.05413337 1 P 0 ;0,1=483,2=270.000000
L 5.95786713 4.05413337 5.9542503 4.05298287 1 P 0 ;0,1=483,2=270.000000
L 5.9542503 4.05298287 5.95063346 4.0537501 1 P 0 ;0,1=483,2=270.000000
L 5.95063346 4.0537501 5.94805069 4.05566634 1 P 0 ;0,1=483,2=270.000000
L 5.94805069 4.05566634 5.9465 4.0583498 1 P 0 ;0,1=483,2=270.000000
L 5.9465 4.0583498 5.9465 4.06103327 1 P 0 ;0,1=483,2=270.000000
L 5.9465 4.06103327 5.94753317 4.06371673 1 P 0 ;0,1=483,2=270.000000
L 5.94753317 4.06371673 5.95011693 4.06601703 1 P 0 ;0,1=483,2=270.000000
L 5.9775 4.09049961 5.9465 4.09049961 1 P 0 ;0,1=483,2=270.000000
L 5.9465 4.09049961 5.9526997 4.0858999 1 P 0 ;0,1=483,2=270.000000
L 5.9775 4.0858999 5.9775 4.09509931 1 P 0 ;0,1=483,2=270.000000
L 5.97388415 4.11498287 5.97646693 4.11766634 1 P 0 ;0,1=483,2=270.000000
L 5.97646693 4.11766634 5.9775 4.12073307 1 P 0 ;0,1=483,2=270.000000
L 5.9775 4.12073307 5.97646693 4.1237998 1 P 0 ;0,1=483,2=270.000000
L 5.97646693 4.1237998 5.97336762 4.12648327 1 P 0 ;0,1=483,2=270.000000
L 5.97336762 4.12648327 5.96871673 4.1284002 1 P 0 ;0,1=483,2=270.000000
L 5.96871673 4.1284002 5.96406673 4.12916673 1 P 0 ;0,1=483,2=270.000000
L 5.96406673 4.12916673 5.95838366 4.12916673 1 P 0 ;0,1=483,2=270.000000
L 5.95838366 4.12916673 5.95373376 4.1284002 1 P 0 ;0,1=483,2=270.000000
L 5.95373376 4.1284002 5.9496003 4.12648327 1 P 0 ;0,1=483,2=270.000000
L 5.9496003 4.12648327 5.94753317 4.12418307 1 P 0 ;0,1=483,2=270.000000
L 5.94753317 4.12418307 5.9465 4.12149961 1 P 0 ;0,1=483,2=270.000000
L 5.9465 4.12149961 5.94753317 4.11843287 1 P 0 ;0,1=483,2=270.000000
L 5.94753317 4.11843287 5.9496003 4.11613337 1 P 0 ;0,1=483,2=270.000000
L 5.9496003 4.11613337 5.9526997 4.1145997 1 P 0 ;0,1=483,2=270.000000
L 5.9526997 4.1145997 5.95683406 4.11383317 1 P 0 ;0,1=483,2=270.000000
L 5.95683406 4.11383317 5.9604499 4.1145997 1 P 0 ;0,1=483,2=270.000000
L 5.9604499 4.1145997 5.96406673 4.11651663 1 P 0 ;0,1=483,2=270.000000
L 5.96406673 4.11651663 5.96613396 4.11881683 1 P 0 ;0,1=483,2=270.000000
L 5.96613396 4.11881683 5.96665049 4.12149961 1 P 0 ;0,1=483,2=270.000000
L 5.96665049 4.12149961 5.96561732 4.12456634 1 P 0 ;0,1=483,2=270.000000
L 5.96561732 4.12456634 5.96303366 4.12686654 1 P 0 ;0,1=483,2=270.000000
L 5.96303366 4.12686654 5.95838366 4.12916673 1 P 0 ;0,1=483,2=270.000000
L 5.87333297 4.1775 5.8799997 4.2025 1 P 0 ;0,1=1,2=0.000000
L 5.8799997 4.2025 5.88666693 4.1775 1 P 0 ;0,1=1,2=0.000000
L 5.88426644 4.18624961 5.87573297 4.18624961 1 P 0 ;0,1=1,2=0.000000
L 5.90586663 4.02041634 5.90426644 4.02166683 1 P 0 ;0,1=22,2=0.000000
L 5.90426644 4.02166683 5.9024002 4.0225 1 P 0 ;0,1=22,2=0.000000
L 5.9024002 4.0225 5.90026683 4.0225 1 P 0 ;0,1=22,2=0.000000
L 5.90026683 4.0225 5.89786634 4.02124941 1 P 0 ;0,1=22,2=0.000000
L 5.89786634 4.02124941 5.8960001 4.01916654 1 P 0 ;0,1=22,2=0.000000
L 5.8960001 4.01916654 5.89466654 4.01666634 1 P 0 ;0,1=22,2=0.000000
L 5.89466654 4.01666634 5.89359961 4.0124998 1 P 0 ;0,1=22,2=0.000000
L 5.89359961 4.0124998 5.89333297 4.0087498 1 P 0 ;0,1=22,2=0.000000
L 5.89333297 4.0087498 5.89386673 4.0049999 1 P 0 ;0,1=22,2=0.000000
L 5.89386673 4.0049999 5.89466654 4.00249961 1 P 0 ;0,1=22,2=0.000000
L 5.89466654 4.00249961 5.89626663 3.99999941 1 P 0 ;0,1=22,2=0.000000
L 5.89626663 3.99999941 5.89813346 3.99833307 1 P 0 ;0,1=22,2=0.000000
L 5.89813346 3.99833307 5.8999997 3.9975 1 P 0 ;0,1=22,2=0.000000
L 5.8999997 3.9975 5.90186644 3.9975 1 P 0 ;0,1=22,2=0.000000
L 5.90186644 3.9975 5.90373327 3.99833307 1 P 0 ;0,1=22,2=0.000000
L 5.90373327 3.99833307 5.90533337 3.99958287 1 P 0 ;0,1=22,2=0.000000
L 5.90533337 3.99958287 5.90666693 4.00124911 1 P 0 ;0,1=22,2=0.000000
L 5.64353996 4.30108002 5.69898002 4.30108002 1 P 0 
L 5.62326004 4.29806004 5.62326004 4.34806004 1 P 0 
L 5.64826004 4.32306004 5.59826004 4.32306004 1 P 0 
L 5.69898002 4.30108002 5.69898002 4.19103996 1 P 0 
L 5.69898002 4.19103996 5.64353996 4.19103996 1 P 0 
L 5.64353996 4.19103996 5.64353996 4.30108002 1 P 0 
P 5.67125994 4.18103996 3 P 0 8 0
L 5.69333297 4.3125 5.6999997 4.3375 1 P 0 ;0,1=1,2=0.000000
L 5.6999997 4.3375 5.70666693 4.3125 1 P 0 ;0,1=1,2=0.000000
L 5.70426644 4.32124961 5.69573297 4.32124961 1 P 0 ;0,1=1,2=0.000000
L 5.6255 4.19713327 5.6005 4.19713327 1 P 0 ;0,1=484,2=270.000000
L 5.6005 4.19713327 5.6005 4.20246654 1 P 0 ;0,1=484,2=270.000000
L 5.6005 4.20246654 5.60175059 4.2045999 1 P 0 ;0,1=484,2=270.000000
L 5.60175059 4.2045999 5.60341683 4.2062 1 P 0 ;0,1=484,2=270.000000
L 5.60341683 4.2062 5.60591634 4.20753356 1 P 0 ;0,1=484,2=270.000000
L 5.60591634 4.20753356 5.60883386 4.2086 1 P 0 ;0,1=484,2=270.000000
L 5.60883386 4.2086 5.61300039 4.20886663 1 P 0 ;0,1=484,2=270.000000
L 5.61300039 4.20886663 5.61716693 4.2086 1 P 0 ;0,1=484,2=270.000000
L 5.61716693 4.2086 5.62008376 4.20753356 1 P 0 ;0,1=484,2=270.000000
L 5.62008376 4.20753356 5.62258396 4.2062 1 P 0 ;0,1=484,2=270.000000
L 5.62258396 4.2062 5.6242503 4.2045999 1 P 0 ;0,1=484,2=270.000000
L 5.6242503 4.2045999 5.6255 4.20246654 1 P 0 ;0,1=484,2=270.000000
L 5.6255 4.20246654 5.6255 4.19713327 1 P 0 ;0,1=484,2=270.000000
L 5.62216742 4.2193999 5.6242503 4.22153327 1 P 0 ;0,1=484,2=270.000000
L 5.6242503 4.22153327 5.6255 4.22393327 1 P 0 ;0,1=484,2=270.000000
L 5.6255 4.22393327 5.6255 4.22606663 1 P 0 ;0,1=484,2=270.000000
L 5.6255 4.22606663 5.6242503 4.2282 1 P 0 ;0,1=484,2=270.000000
L 5.6242503 4.2282 5.62216742 4.2298001 1 P 0 ;0,1=484,2=270.000000
L 5.62216742 4.2298001 5.6192499 4.2306 1 P 0 ;0,1=484,2=270.000000
L 5.6192499 4.2306 5.61633386 4.23006673 1 P 0 ;0,1=484,2=270.000000
L 5.61633386 4.23006673 5.61383356 4.22873327 1 P 0 ;0,1=484,2=270.000000
L 5.61383356 4.22873327 5.61216654 4.22633327 1 P 0 ;0,1=484,2=270.000000
L 5.61216654 4.22633327 5.61133337 4.22313346 1 P 0 ;0,1=484,2=270.000000
L 5.61133337 4.22313346 5.60966703 4.22126663 1 P 0 ;0,1=484,2=270.000000
L 5.60966703 4.22126663 5.6067502 4.22046634 1 P 0 ;0,1=484,2=270.000000
L 5.6067502 4.22046634 5.60383346 4.2210001 1 P 0 ;0,1=484,2=270.000000
L 5.60383346 4.2210001 5.60175059 4.22233317 1 P 0 ;0,1=484,2=270.000000
L 5.60175059 4.22233317 5.6005 4.2241999 1 P 0 ;0,1=484,2=270.000000
L 5.6005 4.2241999 5.6005 4.22606663 1 P 0 ;0,1=484,2=270.000000
L 5.6005 4.22606663 5.60133317 4.22793337 1 P 0 ;0,1=484,2=270.000000
L 5.60133317 4.22793337 5.60341683 4.22953356 1 P 0 ;0,1=484,2=270.000000
L 5.62050039 4.24113327 5.62341713 4.24273297 1 P 0 ;0,1=484,2=270.000000
L 5.62341713 4.24273297 5.62508346 4.24486634 1 P 0 ;0,1=484,2=270.000000
L 5.62508346 4.24486634 5.6255 4.24726683 1 P 0 ;0,1=484,2=270.000000
L 5.6255 4.24726683 5.62508346 4.2494002 1 P 0 ;0,1=484,2=270.000000
L 5.62508346 4.2494002 5.62300059 4.25153356 1 P 0 ;0,1=484,2=270.000000
L 5.62300059 4.25153356 5.62050039 4.25286663 1 P 0 ;0,1=484,2=270.000000
L 5.62050039 4.25286663 5.6180001 4.25313317 1 P 0 ;0,1=484,2=270.000000
L 5.6180001 4.25313317 5.61508406 4.2526 1 P 0 ;0,1=484,2=270.000000
L 5.61508406 4.2526 5.61300039 4.25073327 1 P 0 ;0,1=484,2=270.000000
L 5.61300039 4.25073327 5.61216654 4.24886644 1 P 0 ;0,1=484,2=270.000000
L 5.61216654 4.24886644 5.61216654 4.24646654 1 P 0 ;0,1=484,2=270.000000
L 5.61216654 4.24886644 5.61091673 4.25046663 1 P 0 ;0,1=484,2=270.000000
L 5.61091673 4.25046663 5.60883386 4.2518001 1 P 0 ;0,1=484,2=270.000000
L 5.60883386 4.2518001 5.60633366 4.25233337 1 P 0 ;0,1=484,2=270.000000
L 5.60633366 4.25233337 5.60383346 4.2518001 1 P 0 ;0,1=484,2=270.000000
L 5.60383346 4.2518001 5.60175059 4.25046663 1 P 0 ;0,1=484,2=270.000000
L 5.60175059 4.25046663 5.6005 4.24806663 1 P 0 ;0,1=484,2=270.000000
L 5.6005 4.24806663 5.60091663 4.24566663 1 P 0 ;0,1=484,2=270.000000
L 5.60091663 4.24566663 5.60258366 4.24326663 1 P 0 ;0,1=484,2=270.000000
L 5.72586663 4.21041634 5.72426644 4.21166683 1 P 0 ;0,1=22,2=0.000000
L 5.72426644 4.21166683 5.7224002 4.2125 1 P 0 ;0,1=22,2=0.000000
L 5.7224002 4.2125 5.72026683 4.2125 1 P 0 ;0,1=22,2=0.000000
L 5.72026683 4.2125 5.71786634 4.21124941 1 P 0 ;0,1=22,2=0.000000
L 5.71786634 4.21124941 5.7160001 4.20916654 1 P 0 ;0,1=22,2=0.000000
L 5.7160001 4.20916654 5.71466654 4.20666634 1 P 0 ;0,1=22,2=0.000000
L 5.71466654 4.20666634 5.71359961 4.2024998 1 P 0 ;0,1=22,2=0.000000
L 5.71359961 4.2024998 5.71333297 4.1987498 1 P 0 ;0,1=22,2=0.000000
L 5.71333297 4.1987498 5.71386673 4.1949999 1 P 0 ;0,1=22,2=0.000000
L 5.71386673 4.1949999 5.71466654 4.19249961 1 P 0 ;0,1=22,2=0.000000
L 5.71466654 4.19249961 5.71626663 4.18999941 1 P 0 ;0,1=22,2=0.000000
L 5.71626663 4.18999941 5.71813346 4.18833307 1 P 0 ;0,1=22,2=0.000000
L 5.71813346 4.18833307 5.7199997 4.1875 1 P 0 ;0,1=22,2=0.000000
L 5.7199997 4.1875 5.72186644 4.1875 1 P 0 ;0,1=22,2=0.000000
L 5.72186644 4.1875 5.72373327 4.18833307 1 P 0 ;0,1=22,2=0.000000
L 5.72373327 4.18833307 5.72533337 4.18958287 1 P 0 ;0,1=22,2=0.000000
L 5.72533337 4.18958287 5.72666693 4.19124911 1 P 0 ;0,1=22,2=0.000000
L 5.40731998 4.16328996 5.46276004 4.16328996 1 P 0 
L 5.40731998 4.05325 5.40731998 4.16328996 1 P 0 
L 5.46276004 4.05325 5.40731998 4.05325 1 P 0 
L 5.46276004 4.16328996 5.46276004 4.05325 1 P 0 
L 5.36203996 4.14026998 5.36203996 4.19026998 1 P 0 
L 5.38703996 4.16526998 5.33703996 4.16526998 1 P 0 
P 5.43503996 4.04325 3 P 0 8 0
L 5.36333297 4.1275 5.3699997 4.1525 1 P 0 ;0,1=1,2=0.000000
L 5.3699997 4.1525 5.37666693 4.1275 1 P 0 ;0,1=1,2=0.000000
L 5.37426644 4.13624961 5.36573297 4.13624961 1 P 0 ;0,1=1,2=0.000000
L 5.3705 4.03556663 5.3395 4.03556663 1 P 0 ;0,1=485,2=270.000000
L 5.3395 4.03556663 5.3395 4.04323307 1 P 0 ;0,1=485,2=270.000000
L 5.3395 4.04323307 5.34105069 4.0462998 1 P 0 ;0,1=485,2=270.000000
L 5.34105069 4.0462998 5.34311693 4.0486 1 P 0 ;0,1=485,2=270.000000
L 5.34311693 4.0486 5.34621624 4.05051703 1 P 0 ;0,1=485,2=270.000000
L 5.34621624 4.05051703 5.34983406 4.05205 1 P 0 ;0,1=485,2=270.000000
L 5.34983406 4.05205 5.35500049 4.05243327 1 P 0 ;0,1=485,2=270.000000
L 5.35500049 4.05243327 5.36016703 4.05205 1 P 0 ;0,1=485,2=270.000000
L 5.36016703 4.05205 5.36378386 4.05051703 1 P 0 ;0,1=485,2=270.000000
L 5.36378386 4.05051703 5.36688415 4.0486 1 P 0 ;0,1=485,2=270.000000
L 5.36688415 4.0486 5.36895039 4.0462998 1 P 0 ;0,1=485,2=270.000000
L 5.36895039 4.0462998 5.3705 4.04323307 1 P 0 ;0,1=485,2=270.000000
L 5.3705 4.04323307 5.3705 4.03556663 1 P 0 ;0,1=485,2=270.000000
L 5.36636762 4.0669499 5.36895039 4.07001663 1 P 0 ;0,1=485,2=270.000000
L 5.36895039 4.07001663 5.3705 4.07346663 1 P 0 ;0,1=485,2=270.000000
L 5.3705 4.07346663 5.3705 4.07653327 1 P 0 ;0,1=485,2=270.000000
L 5.3705 4.07653327 5.36895039 4.0796 1 P 0 ;0,1=485,2=270.000000
L 5.36895039 4.0796 5.36636762 4.0819002 1 P 0 ;0,1=485,2=270.000000
L 5.36636762 4.0819002 5.3627498 4.08305 1 P 0 ;0,1=485,2=270.000000
L 5.3627498 4.08305 5.35913396 4.08228346 1 P 0 ;0,1=485,2=270.000000
L 5.35913396 4.08228346 5.35603366 4.08036654 1 P 0 ;0,1=485,2=270.000000
L 5.35603366 4.08036654 5.35396644 4.07691654 1 P 0 ;0,1=485,2=270.000000
L 5.35396644 4.07691654 5.35293337 4.07231683 1 P 0 ;0,1=485,2=270.000000
L 5.35293337 4.07231683 5.35086713 4.06963337 1 P 0 ;0,1=485,2=270.000000
L 5.35086713 4.06963337 5.3472503 4.06848287 1 P 0 ;0,1=485,2=270.000000
L 5.3472503 4.06848287 5.34363346 4.0692501 1 P 0 ;0,1=485,2=270.000000
L 5.34363346 4.0692501 5.34105069 4.07116634 1 P 0 ;0,1=485,2=270.000000
L 5.34105069 4.07116634 5.3395 4.0738498 1 P 0 ;0,1=485,2=270.000000
L 5.3395 4.0738498 5.3395 4.07653327 1 P 0 ;0,1=485,2=270.000000
L 5.3395 4.07653327 5.34053317 4.07921673 1 P 0 ;0,1=485,2=270.000000
L 5.34053317 4.07921673 5.34311693 4.08151703 1 P 0 ;0,1=485,2=270.000000
L 5.35758425 4.09871644 5.35396644 4.1013999 1 P 0 ;0,1=485,2=270.000000
L 5.35396644 4.1013999 5.3519002 4.1037001 1 P 0 ;0,1=485,2=270.000000
L 5.3519002 4.1037001 5.35086713 4.10676683 1 P 0 ;0,1=485,2=270.000000
L 5.35086713 4.10676683 5.3519002 4.1094503 1 P 0 ;0,1=485,2=270.000000
L 5.3519002 4.1094503 5.35396644 4.11136654 1 P 0 ;0,1=485,2=270.000000
L 5.35396644 4.11136654 5.35706673 4.1129002 1 P 0 ;0,1=485,2=270.000000
L 5.35706673 4.1129002 5.36068356 4.11328346 1 P 0 ;0,1=485,2=270.000000
L 5.36068356 4.11328346 5.36378386 4.1129002 1 P 0 ;0,1=485,2=270.000000
L 5.36378386 4.1129002 5.36688415 4.11136654 1 P 0 ;0,1=485,2=270.000000
L 5.36688415 4.11136654 5.36946693 4.10906634 1 P 0 ;0,1=485,2=270.000000
L 5.36946693 4.10906634 5.3705 4.10638356 1 P 0 ;0,1=485,2=270.000000
L 5.3705 4.10638356 5.36946693 4.10331683 1 P 0 ;0,1=485,2=270.000000
L 5.36946693 4.10331683 5.36636762 4.10063337 1 P 0 ;0,1=485,2=270.000000
L 5.36636762 4.10063337 5.36171673 4.0990997 1 P 0 ;0,1=485,2=270.000000
L 5.36171673 4.0990997 5.3565502 4.09871644 1 P 0 ;0,1=485,2=270.000000
L 5.3565502 4.09871644 5.34983406 4.09948287 1 P 0 ;0,1=485,2=270.000000
L 5.34983406 4.09948287 5.34621624 4.10063337 1 P 0 ;0,1=485,2=270.000000
L 5.34621624 4.10063337 5.3426003 4.10254961 1 P 0 ;0,1=485,2=270.000000
L 5.3426003 4.10254961 5.34001663 4.10523307 1 P 0 ;0,1=485,2=270.000000
L 5.34001663 4.10523307 5.3395 4.10791654 1 P 0 ;0,1=485,2=270.000000
L 5.3395 4.10791654 5.34053317 4.1106 1 P 0 ;0,1=485,2=270.000000
L 5.34053317 4.1106 5.34311693 4.11251703 1 P 0 ;0,1=485,2=270.000000
L 5.39086663 4.04541634 5.38926644 4.04666683 1 P 0 ;0,1=22,2=0.000000
L 5.38926644 4.04666683 5.3874002 4.0475 1 P 0 ;0,1=22,2=0.000000
L 5.3874002 4.0475 5.38526683 4.0475 1 P 0 ;0,1=22,2=0.000000
L 5.38526683 4.0475 5.38286634 4.04624941 1 P 0 ;0,1=22,2=0.000000
L 5.38286634 4.04624941 5.3810001 4.04416654 1 P 0 ;0,1=22,2=0.000000
L 5.3810001 4.04416654 5.37966654 4.04166634 1 P 0 ;0,1=22,2=0.000000
L 5.37966654 4.04166634 5.37859961 4.0374998 1 P 0 ;0,1=22,2=0.000000
L 5.37859961 4.0374998 5.37833297 4.0337498 1 P 0 ;0,1=22,2=0.000000
L 5.37833297 4.0337498 5.37886673 4.0299999 1 P 0 ;0,1=22,2=0.000000
L 5.37886673 4.0299999 5.37966654 4.02749961 1 P 0 ;0,1=22,2=0.000000
L 5.37966654 4.02749961 5.38126663 4.02499941 1 P 0 ;0,1=22,2=0.000000
L 5.38126663 4.02499941 5.38313346 4.02333307 1 P 0 ;0,1=22,2=0.000000
L 5.38313346 4.02333307 5.3849997 4.0225 1 P 0 ;0,1=22,2=0.000000
L 5.3849997 4.0225 5.38686644 4.0225 1 P 0 ;0,1=22,2=0.000000
L 5.38686644 4.0225 5.38873327 4.02333307 1 P 0 ;0,1=22,2=0.000000
L 5.38873327 4.02333307 5.39033337 4.02458287 1 P 0 ;0,1=22,2=0.000000
L 5.39033337 4.02458287 5.39166693 4.02624911 1 P 0 ;0,1=22,2=0.000000
L 5.76165 4.30108002 5.81708996 4.30108002 1 P 0 
L 5.81708996 4.30108002 5.81708996 4.19103996 1 P 0 
L 5.81708996 4.19103996 5.76165 4.19103996 1 P 0 
L 5.76165 4.19103996 5.76165 4.30108002 1 P 0 
L 5.74636998 4.29806004 5.74636998 4.34806004 1 P 0 
L 5.77136998 4.32306004 5.72136998 4.32306004 1 P 0 
P 5.78936998 4.18103996 3 P 0 8 0
L 5.81333297 4.3075 5.8199997 4.3325 1 P 0 ;0,1=1,2=0.000000
L 5.8199997 4.3325 5.82666693 4.3075 1 P 0 ;0,1=1,2=0.000000
L 5.82426644 4.31624961 5.81573297 4.31624961 1 P 0 ;0,1=1,2=0.000000
L 5.85586663 4.21041634 5.85426644 4.21166683 1 P 0 ;0,1=22,2=0.000000
L 5.85426644 4.21166683 5.8524002 4.2125 1 P 0 ;0,1=22,2=0.000000
L 5.8524002 4.2125 5.85026683 4.2125 1 P 0 ;0,1=22,2=0.000000
L 5.85026683 4.2125 5.84786634 4.21124941 1 P 0 ;0,1=22,2=0.000000
L 5.84786634 4.21124941 5.8460001 4.20916654 1 P 0 ;0,1=22,2=0.000000
L 5.8460001 4.20916654 5.84466654 4.20666634 1 P 0 ;0,1=22,2=0.000000
L 5.84466654 4.20666634 5.84359961 4.2024998 1 P 0 ;0,1=22,2=0.000000
L 5.84359961 4.2024998 5.84333297 4.1987498 1 P 0 ;0,1=22,2=0.000000
L 5.84333297 4.1987498 5.84386673 4.1949999 1 P 0 ;0,1=22,2=0.000000
L 5.84386673 4.1949999 5.84466654 4.19249961 1 P 0 ;0,1=22,2=0.000000
L 5.84466654 4.19249961 5.84626663 4.18999941 1 P 0 ;0,1=22,2=0.000000
L 5.84626663 4.18999941 5.84813346 4.18833307 1 P 0 ;0,1=22,2=0.000000
L 5.84813346 4.18833307 5.8499997 4.1875 1 P 0 ;0,1=22,2=0.000000
L 5.8499997 4.1875 5.85186644 4.1875 1 P 0 ;0,1=22,2=0.000000
L 5.85186644 4.1875 5.85373327 4.18833307 1 P 0 ;0,1=22,2=0.000000
L 5.85373327 4.18833307 5.85533337 4.18958287 1 P 0 ;0,1=22,2=0.000000
L 5.85533337 4.18958287 5.85666693 4.19124911 1 P 0 ;0,1=22,2=0.000000
L 5.8705 4.24056663 5.8395 4.24056663 1 P 0 ;0,1=486,2=270.000000
L 5.8395 4.24056663 5.8395 4.24823307 1 P 0 ;0,1=486,2=270.000000
L 5.8395 4.24823307 5.84105069 4.2512998 1 P 0 ;0,1=486,2=270.000000
L 5.84105069 4.2512998 5.84311693 4.2536 1 P 0 ;0,1=486,2=270.000000
L 5.84311693 4.2536 5.84621624 4.25551703 1 P 0 ;0,1=486,2=270.000000
L 5.84621624 4.25551703 5.84983406 4.25705 1 P 0 ;0,1=486,2=270.000000
L 5.84983406 4.25705 5.85500049 4.25743327 1 P 0 ;0,1=486,2=270.000000
L 5.85500049 4.25743327 5.86016703 4.25705 1 P 0 ;0,1=486,2=270.000000
L 5.86016703 4.25705 5.86378386 4.25551703 1 P 0 ;0,1=486,2=270.000000
L 5.86378386 4.25551703 5.86688415 4.2536 1 P 0 ;0,1=486,2=270.000000
L 5.86688415 4.2536 5.86895039 4.2512998 1 P 0 ;0,1=486,2=270.000000
L 5.86895039 4.2512998 5.8705 4.24823307 1 P 0 ;0,1=486,2=270.000000
L 5.8705 4.24823307 5.8705 4.24056663 1 P 0 ;0,1=486,2=270.000000
L 5.86636762 4.2719499 5.86895039 4.27501663 1 P 0 ;0,1=486,2=270.000000
L 5.86895039 4.27501663 5.8705 4.27846663 1 P 0 ;0,1=486,2=270.000000
L 5.8705 4.27846663 5.8705 4.28153327 1 P 0 ;0,1=486,2=270.000000
L 5.8705 4.28153327 5.86895039 4.2846 1 P 0 ;0,1=486,2=270.000000
L 5.86895039 4.2846 5.86636762 4.2869002 1 P 0 ;0,1=486,2=270.000000
L 5.86636762 4.2869002 5.8627498 4.28805 1 P 0 ;0,1=486,2=270.000000
L 5.8627498 4.28805 5.85913396 4.28728346 1 P 0 ;0,1=486,2=270.000000
L 5.85913396 4.28728346 5.85603366 4.28536654 1 P 0 ;0,1=486,2=270.000000
L 5.85603366 4.28536654 5.85396644 4.28191654 1 P 0 ;0,1=486,2=270.000000
L 5.85396644 4.28191654 5.85293337 4.27731683 1 P 0 ;0,1=486,2=270.000000
L 5.85293337 4.27731683 5.85086713 4.27463337 1 P 0 ;0,1=486,2=270.000000
L 5.85086713 4.27463337 5.8472503 4.27348287 1 P 0 ;0,1=486,2=270.000000
L 5.8472503 4.27348287 5.84363346 4.2742501 1 P 0 ;0,1=486,2=270.000000
L 5.84363346 4.2742501 5.84105069 4.27616634 1 P 0 ;0,1=486,2=270.000000
L 5.84105069 4.27616634 5.8395 4.2788498 1 P 0 ;0,1=486,2=270.000000
L 5.8395 4.2788498 5.8395 4.28153327 1 P 0 ;0,1=486,2=270.000000
L 5.8395 4.28153327 5.84053317 4.28421673 1 P 0 ;0,1=486,2=270.000000
L 5.84053317 4.28421673 5.84311693 4.28651703 1 P 0 ;0,1=486,2=270.000000
L 5.8705 4.3156 5.8395 4.3156 1 P 0 ;0,1=486,2=270.000000
L 5.8395 4.3156 5.86171673 4.30141624 1 P 0 ;0,1=486,2=270.000000
L 5.86171673 4.30141624 5.86171673 4.32058366 1 P 0 ;0,1=486,2=270.000000
L 5.25528002 4.12498996 5.25528002 4.23503002 1 P 0 
L 5.31071998 4.12498996 5.25528002 4.12498996 1 P 0 
L 5.31071998 4.23503002 5.31071998 4.12498996 1 P 0 
L 5.25528002 4.23503002 5.31071998 4.23503002 1 P 0 
L 5.23 4.23201004 5.23 4.28201004 1 P 0 
L 5.255 4.25701004 5.205 4.25701004 1 P 0 
P 5.283 4.11498996 3 P 0 8 0
L 5.26833297 4.2525 5.2749997 4.2775 1 P 0 ;0,1=1,2=0.000000
L 5.2749997 4.2775 5.28166693 4.2525 1 P 0 ;0,1=1,2=0.000000
L 5.27926644 4.26124961 5.27073297 4.26124961 1 P 0 ;0,1=1,2=0.000000
L 5.2105 4.14556663 5.1795 4.14556663 1 P 0 ;0,1=487,2=270.000000
L 5.1795 4.14556663 5.1795 4.15323307 1 P 0 ;0,1=487,2=270.000000
L 5.1795 4.15323307 5.18105069 4.1562998 1 P 0 ;0,1=487,2=270.000000
L 5.18105069 4.1562998 5.18311693 4.1586 1 P 0 ;0,1=487,2=270.000000
L 5.18311693 4.1586 5.18621624 4.16051703 1 P 0 ;0,1=487,2=270.000000
L 5.18621624 4.16051703 5.18983406 4.16205 1 P 0 ;0,1=487,2=270.000000
L 5.18983406 4.16205 5.19500049 4.16243327 1 P 0 ;0,1=487,2=270.000000
L 5.19500049 4.16243327 5.20016703 4.16205 1 P 0 ;0,1=487,2=270.000000
L 5.20016703 4.16205 5.20378386 4.16051703 1 P 0 ;0,1=487,2=270.000000
L 5.20378386 4.16051703 5.20688415 4.1586 1 P 0 ;0,1=487,2=270.000000
L 5.20688415 4.1586 5.20895039 4.1562998 1 P 0 ;0,1=487,2=270.000000
L 5.20895039 4.1562998 5.2105 4.15323307 1 P 0 ;0,1=487,2=270.000000
L 5.2105 4.15323307 5.2105 4.14556663 1 P 0 ;0,1=487,2=270.000000
L 5.20636762 4.1769499 5.20895039 4.18001663 1 P 0 ;0,1=487,2=270.000000
L 5.20895039 4.18001663 5.2105 4.18346663 1 P 0 ;0,1=487,2=270.000000
L 5.2105 4.18346663 5.2105 4.18653327 1 P 0 ;0,1=487,2=270.000000
L 5.2105 4.18653327 5.20895039 4.1896 1 P 0 ;0,1=487,2=270.000000
L 5.20895039 4.1896 5.20636762 4.1919002 1 P 0 ;0,1=487,2=270.000000
L 5.20636762 4.1919002 5.2027498 4.19305 1 P 0 ;0,1=487,2=270.000000
L 5.2027498 4.19305 5.19913396 4.19228346 1 P 0 ;0,1=487,2=270.000000
L 5.19913396 4.19228346 5.19603366 4.19036654 1 P 0 ;0,1=487,2=270.000000
L 5.19603366 4.19036654 5.19396644 4.18691654 1 P 0 ;0,1=487,2=270.000000
L 5.19396644 4.18691654 5.19293337 4.18231683 1 P 0 ;0,1=487,2=270.000000
L 5.19293337 4.18231683 5.19086713 4.17963337 1 P 0 ;0,1=487,2=270.000000
L 5.19086713 4.17963337 5.1872503 4.17848287 1 P 0 ;0,1=487,2=270.000000
L 5.1872503 4.17848287 5.18363346 4.1792501 1 P 0 ;0,1=487,2=270.000000
L 5.18363346 4.1792501 5.18105069 4.18116634 1 P 0 ;0,1=487,2=270.000000
L 5.18105069 4.18116634 5.1795 4.1838498 1 P 0 ;0,1=487,2=270.000000
L 5.1795 4.1838498 5.1795 4.18653327 1 P 0 ;0,1=487,2=270.000000
L 5.1795 4.18653327 5.18053317 4.18921673 1 P 0 ;0,1=487,2=270.000000
L 5.18053317 4.18921673 5.18311693 4.19151703 1 P 0 ;0,1=487,2=270.000000
L 5.20688415 4.20948287 5.20946693 4.21216634 1 P 0 ;0,1=487,2=270.000000
L 5.20946693 4.21216634 5.2105 4.21523307 1 P 0 ;0,1=487,2=270.000000
L 5.2105 4.21523307 5.20946693 4.2182998 1 P 0 ;0,1=487,2=270.000000
L 5.20946693 4.2182998 5.20636762 4.22098327 1 P 0 ;0,1=487,2=270.000000
L 5.20636762 4.22098327 5.20171673 4.2229002 1 P 0 ;0,1=487,2=270.000000
L 5.20171673 4.2229002 5.19706673 4.22366673 1 P 0 ;0,1=487,2=270.000000
L 5.19706673 4.22366673 5.19138366 4.22366673 1 P 0 ;0,1=487,2=270.000000
L 5.19138366 4.22366673 5.18673376 4.2229002 1 P 0 ;0,1=487,2=270.000000
L 5.18673376 4.2229002 5.1826003 4.22098327 1 P 0 ;0,1=487,2=270.000000
L 5.1826003 4.22098327 5.18053317 4.21868307 1 P 0 ;0,1=487,2=270.000000
L 5.18053317 4.21868307 5.1795 4.21599961 1 P 0 ;0,1=487,2=270.000000
L 5.1795 4.21599961 5.18053317 4.21293287 1 P 0 ;0,1=487,2=270.000000
L 5.18053317 4.21293287 5.1826003 4.21063337 1 P 0 ;0,1=487,2=270.000000
L 5.1826003 4.21063337 5.1856997 4.2090997 1 P 0 ;0,1=487,2=270.000000
L 5.1856997 4.2090997 5.18983406 4.20833317 1 P 0 ;0,1=487,2=270.000000
L 5.18983406 4.20833317 5.1934499 4.2090997 1 P 0 ;0,1=487,2=270.000000
L 5.1934499 4.2090997 5.19706673 4.21101663 1 P 0 ;0,1=487,2=270.000000
L 5.19706673 4.21101663 5.19913396 4.21331683 1 P 0 ;0,1=487,2=270.000000
L 5.19913396 4.21331683 5.19965049 4.21599961 1 P 0 ;0,1=487,2=270.000000
L 5.19965049 4.21599961 5.19861732 4.21906634 1 P 0 ;0,1=487,2=270.000000
L 5.19861732 4.21906634 5.19603366 4.22136654 1 P 0 ;0,1=487,2=270.000000
L 5.19603366 4.22136654 5.19138366 4.22366673 1 P 0 ;0,1=487,2=270.000000
L 5.23086663 4.11241634 5.22926644 4.11366683 1 P 0 ;0,1=22,2=0.000000
L 5.22926644 4.11366683 5.2274002 4.1145 1 P 0 ;0,1=22,2=0.000000
L 5.2274002 4.1145 5.22526683 4.1145 1 P 0 ;0,1=22,2=0.000000
L 5.22526683 4.1145 5.22286634 4.11324941 1 P 0 ;0,1=22,2=0.000000
L 5.22286634 4.11324941 5.2210001 4.11116654 1 P 0 ;0,1=22,2=0.000000
L 5.2210001 4.11116654 5.21966654 4.10866634 1 P 0 ;0,1=22,2=0.000000
L 5.21966654 4.10866634 5.21859961 4.1044998 1 P 0 ;0,1=22,2=0.000000
L 5.21859961 4.1044998 5.21833297 4.1007498 1 P 0 ;0,1=22,2=0.000000
L 5.21833297 4.1007498 5.21886673 4.0969999 1 P 0 ;0,1=22,2=0.000000
L 5.21886673 4.0969999 5.21966654 4.09449961 1 P 0 ;0,1=22,2=0.000000
L 5.21966654 4.09449961 5.22126663 4.09199941 1 P 0 ;0,1=22,2=0.000000
L 5.22126663 4.09199941 5.22313346 4.09033307 1 P 0 ;0,1=22,2=0.000000
L 5.22313346 4.09033307 5.2249997 4.0895 1 P 0 ;0,1=22,2=0.000000
L 5.2249997 4.0895 5.22686644 4.0895 1 P 0 ;0,1=22,2=0.000000
L 5.22686644 4.0895 5.22873327 4.09033307 1 P 0 ;0,1=22,2=0.000000
L 5.22873327 4.09033307 5.23033337 4.09158287 1 P 0 ;0,1=22,2=0.000000
L 5.23033337 4.09158287 5.23166693 4.09324911 1 P 0 ;0,1=22,2=0.000000
L 5.40731998 4.30108002 5.46276004 4.30108002 1 P 0 
L 5.46276004 4.30108002 5.46276004 4.19103996 1 P 0 
L 5.46276004 4.19103996 5.40731998 4.19103996 1 P 0 
L 5.40731998 4.19103996 5.40731998 4.30108002 1 P 0 
L 5.41203996 4.32306004 5.36203996 4.32306004 1 P 0 
L 5.38703996 4.29806004 5.38703996 4.34806004 1 P 0 
P 5.43503996 4.18103996 3 P 0 8 0
L 5.41333297 4.3145 5.4199997 4.3395 1 P 0 ;0,1=1,2=0.000000
L 5.4199997 4.3395 5.42666693 4.3145 1 P 0 ;0,1=1,2=0.000000
L 5.42426644 4.32324961 5.41573297 4.32324961 1 P 0 ;0,1=1,2=0.000000
L 5.38586663 4.19541634 5.38426644 4.19666683 1 P 0 ;0,1=22,2=0.000000
L 5.38426644 4.19666683 5.3824002 4.1975 1 P 0 ;0,1=22,2=0.000000
L 5.3824002 4.1975 5.38026683 4.1975 1 P 0 ;0,1=22,2=0.000000
L 5.38026683 4.1975 5.37786634 4.19624941 1 P 0 ;0,1=22,2=0.000000
L 5.37786634 4.19624941 5.3760001 4.19416654 1 P 0 ;0,1=22,2=0.000000
L 5.3760001 4.19416654 5.37466654 4.19166634 1 P 0 ;0,1=22,2=0.000000
L 5.37466654 4.19166634 5.37359961 4.1874998 1 P 0 ;0,1=22,2=0.000000
L 5.37359961 4.1874998 5.37333297 4.1837498 1 P 0 ;0,1=22,2=0.000000
L 5.37333297 4.1837498 5.37386673 4.1799999 1 P 0 ;0,1=22,2=0.000000
L 5.37386673 4.1799999 5.37466654 4.17749961 1 P 0 ;0,1=22,2=0.000000
L 5.37466654 4.17749961 5.37626663 4.17499941 1 P 0 ;0,1=22,2=0.000000
L 5.37626663 4.17499941 5.37813346 4.17333307 1 P 0 ;0,1=22,2=0.000000
L 5.37813346 4.17333307 5.3799997 4.1725 1 P 0 ;0,1=22,2=0.000000
L 5.3799997 4.1725 5.38186644 4.1725 1 P 0 ;0,1=22,2=0.000000
L 5.38186644 4.1725 5.38373327 4.17333307 1 P 0 ;0,1=22,2=0.000000
L 5.38373327 4.17333307 5.38533337 4.17458287 1 P 0 ;0,1=22,2=0.000000
L 5.38533337 4.17458287 5.38666693 4.17624911 1 P 0 ;0,1=22,2=0.000000
L 5.3755 4.21056663 5.3445 4.21056663 1 P 0 ;0,1=488,2=270.000000
L 5.3445 4.21056663 5.3445 4.21823307 1 P 0 ;0,1=488,2=270.000000
L 5.3445 4.21823307 5.34605069 4.2212998 1 P 0 ;0,1=488,2=270.000000
L 5.34605069 4.2212998 5.34811693 4.2236 1 P 0 ;0,1=488,2=270.000000
L 5.34811693 4.2236 5.35121624 4.22551703 1 P 0 ;0,1=488,2=270.000000
L 5.35121624 4.22551703 5.35483406 4.22705 1 P 0 ;0,1=488,2=270.000000
L 5.35483406 4.22705 5.36000049 4.22743327 1 P 0 ;0,1=488,2=270.000000
L 5.36000049 4.22743327 5.36516703 4.22705 1 P 0 ;0,1=488,2=270.000000
L 5.36516703 4.22705 5.36878386 4.22551703 1 P 0 ;0,1=488,2=270.000000
L 5.36878386 4.22551703 5.37188415 4.2236 1 P 0 ;0,1=488,2=270.000000
L 5.37188415 4.2236 5.37395039 4.2212998 1 P 0 ;0,1=488,2=270.000000
L 5.37395039 4.2212998 5.3755 4.21823307 1 P 0 ;0,1=488,2=270.000000
L 5.3755 4.21823307 5.3755 4.21056663 1 P 0 ;0,1=488,2=270.000000
L 5.37136762 4.2419499 5.37395039 4.24501663 1 P 0 ;0,1=488,2=270.000000
L 5.37395039 4.24501663 5.3755 4.24846663 1 P 0 ;0,1=488,2=270.000000
L 5.3755 4.24846663 5.3755 4.25153327 1 P 0 ;0,1=488,2=270.000000
L 5.3755 4.25153327 5.37395039 4.2546 1 P 0 ;0,1=488,2=270.000000
L 5.37395039 4.2546 5.37136762 4.2569002 1 P 0 ;0,1=488,2=270.000000
L 5.37136762 4.2569002 5.3677498 4.25805 1 P 0 ;0,1=488,2=270.000000
L 5.3677498 4.25805 5.36413396 4.25728346 1 P 0 ;0,1=488,2=270.000000
L 5.36413396 4.25728346 5.36103366 4.25536654 1 P 0 ;0,1=488,2=270.000000
L 5.36103366 4.25536654 5.35896644 4.25191654 1 P 0 ;0,1=488,2=270.000000
L 5.35896644 4.25191654 5.35793337 4.24731683 1 P 0 ;0,1=488,2=270.000000
L 5.35793337 4.24731683 5.35586713 4.24463337 1 P 0 ;0,1=488,2=270.000000
L 5.35586713 4.24463337 5.3522503 4.24348287 1 P 0 ;0,1=488,2=270.000000
L 5.3522503 4.24348287 5.34863346 4.2442501 1 P 0 ;0,1=488,2=270.000000
L 5.34863346 4.2442501 5.34605069 4.24616634 1 P 0 ;0,1=488,2=270.000000
L 5.34605069 4.24616634 5.3445 4.2488498 1 P 0 ;0,1=488,2=270.000000
L 5.3445 4.2488498 5.3445 4.25153327 1 P 0 ;0,1=488,2=270.000000
L 5.3445 4.25153327 5.34553317 4.25421673 1 P 0 ;0,1=488,2=270.000000
L 5.34553317 4.25421673 5.34811693 4.25651703 1 P 0 ;0,1=488,2=270.000000
L 5.3755 4.28099961 5.3445 4.28099961 1 P 0 ;0,1=488,2=270.000000
L 5.3445 4.28099961 5.3506997 4.2763999 1 P 0 ;0,1=488,2=270.000000
L 5.3755 4.2763999 5.3755 4.28559931 1 P 0 ;0,1=488,2=270.000000
L 5.58086998 4.16328996 5.58086998 4.05325 1 P 0 
L 5.52543002 4.16328996 5.58086998 4.16328996 1 P 0 
L 5.50515 4.15026998 5.50515 4.20026998 1 P 0 
L 5.53015 4.17526998 5.48015 4.17526998 1 P 0 
L 5.58086998 4.05325 5.52543002 4.05325 1 P 0 
L 5.52543002 4.05325 5.52543002 4.16328996 1 P 0 
S P 0
OB 5.580869980315 4.05325 I
OS 5.580869980315 4.03325
OS 5.525430019685 4.03325
OS 5.525430019685 4.05325
OS 5.580869980315 4.05325
OE
SE
L 5.48833297 4.1225 5.4949997 4.1475 1 P 0 ;0,1=1,2=0.000000
L 5.4949997 4.1475 5.50166693 4.1225 1 P 0 ;0,1=1,2=0.000000
L 5.49926644 4.13124961 5.49073297 4.13124961 1 P 0 ;0,1=1,2=0.000000
L 5.53086663 4.02541634 5.52926644 4.02666683 1 P 0 ;0,1=22,2=0.000000
L 5.52926644 4.02666683 5.5274002 4.0275 1 P 0 ;0,1=22,2=0.000000
L 5.5274002 4.0275 5.52526683 4.0275 1 P 0 ;0,1=22,2=0.000000
L 5.52526683 4.0275 5.52286634 4.02624941 1 P 0 ;0,1=22,2=0.000000
L 5.52286634 4.02624941 5.5210001 4.02416654 1 P 0 ;0,1=22,2=0.000000
L 5.5210001 4.02416654 5.51966654 4.02166634 1 P 0 ;0,1=22,2=0.000000
L 5.51966654 4.02166634 5.51859961 4.0174998 1 P 0 ;0,1=22,2=0.000000
L 5.51859961 4.0174998 5.51833297 4.0137498 1 P 0 ;0,1=22,2=0.000000
L 5.51833297 4.0137498 5.51886673 4.0099999 1 P 0 ;0,1=22,2=0.000000
L 5.51886673 4.0099999 5.51966654 4.00749961 1 P 0 ;0,1=22,2=0.000000
L 5.51966654 4.00749961 5.52126663 4.00499941 1 P 0 ;0,1=22,2=0.000000
L 5.52126663 4.00499941 5.52313346 4.00333307 1 P 0 ;0,1=22,2=0.000000
L 5.52313346 4.00333307 5.5249997 4.0025 1 P 0 ;0,1=22,2=0.000000
L 5.5249997 4.0025 5.52686644 4.0025 1 P 0 ;0,1=22,2=0.000000
L 5.52686644 4.0025 5.52873327 4.00333307 1 P 0 ;0,1=22,2=0.000000
L 5.52873327 4.00333307 5.53033337 4.00458287 1 P 0 ;0,1=22,2=0.000000
L 5.53033337 4.00458287 5.53166693 4.00624911 1 P 0 ;0,1=22,2=0.000000
L 5.5025 4.04213327 5.4775 4.04213327 1 P 0 ;0,1=489,2=270.000000
L 5.4775 4.04213327 5.4775 4.04746654 1 P 0 ;0,1=489,2=270.000000
L 5.4775 4.04746654 5.47875059 4.0495999 1 P 0 ;0,1=489,2=270.000000
L 5.47875059 4.0495999 5.48041683 4.0512 1 P 0 ;0,1=489,2=270.000000
L 5.48041683 4.0512 5.48291634 4.05253356 1 P 0 ;0,1=489,2=270.000000
L 5.48291634 4.05253356 5.48583386 4.0536 1 P 0 ;0,1=489,2=270.000000
L 5.48583386 4.0536 5.49000039 4.05386663 1 P 0 ;0,1=489,2=270.000000
L 5.49000039 4.05386663 5.49416693 4.0536 1 P 0 ;0,1=489,2=270.000000
L 5.49416693 4.0536 5.49708376 4.05253356 1 P 0 ;0,1=489,2=270.000000
L 5.49708376 4.05253356 5.49958396 4.0512 1 P 0 ;0,1=489,2=270.000000
L 5.49958396 4.0512 5.5012503 4.0495999 1 P 0 ;0,1=489,2=270.000000
L 5.5012503 4.0495999 5.5025 4.04746654 1 P 0 ;0,1=489,2=270.000000
L 5.5025 4.04746654 5.5025 4.04213327 1 P 0 ;0,1=489,2=270.000000
L 5.49916742 4.0643999 5.5012503 4.06653327 1 P 0 ;0,1=489,2=270.000000
L 5.5012503 4.06653327 5.5025 4.06893327 1 P 0 ;0,1=489,2=270.000000
L 5.5025 4.06893327 5.5025 4.07106663 1 P 0 ;0,1=489,2=270.000000
L 5.5025 4.07106663 5.5012503 4.0732 1 P 0 ;0,1=489,2=270.000000
L 5.5012503 4.0732 5.49916742 4.0748001 1 P 0 ;0,1=489,2=270.000000
L 5.49916742 4.0748001 5.4962499 4.0756 1 P 0 ;0,1=489,2=270.000000
L 5.4962499 4.0756 5.49333386 4.07506673 1 P 0 ;0,1=489,2=270.000000
L 5.49333386 4.07506673 5.49083356 4.07373327 1 P 0 ;0,1=489,2=270.000000
L 5.49083356 4.07373327 5.48916654 4.07133327 1 P 0 ;0,1=489,2=270.000000
L 5.48916654 4.07133327 5.48833337 4.06813346 1 P 0 ;0,1=489,2=270.000000
L 5.48833337 4.06813346 5.48666703 4.06626663 1 P 0 ;0,1=489,2=270.000000
L 5.48666703 4.06626663 5.4837502 4.06546634 1 P 0 ;0,1=489,2=270.000000
L 5.4837502 4.06546634 5.48083346 4.0660001 1 P 0 ;0,1=489,2=270.000000
L 5.48083346 4.0660001 5.47875059 4.06733317 1 P 0 ;0,1=489,2=270.000000
L 5.47875059 4.06733317 5.4775 4.0691999 1 P 0 ;0,1=489,2=270.000000
L 5.4775 4.0691999 5.4775 4.07106663 1 P 0 ;0,1=489,2=270.000000
L 5.4775 4.07106663 5.47833317 4.07293337 1 P 0 ;0,1=489,2=270.000000
L 5.47833317 4.07293337 5.48041683 4.07453356 1 P 0 ;0,1=489,2=270.000000
L 5.5025 4.09146654 5.49708376 4.0919997 1 P 0 ;0,1=489,2=270.000000
L 5.49708376 4.0919997 5.49250069 4.0928 1 P 0 ;0,1=489,2=270.000000
L 5.49250069 4.0928 5.48833337 4.09386644 1 P 0 ;0,1=489,2=270.000000
L 5.48833337 4.09386644 5.4837502 4.0952 1 P 0 ;0,1=489,2=270.000000
L 5.4837502 4.0952 5.4775 4.09733337 1 P 0 ;0,1=489,2=270.000000
L 5.4775 4.09733337 5.4775 4.08666654 1 P 0 ;0,1=489,2=270.000000
L 6.11598002 4.30108002 6.17141998 4.30108002 1 P 0 
L 6.17141998 4.30108002 6.17141998 4.19103996 1 P 0 
L 6.17141998 4.19103996 6.11598002 4.19103996 1 P 0 
L 6.11598002 4.19103996 6.11598002 4.30108002 1 P 0 
L 6.1257 4.32306004 6.0757 4.32306004 1 P 0 
L 6.1007 4.29806004 6.1007 4.34806004 1 P 0 
P 6.1437 4.18103996 3 P 0 8 0
L 6.18833297 4.3025 6.1949997 4.3275 1 P 0 ;0,1=1,2=0.000000
L 6.1949997 4.3275 6.20166693 4.3025 1 P 0 ;0,1=1,2=0.000000
L 6.19926644 4.31124961 6.19073297 4.31124961 1 P 0 ;0,1=1,2=0.000000
L 6.20086663 4.20041634 6.19926644 4.20166683 1 P 0 ;0,1=22,2=0.000000
L 6.19926644 4.20166683 6.1974002 4.2025 1 P 0 ;0,1=22,2=0.000000
L 6.1974002 4.2025 6.19526683 4.2025 1 P 0 ;0,1=22,2=0.000000
L 6.19526683 4.2025 6.19286634 4.20124941 1 P 0 ;0,1=22,2=0.000000
L 6.19286634 4.20124941 6.1910001 4.19916654 1 P 0 ;0,1=22,2=0.000000
L 6.1910001 4.19916654 6.18966654 4.19666634 1 P 0 ;0,1=22,2=0.000000
L 6.18966654 4.19666634 6.18859961 4.1924998 1 P 0 ;0,1=22,2=0.000000
L 6.18859961 4.1924998 6.18833297 4.1887498 1 P 0 ;0,1=22,2=0.000000
L 6.18833297 4.1887498 6.18886673 4.1849999 1 P 0 ;0,1=22,2=0.000000
L 6.18886673 4.1849999 6.18966654 4.18249961 1 P 0 ;0,1=22,2=0.000000
L 6.18966654 4.18249961 6.19126663 4.17999941 1 P 0 ;0,1=22,2=0.000000
L 6.19126663 4.17999941 6.19313346 4.17833307 1 P 0 ;0,1=22,2=0.000000
L 6.19313346 4.17833307 6.1949997 4.1775 1 P 0 ;0,1=22,2=0.000000
L 6.1949997 4.1775 6.19686644 4.1775 1 P 0 ;0,1=22,2=0.000000
L 6.19686644 4.1775 6.19873327 4.17833307 1 P 0 ;0,1=22,2=0.000000
L 6.19873327 4.17833307 6.20033337 4.17958287 1 P 0 ;0,1=22,2=0.000000
L 6.20033337 4.17958287 6.20166693 4.18124911 1 P 0 ;0,1=22,2=0.000000
L 6.2455 4.19506663 6.2145 4.19506663 1 P 0 ;0,1=490,2=270.000000
L 6.2145 4.19506663 6.2145 4.20273307 1 P 0 ;0,1=490,2=270.000000
L 6.2145 4.20273307 6.21605069 4.2057998 1 P 0 ;0,1=490,2=270.000000
L 6.21605069 4.2057998 6.21811693 4.2081 1 P 0 ;0,1=490,2=270.000000
L 6.21811693 4.2081 6.22121624 4.21001703 1 P 0 ;0,1=490,2=270.000000
L 6.22121624 4.21001703 6.22483406 4.21155 1 P 0 ;0,1=490,2=270.000000
L 6.22483406 4.21155 6.23000049 4.21193327 1 P 0 ;0,1=490,2=270.000000
L 6.23000049 4.21193327 6.23516703 4.21155 1 P 0 ;0,1=490,2=270.000000
L 6.23516703 4.21155 6.23878386 4.21001703 1 P 0 ;0,1=490,2=270.000000
L 6.23878386 4.21001703 6.24188415 4.2081 1 P 0 ;0,1=490,2=270.000000
L 6.24188415 4.2081 6.24395039 4.2057998 1 P 0 ;0,1=490,2=270.000000
L 6.24395039 4.2057998 6.2455 4.20273307 1 P 0 ;0,1=490,2=270.000000
L 6.2455 4.20273307 6.2455 4.19506663 1 P 0 ;0,1=490,2=270.000000
L 6.24136762 4.2264499 6.24395039 4.22951663 1 P 0 ;0,1=490,2=270.000000
L 6.24395039 4.22951663 6.2455 4.23296663 1 P 0 ;0,1=490,2=270.000000
L 6.2455 4.23296663 6.2455 4.23603327 1 P 0 ;0,1=490,2=270.000000
L 6.2455 4.23603327 6.24395039 4.2391 1 P 0 ;0,1=490,2=270.000000
L 6.24395039 4.2391 6.24136762 4.2414002 1 P 0 ;0,1=490,2=270.000000
L 6.24136762 4.2414002 6.2377498 4.24255 1 P 0 ;0,1=490,2=270.000000
L 6.2377498 4.24255 6.23413396 4.24178346 1 P 0 ;0,1=490,2=270.000000
L 6.23413396 4.24178346 6.23103366 4.23986654 1 P 0 ;0,1=490,2=270.000000
L 6.23103366 4.23986654 6.22896644 4.23641654 1 P 0 ;0,1=490,2=270.000000
L 6.22896644 4.23641654 6.22793337 4.23181683 1 P 0 ;0,1=490,2=270.000000
L 6.22793337 4.23181683 6.22586713 4.22913337 1 P 0 ;0,1=490,2=270.000000
L 6.22586713 4.22913337 6.2222503 4.22798287 1 P 0 ;0,1=490,2=270.000000
L 6.2222503 4.22798287 6.21863346 4.2287501 1 P 0 ;0,1=490,2=270.000000
L 6.21863346 4.2287501 6.21605069 4.23066634 1 P 0 ;0,1=490,2=270.000000
L 6.21605069 4.23066634 6.2145 4.2333498 1 P 0 ;0,1=490,2=270.000000
L 6.2145 4.2333498 6.2145 4.23603327 1 P 0 ;0,1=490,2=270.000000
L 6.2145 4.23603327 6.21553317 4.23871673 1 P 0 ;0,1=490,2=270.000000
L 6.21553317 4.23871673 6.21811693 4.24101703 1 P 0 ;0,1=490,2=270.000000
L 6.2455 4.26549961 6.2145 4.26549961 1 P 0 ;0,1=490,2=270.000000
L 6.2145 4.26549961 6.2206997 4.2608999 1 P 0 ;0,1=490,2=270.000000
L 6.2455 4.2608999 6.2455 4.27009931 1 P 0 ;0,1=490,2=270.000000
L 6.2455 4.29649961 6.2145 4.29649961 1 P 0 ;0,1=490,2=270.000000
L 6.2145 4.29649961 6.2206997 4.2918999 1 P 0 ;0,1=490,2=270.000000
L 6.2455 4.2918999 6.2455 4.30109931 1 P 0 ;0,1=490,2=270.000000
L 5.99786998 4.30108002 6.05331004 4.30108002 1 P 0 
L 6.00758996 4.31806004 5.95758996 4.31806004 1 P 0 
L 5.98258996 4.29306004 5.98258996 4.34306004 1 P 0 
L 6.05331004 4.30108002 6.05331004 4.19103996 1 P 0 
L 6.05331004 4.19103996 5.99786998 4.19103996 1 P 0 
L 5.99786998 4.19103996 5.99786998 4.30108002 1 P 0 
P 6.02558996 4.18103996 3 P 0 8 0
L 6.01833297 4.3075 6.0249997 4.3325 1 P 0 ;0,1=1,2=0.000000
L 6.0249997 4.3325 6.03166693 4.3075 1 P 0 ;0,1=1,2=0.000000
L 6.02926644 4.31624961 6.02073297 4.31624961 1 P 0 ;0,1=1,2=0.000000
L 6.0955 4.19006663 6.0645 4.19006663 1 P 0 ;0,1=491,2=270.000000
L 6.0645 4.19006663 6.0645 4.19773307 1 P 0 ;0,1=491,2=270.000000
L 6.0645 4.19773307 6.06605069 4.2007998 1 P 0 ;0,1=491,2=270.000000
L 6.06605069 4.2007998 6.06811693 4.2031 1 P 0 ;0,1=491,2=270.000000
L 6.06811693 4.2031 6.07121624 4.20501703 1 P 0 ;0,1=491,2=270.000000
L 6.07121624 4.20501703 6.07483406 4.20655 1 P 0 ;0,1=491,2=270.000000
L 6.07483406 4.20655 6.08000049 4.20693327 1 P 0 ;0,1=491,2=270.000000
L 6.08000049 4.20693327 6.08516703 4.20655 1 P 0 ;0,1=491,2=270.000000
L 6.08516703 4.20655 6.08878386 4.20501703 1 P 0 ;0,1=491,2=270.000000
L 6.08878386 4.20501703 6.09188415 4.2031 1 P 0 ;0,1=491,2=270.000000
L 6.09188415 4.2031 6.09395039 4.2007998 1 P 0 ;0,1=491,2=270.000000
L 6.09395039 4.2007998 6.0955 4.19773307 1 P 0 ;0,1=491,2=270.000000
L 6.0955 4.19773307 6.0955 4.19006663 1 P 0 ;0,1=491,2=270.000000
L 6.09136762 4.2214499 6.09395039 4.22451663 1 P 0 ;0,1=491,2=270.000000
L 6.09395039 4.22451663 6.0955 4.22796663 1 P 0 ;0,1=491,2=270.000000
L 6.0955 4.22796663 6.0955 4.23103327 1 P 0 ;0,1=491,2=270.000000
L 6.0955 4.23103327 6.09395039 4.2341 1 P 0 ;0,1=491,2=270.000000
L 6.09395039 4.2341 6.09136762 4.2364002 1 P 0 ;0,1=491,2=270.000000
L 6.09136762 4.2364002 6.0877498 4.23755 1 P 0 ;0,1=491,2=270.000000
L 6.0877498 4.23755 6.08413396 4.23678346 1 P 0 ;0,1=491,2=270.000000
L 6.08413396 4.23678346 6.08103366 4.23486654 1 P 0 ;0,1=491,2=270.000000
L 6.08103366 4.23486654 6.07896644 4.23141654 1 P 0 ;0,1=491,2=270.000000
L 6.07896644 4.23141654 6.07793337 4.22681683 1 P 0 ;0,1=491,2=270.000000
L 6.07793337 4.22681683 6.07586713 4.22413337 1 P 0 ;0,1=491,2=270.000000
L 6.07586713 4.22413337 6.0722503 4.22298287 1 P 0 ;0,1=491,2=270.000000
L 6.0722503 4.22298287 6.06863346 4.2237501 1 P 0 ;0,1=491,2=270.000000
L 6.06863346 4.2237501 6.06605069 4.22566634 1 P 0 ;0,1=491,2=270.000000
L 6.06605069 4.22566634 6.0645 4.2283498 1 P 0 ;0,1=491,2=270.000000
L 6.0645 4.2283498 6.0645 4.23103327 1 P 0 ;0,1=491,2=270.000000
L 6.0645 4.23103327 6.06553317 4.23371673 1 P 0 ;0,1=491,2=270.000000
L 6.06553317 4.23371673 6.06811693 4.23601703 1 P 0 ;0,1=491,2=270.000000
L 6.0955 4.26049961 6.0645 4.26049961 1 P 0 ;0,1=491,2=270.000000
L 6.0645 4.26049961 6.0706997 4.2558999 1 P 0 ;0,1=491,2=270.000000
L 6.0955 4.2558999 6.0955 4.26509931 1 P 0 ;0,1=491,2=270.000000
L 6.0645 4.29149961 6.06553317 4.28843287 1 P 0 ;0,1=491,2=270.000000
L 6.06553317 4.28843287 6.06811693 4.28613337 1 P 0 ;0,1=491,2=270.000000
L 6.06811693 4.28613337 6.07121624 4.2845997 1 P 0 ;0,1=491,2=270.000000
L 6.07121624 4.2845997 6.07535059 4.2834499 1 P 0 ;0,1=491,2=270.000000
L 6.07535059 4.2834499 6.08000049 4.28306663 1 P 0 ;0,1=491,2=270.000000
L 6.08000049 4.28306663 6.08465049 4.2834499 1 P 0 ;0,1=491,2=270.000000
L 6.08465049 4.2834499 6.08878386 4.2845997 1 P 0 ;0,1=491,2=270.000000
L 6.08878386 4.2845997 6.09188415 4.28613337 1 P 0 ;0,1=491,2=270.000000
L 6.09188415 4.28613337 6.09446693 4.28843287 1 P 0 ;0,1=491,2=270.000000
L 6.09446693 4.28843287 6.0955 4.29149961 1 P 0 ;0,1=491,2=270.000000
L 6.0955 4.29149961 6.09446693 4.29456634 1 P 0 ;0,1=491,2=270.000000
L 6.09446693 4.29456634 6.09188415 4.29686654 1 P 0 ;0,1=491,2=270.000000
L 6.09188415 4.29686654 6.08878386 4.2984002 1 P 0 ;0,1=491,2=270.000000
L 6.08878386 4.2984002 6.08465049 4.29955 1 P 0 ;0,1=491,2=270.000000
L 6.08465049 4.29955 6.08000049 4.29993327 1 P 0 ;0,1=491,2=270.000000
L 6.08000049 4.29993327 6.07535059 4.29955 1 P 0 ;0,1=491,2=270.000000
L 6.07535059 4.29955 6.07121624 4.2984002 1 P 0 ;0,1=491,2=270.000000
L 6.07121624 4.2984002 6.06811693 4.29686654 1 P 0 ;0,1=491,2=270.000000
L 6.06811693 4.29686654 6.06553317 4.29456634 1 P 0 ;0,1=491,2=270.000000
L 6.06553317 4.29456634 6.0645 4.29149961 1 P 0 ;0,1=491,2=270.000000
L 5.98086663 4.20241634 5.97926644 4.20366683 1 P 0 ;0,1=22,2=0.000000
L 5.97926644 4.20366683 5.9774002 4.2045 1 P 0 ;0,1=22,2=0.000000
L 5.9774002 4.2045 5.97526683 4.2045 1 P 0 ;0,1=22,2=0.000000
L 5.97526683 4.2045 5.97286634 4.20324941 1 P 0 ;0,1=22,2=0.000000
L 5.97286634 4.20324941 5.9710001 4.20116654 1 P 0 ;0,1=22,2=0.000000
L 5.9710001 4.20116654 5.96966654 4.19866634 1 P 0 ;0,1=22,2=0.000000
L 5.96966654 4.19866634 5.96859961 4.1944998 1 P 0 ;0,1=22,2=0.000000
L 5.96859961 4.1944998 5.96833297 4.1907498 1 P 0 ;0,1=22,2=0.000000
L 5.96833297 4.1907498 5.96886673 4.1869999 1 P 0 ;0,1=22,2=0.000000
L 5.96886673 4.1869999 5.96966654 4.18449961 1 P 0 ;0,1=22,2=0.000000
L 5.96966654 4.18449961 5.97126663 4.18199941 1 P 0 ;0,1=22,2=0.000000
L 5.97126663 4.18199941 5.97313346 4.18033307 1 P 0 ;0,1=22,2=0.000000
L 5.97313346 4.18033307 5.9749997 4.1795 1 P 0 ;0,1=22,2=0.000000
L 5.9749997 4.1795 5.97686644 4.1795 1 P 0 ;0,1=22,2=0.000000
L 5.97686644 4.1795 5.97873327 4.18033307 1 P 0 ;0,1=22,2=0.000000
L 5.97873327 4.18033307 5.98033337 4.18158287 1 P 0 ;0,1=22,2=0.000000
L 5.98033337 4.18158287 5.98166693 4.18324911 1 P 0 ;0,1=22,2=0.000000
L 5.76165 4.16328996 5.81708996 4.16328996 1 P 0 
L 5.81708996 4.16328996 5.81708996 4.05325 1 P 0 
L 5.81708996 4.05325 5.76165 4.05325 1 P 0 
L 5.76165 4.05325 5.76165 4.16328996 1 P 0 
L 5.76136998 4.17026998 5.71136998 4.17026998 1 P 0 
L 5.73636998 4.14526998 5.73636998 4.19526998 1 P 0 
P 5.78936998 4.04325 3 P 0 8 0
L 5.83333297 4.1575 5.8399997 4.1825 1 P 0 ;0,1=1,2=0.000000
L 5.8399997 4.1825 5.84666693 4.1575 1 P 0 ;0,1=1,2=0.000000
L 5.84426644 4.16624961 5.83573297 4.16624961 1 P 0 ;0,1=1,2=0.000000
L 5.81086663 4.02541634 5.80926644 4.02666683 1 P 0 ;0,1=22,2=0.000000
L 5.80926644 4.02666683 5.8074002 4.0275 1 P 0 ;0,1=22,2=0.000000
L 5.8074002 4.0275 5.80526683 4.0275 1 P 0 ;0,1=22,2=0.000000
L 5.80526683 4.0275 5.80286634 4.02624941 1 P 0 ;0,1=22,2=0.000000
L 5.80286634 4.02624941 5.8010001 4.02416654 1 P 0 ;0,1=22,2=0.000000
L 5.8010001 4.02416654 5.79966654 4.02166634 1 P 0 ;0,1=22,2=0.000000
L 5.79966654 4.02166634 5.79859961 4.0174998 1 P 0 ;0,1=22,2=0.000000
L 5.79859961 4.0174998 5.79833297 4.0137498 1 P 0 ;0,1=22,2=0.000000
L 5.79833297 4.0137498 5.79886673 4.0099999 1 P 0 ;0,1=22,2=0.000000
L 5.79886673 4.0099999 5.79966654 4.00749961 1 P 0 ;0,1=22,2=0.000000
L 5.79966654 4.00749961 5.80126663 4.00499941 1 P 0 ;0,1=22,2=0.000000
L 5.80126663 4.00499941 5.80313346 4.00333307 1 P 0 ;0,1=22,2=0.000000
L 5.80313346 4.00333307 5.8049997 4.0025 1 P 0 ;0,1=22,2=0.000000
L 5.8049997 4.0025 5.80686644 4.0025 1 P 0 ;0,1=22,2=0.000000
L 5.80686644 4.0025 5.80873327 4.00333307 1 P 0 ;0,1=22,2=0.000000
L 5.80873327 4.00333307 5.81033337 4.00458287 1 P 0 ;0,1=22,2=0.000000
L 5.81033337 4.00458287 5.81166693 4.00624911 1 P 0 ;0,1=22,2=0.000000
L 5.8605 4.05056663 5.8295 4.05056663 1 P 0 ;0,1=492,2=270.000000
L 5.8295 4.05056663 5.8295 4.05823307 1 P 0 ;0,1=492,2=270.000000
L 5.8295 4.05823307 5.83105069 4.0612998 1 P 0 ;0,1=492,2=270.000000
L 5.83105069 4.0612998 5.83311693 4.0636 1 P 0 ;0,1=492,2=270.000000
L 5.83311693 4.0636 5.83621624 4.06551703 1 P 0 ;0,1=492,2=270.000000
L 5.83621624 4.06551703 5.83983406 4.06705 1 P 0 ;0,1=492,2=270.000000
L 5.83983406 4.06705 5.84500049 4.06743327 1 P 0 ;0,1=492,2=270.000000
L 5.84500049 4.06743327 5.85016703 4.06705 1 P 0 ;0,1=492,2=270.000000
L 5.85016703 4.06705 5.85378386 4.06551703 1 P 0 ;0,1=492,2=270.000000
L 5.85378386 4.06551703 5.85688415 4.0636 1 P 0 ;0,1=492,2=270.000000
L 5.85688415 4.0636 5.85895039 4.0612998 1 P 0 ;0,1=492,2=270.000000
L 5.85895039 4.0612998 5.8605 4.05823307 1 P 0 ;0,1=492,2=270.000000
L 5.8605 4.05823307 5.8605 4.05056663 1 P 0 ;0,1=492,2=270.000000
L 5.85636762 4.0819499 5.85895039 4.08501663 1 P 0 ;0,1=492,2=270.000000
L 5.85895039 4.08501663 5.8605 4.08846663 1 P 0 ;0,1=492,2=270.000000
L 5.8605 4.08846663 5.8605 4.09153327 1 P 0 ;0,1=492,2=270.000000
L 5.8605 4.09153327 5.85895039 4.0946 1 P 0 ;0,1=492,2=270.000000
L 5.85895039 4.0946 5.85636762 4.0969002 1 P 0 ;0,1=492,2=270.000000
L 5.85636762 4.0969002 5.8527498 4.09805 1 P 0 ;0,1=492,2=270.000000
L 5.8527498 4.09805 5.84913396 4.09728346 1 P 0 ;0,1=492,2=270.000000
L 5.84913396 4.09728346 5.84603366 4.09536654 1 P 0 ;0,1=492,2=270.000000
L 5.84603366 4.09536654 5.84396644 4.09191654 1 P 0 ;0,1=492,2=270.000000
L 5.84396644 4.09191654 5.84293337 4.08731683 1 P 0 ;0,1=492,2=270.000000
L 5.84293337 4.08731683 5.84086713 4.08463337 1 P 0 ;0,1=492,2=270.000000
L 5.84086713 4.08463337 5.8372503 4.08348287 1 P 0 ;0,1=492,2=270.000000
L 5.8372503 4.08348287 5.83363346 4.0842501 1 P 0 ;0,1=492,2=270.000000
L 5.83363346 4.0842501 5.83105069 4.08616634 1 P 0 ;0,1=492,2=270.000000
L 5.83105069 4.08616634 5.8295 4.0888498 1 P 0 ;0,1=492,2=270.000000
L 5.8295 4.0888498 5.8295 4.09153327 1 P 0 ;0,1=492,2=270.000000
L 5.8295 4.09153327 5.83053317 4.09421673 1 P 0 ;0,1=492,2=270.000000
L 5.83053317 4.09421673 5.83311693 4.09651703 1 P 0 ;0,1=492,2=270.000000
L 5.85585108 4.11256663 5.85843386 4.11486614 1 P 0 ;0,1=492,2=270.000000
L 5.85843386 4.11486614 5.85998346 4.11754961 1 P 0 ;0,1=492,2=270.000000
L 5.85998346 4.11754961 5.8605 4.12099961 1 P 0 ;0,1=492,2=270.000000
L 5.8605 4.12099961 5.85946693 4.1244503 1 P 0 ;0,1=492,2=270.000000
L 5.85946693 4.1244503 5.85740069 4.12713307 1 P 0 ;0,1=492,2=270.000000
L 5.85740069 4.12713307 5.85378386 4.12905 1 P 0 ;0,1=492,2=270.000000
L 5.85378386 4.12905 5.84965049 4.12943327 1 P 0 ;0,1=492,2=270.000000
L 5.84965049 4.12943327 5.84551713 4.12866673 1 P 0 ;0,1=492,2=270.000000
L 5.84551713 4.12866673 5.84293337 4.1267498 1 P 0 ;0,1=492,2=270.000000
L 5.84293337 4.1267498 5.84086713 4.12406634 1 P 0 ;0,1=492,2=270.000000
L 5.84086713 4.12406634 5.84035059 4.12138356 1 P 0 ;0,1=492,2=270.000000
L 5.84035059 4.12138356 5.84086713 4.1187001 1 P 0 ;0,1=492,2=270.000000
L 5.84086713 4.1187001 5.84293337 4.1152501 1 P 0 ;0,1=492,2=270.000000
L 5.84293337 4.1152501 5.8295 4.1163999 1 P 0 ;0,1=492,2=270.000000
L 5.8295 4.1163999 5.8295 4.1267498 1 P 0 ;0,1=492,2=270.000000
L 5.64353996 4.16328996 5.69898002 4.16328996 1 P 0 
L 5.64326004 4.17526998 5.59326004 4.17526998 1 P 0 
L 5.61826004 4.15026998 5.61826004 4.20026998 1 P 0 
L 5.69898002 4.16328996 5.69898002 4.05325 1 P 0 
L 5.69898002 4.05325 5.64353996 4.05325 1 P 0 
L 5.64353996 4.05325 5.64353996 4.16328996 1 P 0 
P 5.67125994 4.04325 3 P 0 8 0
L 5.59833297 4.1425 5.6049997 4.1675 1 P 0 ;0,1=1,2=0.000000
L 5.6049997 4.1675 5.61166693 4.1425 1 P 0 ;0,1=1,2=0.000000
L 5.60926644 4.15124961 5.60073297 4.15124961 1 P 0 ;0,1=1,2=0.000000
L 5.6275 4.05213327 5.6025 4.05213327 1 P 0 ;0,1=493,2=270.000000
L 5.6025 4.05213327 5.6025 4.05746654 1 P 0 ;0,1=493,2=270.000000
L 5.6025 4.05746654 5.60375059 4.0595999 1 P 0 ;0,1=493,2=270.000000
L 5.60375059 4.0595999 5.60541683 4.0612 1 P 0 ;0,1=493,2=270.000000
L 5.60541683 4.0612 5.60791634 4.06253356 1 P 0 ;0,1=493,2=270.000000
L 5.60791634 4.06253356 5.61083386 4.0636 1 P 0 ;0,1=493,2=270.000000
L 5.61083386 4.0636 5.61500039 4.06386663 1 P 0 ;0,1=493,2=270.000000
L 5.61500039 4.06386663 5.61916693 4.0636 1 P 0 ;0,1=493,2=270.000000
L 5.61916693 4.0636 5.62208376 4.06253356 1 P 0 ;0,1=493,2=270.000000
L 5.62208376 4.06253356 5.62458396 4.0612 1 P 0 ;0,1=493,2=270.000000
L 5.62458396 4.0612 5.6262503 4.0595999 1 P 0 ;0,1=493,2=270.000000
L 5.6262503 4.0595999 5.6275 4.05746654 1 P 0 ;0,1=493,2=270.000000
L 5.6275 4.05746654 5.6275 4.05213327 1 P 0 ;0,1=493,2=270.000000
L 5.62416742 4.0743999 5.6262503 4.07653327 1 P 0 ;0,1=493,2=270.000000
L 5.6262503 4.07653327 5.6275 4.07893327 1 P 0 ;0,1=493,2=270.000000
L 5.6275 4.07893327 5.6275 4.08106663 1 P 0 ;0,1=493,2=270.000000
L 5.6275 4.08106663 5.6262503 4.0832 1 P 0 ;0,1=493,2=270.000000
L 5.6262503 4.0832 5.62416742 4.0848001 1 P 0 ;0,1=493,2=270.000000
L 5.62416742 4.0848001 5.6212499 4.0856 1 P 0 ;0,1=493,2=270.000000
L 5.6212499 4.0856 5.61833386 4.08506673 1 P 0 ;0,1=493,2=270.000000
L 5.61833386 4.08506673 5.61583356 4.08373327 1 P 0 ;0,1=493,2=270.000000
L 5.61583356 4.08373327 5.61416654 4.08133327 1 P 0 ;0,1=493,2=270.000000
L 5.61416654 4.08133327 5.61333337 4.07813346 1 P 0 ;0,1=493,2=270.000000
L 5.61333337 4.07813346 5.61166703 4.07626663 1 P 0 ;0,1=493,2=270.000000
L 5.61166703 4.07626663 5.6087502 4.07546634 1 P 0 ;0,1=493,2=270.000000
L 5.6087502 4.07546634 5.60583346 4.0760001 1 P 0 ;0,1=493,2=270.000000
L 5.60583346 4.0760001 5.60375059 4.07733317 1 P 0 ;0,1=493,2=270.000000
L 5.60375059 4.07733317 5.6025 4.0791999 1 P 0 ;0,1=493,2=270.000000
L 5.6025 4.0791999 5.6025 4.08106663 1 P 0 ;0,1=493,2=270.000000
L 5.6025 4.08106663 5.60333317 4.08293337 1 P 0 ;0,1=493,2=270.000000
L 5.60333317 4.08293337 5.60541683 4.08453356 1 P 0 ;0,1=493,2=270.000000
L 5.6275 4.1019997 5.62708346 4.10386644 1 P 0 ;0,1=493,2=270.000000
L 5.62708346 4.10386644 5.62583376 4.1059998 1 P 0 ;0,1=493,2=270.000000
L 5.62583376 4.1059998 5.62375089 4.10733337 1 P 0 ;0,1=493,2=270.000000
L 5.62375089 4.10733337 5.62083327 4.10786663 1 P 0 ;0,1=493,2=270.000000
L 5.62083327 4.10786663 5.61791722 4.10733337 1 P 0 ;0,1=493,2=270.000000
L 5.61791722 4.10733337 5.61541703 4.10573327 1 P 0 ;0,1=493,2=270.000000
L 5.61541703 4.10573327 5.61416654 4.10333327 1 P 0 ;0,1=493,2=270.000000
L 5.61416654 4.10333327 5.61416654 4.10066663 1 P 0 ;0,1=493,2=270.000000
L 5.61416654 4.10066663 5.61333337 4.09906654 1 P 0 ;0,1=493,2=270.000000
L 5.61333337 4.09906654 5.61125049 4.09773297 1 P 0 ;0,1=493,2=270.000000
L 5.61125049 4.09773297 5.60833366 4.0971998 1 P 0 ;0,1=493,2=270.000000
L 5.60833366 4.0971998 5.60541683 4.0980001 1 P 0 ;0,1=493,2=270.000000
L 5.60541683 4.0980001 5.60333317 4.09986634 1 P 0 ;0,1=493,2=270.000000
L 5.60333317 4.09986634 5.6025 4.1019997 1 P 0 ;0,1=493,2=270.000000
L 5.6025 4.1019997 5.60333317 4.10413307 1 P 0 ;0,1=493,2=270.000000
L 5.60333317 4.10413307 5.60541683 4.1059998 1 P 0 ;0,1=493,2=270.000000
L 5.60541683 4.1059998 5.60833366 4.1068001 1 P 0 ;0,1=493,2=270.000000
L 5.60833366 4.1068001 5.61125049 4.10626644 1 P 0 ;0,1=493,2=270.000000
L 5.61125049 4.10626644 5.61333337 4.10493337 1 P 0 ;0,1=493,2=270.000000
L 5.61333337 4.10493337 5.61416654 4.10333327 1 P 0 ;0,1=493,2=270.000000
L 5.61416654 4.10333327 5.61416654 4.10066663 1 P 0 ;0,1=493,2=270.000000
L 5.61416654 4.10066663 5.61541703 4.09826663 1 P 0 ;0,1=493,2=270.000000
L 5.61541703 4.09826663 5.61791722 4.09666654 1 P 0 ;0,1=493,2=270.000000
L 5.61791722 4.09666654 5.62083327 4.09613327 1 P 0 ;0,1=493,2=270.000000
L 5.62083327 4.09613327 5.62375089 4.09666654 1 P 0 ;0,1=493,2=270.000000
L 5.62375089 4.09666654 5.62583376 4.0980001 1 P 0 ;0,1=493,2=270.000000
L 5.62583376 4.0980001 5.62708346 4.10013346 1 P 0 ;0,1=493,2=270.000000
L 5.62708346 4.10013346 5.6275 4.1019997 1 P 0 ;0,1=493,2=270.000000
L 5.71586663 4.02541634 5.71426644 4.02666683 1 P 0 ;0,1=22,2=0.000000
L 5.71426644 4.02666683 5.7124002 4.0275 1 P 0 ;0,1=22,2=0.000000
L 5.7124002 4.0275 5.71026683 4.0275 1 P 0 ;0,1=22,2=0.000000
L 5.71026683 4.0275 5.70786634 4.02624941 1 P 0 ;0,1=22,2=0.000000
L 5.70786634 4.02624941 5.7060001 4.02416654 1 P 0 ;0,1=22,2=0.000000
L 5.7060001 4.02416654 5.70466654 4.02166634 1 P 0 ;0,1=22,2=0.000000
L 5.70466654 4.02166634 5.70359961 4.0174998 1 P 0 ;0,1=22,2=0.000000
L 5.70359961 4.0174998 5.70333297 4.0137498 1 P 0 ;0,1=22,2=0.000000
L 5.70333297 4.0137498 5.70386673 4.0099999 1 P 0 ;0,1=22,2=0.000000
L 5.70386673 4.0099999 5.70466654 4.00749961 1 P 0 ;0,1=22,2=0.000000
L 5.70466654 4.00749961 5.70626663 4.00499941 1 P 0 ;0,1=22,2=0.000000
L 5.70626663 4.00499941 5.70813346 4.00333307 1 P 0 ;0,1=22,2=0.000000
L 5.70813346 4.00333307 5.7099997 4.0025 1 P 0 ;0,1=22,2=0.000000
L 5.7099997 4.0025 5.71186644 4.0025 1 P 0 ;0,1=22,2=0.000000
L 5.71186644 4.0025 5.71373327 4.00333307 1 P 0 ;0,1=22,2=0.000000
L 5.71373327 4.00333307 5.71533337 4.00458287 1 P 0 ;0,1=22,2=0.000000
L 5.71533337 4.00458287 5.71666693 4.00624911 1 P 0 ;0,1=22,2=0.000000
L 5.58086998 4.30108002 5.58086998 4.19103996 1 P 0 
L 5.52543002 4.30108002 5.58086998 4.30108002 1 P 0 
L 5.51015 4.29806004 5.51015 4.34806004 1 P 0 
L 5.53515 4.32306004 5.48515 4.32306004 1 P 0 
L 5.58086998 4.19103996 5.52543002 4.19103996 1 P 0 
L 5.52543002 4.19103996 5.52543002 4.30108002 1 P 0 
P 5.55315 4.18103996 3 P 0 8 0
L 5.57333297 4.3075 5.5799997 4.3325 1 P 0 ;0,1=1,2=0.000000
L 5.5799997 4.3325 5.58666693 4.3075 1 P 0 ;0,1=1,2=0.000000
L 5.58426644 4.31624961 5.57573297 4.31624961 1 P 0 ;0,1=1,2=0.000000
L 5.49586663 4.20041634 5.49426644 4.20166683 1 P 0 ;0,1=22,2=0.000000
L 5.49426644 4.20166683 5.4924002 4.2025 1 P 0 ;0,1=22,2=0.000000
L 5.4924002 4.2025 5.49026683 4.2025 1 P 0 ;0,1=22,2=0.000000
L 5.49026683 4.2025 5.48786634 4.20124941 1 P 0 ;0,1=22,2=0.000000
L 5.48786634 4.20124941 5.4860001 4.19916654 1 P 0 ;0,1=22,2=0.000000
L 5.4860001 4.19916654 5.48466654 4.19666634 1 P 0 ;0,1=22,2=0.000000
L 5.48466654 4.19666634 5.48359961 4.1924998 1 P 0 ;0,1=22,2=0.000000
L 5.48359961 4.1924998 5.48333297 4.1887498 1 P 0 ;0,1=22,2=0.000000
L 5.48333297 4.1887498 5.48386673 4.1849999 1 P 0 ;0,1=22,2=0.000000
L 5.48386673 4.1849999 5.48466654 4.18249961 1 P 0 ;0,1=22,2=0.000000
L 5.48466654 4.18249961 5.48626663 4.17999941 1 P 0 ;0,1=22,2=0.000000
L 5.48626663 4.17999941 5.48813346 4.17833307 1 P 0 ;0,1=22,2=0.000000
L 5.48813346 4.17833307 5.4899997 4.1775 1 P 0 ;0,1=22,2=0.000000
L 5.4899997 4.1775 5.49186644 4.1775 1 P 0 ;0,1=22,2=0.000000
L 5.49186644 4.1775 5.49373327 4.17833307 1 P 0 ;0,1=22,2=0.000000
L 5.49373327 4.17833307 5.49533337 4.17958287 1 P 0 ;0,1=22,2=0.000000
L 5.49533337 4.17958287 5.49666693 4.18124911 1 P 0 ;0,1=22,2=0.000000
L 5.5105 4.21713327 5.4855 4.21713327 1 P 0 ;0,1=494,2=270.000000
L 5.4855 4.21713327 5.4855 4.22246654 1 P 0 ;0,1=494,2=270.000000
L 5.4855 4.22246654 5.48675059 4.2245999 1 P 0 ;0,1=494,2=270.000000
L 5.48675059 4.2245999 5.48841683 4.2262 1 P 0 ;0,1=494,2=270.000000
L 5.48841683 4.2262 5.49091634 4.22753356 1 P 0 ;0,1=494,2=270.000000
L 5.49091634 4.22753356 5.49383386 4.2286 1 P 0 ;0,1=494,2=270.000000
L 5.49383386 4.2286 5.49800039 4.22886663 1 P 0 ;0,1=494,2=270.000000
L 5.49800039 4.22886663 5.50216693 4.2286 1 P 0 ;0,1=494,2=270.000000
L 5.50216693 4.2286 5.50508376 4.22753356 1 P 0 ;0,1=494,2=270.000000
L 5.50508376 4.22753356 5.50758396 4.2262 1 P 0 ;0,1=494,2=270.000000
L 5.50758396 4.2262 5.5092503 4.2245999 1 P 0 ;0,1=494,2=270.000000
L 5.5092503 4.2245999 5.5105 4.22246654 1 P 0 ;0,1=494,2=270.000000
L 5.5105 4.22246654 5.5105 4.21713327 1 P 0 ;0,1=494,2=270.000000
L 5.50716742 4.2393999 5.5092503 4.24153327 1 P 0 ;0,1=494,2=270.000000
L 5.5092503 4.24153327 5.5105 4.24393327 1 P 0 ;0,1=494,2=270.000000
L 5.5105 4.24393327 5.5105 4.24606663 1 P 0 ;0,1=494,2=270.000000
L 5.5105 4.24606663 5.5092503 4.2482 1 P 0 ;0,1=494,2=270.000000
L 5.5092503 4.2482 5.50716742 4.2498001 1 P 0 ;0,1=494,2=270.000000
L 5.50716742 4.2498001 5.5042499 4.2506 1 P 0 ;0,1=494,2=270.000000
L 5.5042499 4.2506 5.50133386 4.25006673 1 P 0 ;0,1=494,2=270.000000
L 5.50133386 4.25006673 5.49883356 4.24873327 1 P 0 ;0,1=494,2=270.000000
L 5.49883356 4.24873327 5.49716654 4.24633327 1 P 0 ;0,1=494,2=270.000000
L 5.49716654 4.24633327 5.49633337 4.24313346 1 P 0 ;0,1=494,2=270.000000
L 5.49633337 4.24313346 5.49466703 4.24126663 1 P 0 ;0,1=494,2=270.000000
L 5.49466703 4.24126663 5.4917502 4.24046634 1 P 0 ;0,1=494,2=270.000000
L 5.4917502 4.24046634 5.48883346 4.2410001 1 P 0 ;0,1=494,2=270.000000
L 5.48883346 4.2410001 5.48675059 4.24233317 1 P 0 ;0,1=494,2=270.000000
L 5.48675059 4.24233317 5.4855 4.2441999 1 P 0 ;0,1=494,2=270.000000
L 5.4855 4.2441999 5.4855 4.24606663 1 P 0 ;0,1=494,2=270.000000
L 5.4855 4.24606663 5.48633317 4.24793337 1 P 0 ;0,1=494,2=270.000000
L 5.48633317 4.24793337 5.48841683 4.24953356 1 P 0 ;0,1=494,2=270.000000
L 5.48966663 4.26193317 5.48716713 4.26353327 1 P 0 ;0,1=494,2=270.000000
L 5.48716713 4.26353327 5.48591663 4.2654 1 P 0 ;0,1=494,2=270.000000
L 5.48591663 4.2654 5.4855 4.26753337 1 P 0 ;0,1=494,2=270.000000
L 5.4855 4.26753337 5.48633317 4.2702 1 P 0 ;0,1=494,2=270.000000
L 5.48633317 4.2702 5.48841683 4.27206673 1 P 0 ;0,1=494,2=270.000000
L 5.48841683 4.27206673 5.49091634 4.2726 1 P 0 ;0,1=494,2=270.000000
L 5.49091634 4.2726 5.49341732 4.27233337 1 P 0 ;0,1=494,2=270.000000
L 5.49341732 4.27233337 5.4955002 4.27126644 1 P 0 ;0,1=494,2=270.000000
L 5.4955002 4.27126644 5.49966673 4.26593327 1 P 0 ;0,1=494,2=270.000000
L 5.49966673 4.26593327 5.50258356 4.26353327 1 P 0 ;0,1=494,2=270.000000
L 5.50258356 4.26353327 5.50675089 4.26193317 1 P 0 ;0,1=494,2=270.000000
L 5.50675089 4.26193317 5.5105 4.2613999 1 P 0 ;0,1=494,2=270.000000
L 5.5105 4.2613999 5.5105 4.2726 1 P 0 ;0,1=494,2=270.000000
L 0.52643002 1.5875 0.52643002 1.5525 1 P 0 
L 0.52643002 1.5525 0.47356998 1.5525 1 P 0 
L 0.47356998 1.5525 0.47356998 1.5875 1 P 0 
L 0.47356998 1.5875 0.52643002 1.5875 1 P 0 
L 0.51286663 1.54041634 0.51126644 1.54166683 1 P 0 ;0,1=495,2=0.000000
L 0.51126644 1.54166683 0.5094002 1.5425 1 P 0 ;0,1=495,2=0.000000
L 0.5094002 1.5425 0.50726683 1.5425 1 P 0 ;0,1=495,2=0.000000
L 0.50726683 1.5425 0.50486634 1.54124941 1 P 0 ;0,1=495,2=0.000000
L 0.50486634 1.54124941 0.5030001 1.53916654 1 P 0 ;0,1=495,2=0.000000
L 0.5030001 1.53916654 0.50166654 1.53666634 1 P 0 ;0,1=495,2=0.000000
L 0.50166654 1.53666634 0.50059961 1.5324998 1 P 0 ;0,1=495,2=0.000000
L 0.50059961 1.5324998 0.50033297 1.5287498 1 P 0 ;0,1=495,2=0.000000
L 0.50033297 1.5287498 0.50086673 1.5249999 1 P 0 ;0,1=495,2=0.000000
L 0.50086673 1.5249999 0.50166654 1.52249961 1 P 0 ;0,1=495,2=0.000000
L 0.50166654 1.52249961 0.50326663 1.51999941 1 P 0 ;0,1=495,2=0.000000
L 0.50326663 1.51999941 0.50513346 1.51833307 1 P 0 ;0,1=495,2=0.000000
L 0.50513346 1.51833307 0.5069997 1.5175 1 P 0 ;0,1=495,2=0.000000
L 0.5069997 1.5175 0.50886644 1.5175 1 P 0 ;0,1=495,2=0.000000
L 0.50886644 1.5175 0.51073327 1.51833307 1 P 0 ;0,1=495,2=0.000000
L 0.51073327 1.51833307 0.51233337 1.51958287 1 P 0 ;0,1=495,2=0.000000
L 0.51233337 1.51958287 0.51366693 1.52124911 1 P 0 ;0,1=495,2=0.000000
L 0.52313327 1.52249961 0.52473297 1.51958287 1 P 0 ;0,1=495,2=0.000000
L 0.52473297 1.51958287 0.52686634 1.51791654 1 P 0 ;0,1=495,2=0.000000
L 0.52686634 1.51791654 0.52926683 1.5175 1 P 0 ;0,1=495,2=0.000000
L 0.52926683 1.5175 0.5314002 1.51791654 1 P 0 ;0,1=495,2=0.000000
L 0.5314002 1.51791654 0.53353356 1.51999941 1 P 0 ;0,1=495,2=0.000000
L 0.53353356 1.51999941 0.53486663 1.52249961 1 P 0 ;0,1=495,2=0.000000
L 0.53486663 1.52249961 0.53513317 1.5249999 1 P 0 ;0,1=495,2=0.000000
L 0.53513317 1.5249999 0.5346 1.52791594 1 P 0 ;0,1=495,2=0.000000
L 0.5346 1.52791594 0.53273327 1.52999961 1 P 0 ;0,1=495,2=0.000000
L 0.53273327 1.52999961 0.53086644 1.53083346 1 P 0 ;0,1=495,2=0.000000
L 0.53086644 1.53083346 0.52846654 1.53083346 1 P 0 ;0,1=495,2=0.000000
L 0.53086644 1.53083346 0.53246663 1.53208327 1 P 0 ;0,1=495,2=0.000000
L 0.53246663 1.53208327 0.5338001 1.53416614 1 P 0 ;0,1=495,2=0.000000
L 0.5338001 1.53416614 0.53433337 1.53666634 1 P 0 ;0,1=495,2=0.000000
L 0.53433337 1.53666634 0.5338001 1.53916654 1 P 0 ;0,1=495,2=0.000000
L 0.5338001 1.53916654 0.53246663 1.54124941 1 P 0 ;0,1=495,2=0.000000
L 0.53246663 1.54124941 0.53006663 1.5425 1 P 0 ;0,1=495,2=0.000000
L 0.53006663 1.5425 0.52766663 1.54208337 1 P 0 ;0,1=495,2=0.000000
L 0.52766663 1.54208337 0.52526663 1.54041634 1 P 0 ;0,1=495,2=0.000000
L 0.5509997 1.5175 0.5509997 1.5425 1 P 0 ;0,1=495,2=0.000000
L 0.5509997 1.5425 0.5477999 1.5375003 1 P 0 ;0,1=495,2=0.000000
L 0.5477999 1.5175 0.55419951 1.5175 1 P 0 ;0,1=495,2=0.000000
L 0.5729997 1.5425 0.57086634 1.54166683 1 P 0 ;0,1=495,2=0.000000
L 0.57086634 1.54166683 0.56926663 1.53958317 1 P 0 ;0,1=495,2=0.000000
L 0.56926663 1.53958317 0.5681998 1.53708366 1 P 0 ;0,1=495,2=0.000000
L 0.5681998 1.53708366 0.5673999 1.53374951 1 P 0 ;0,1=495,2=0.000000
L 0.5673999 1.53374951 0.56713327 1.52999961 1 P 0 ;0,1=495,2=0.000000
L 0.56713327 1.52999961 0.5673999 1.52624961 1 P 0 ;0,1=495,2=0.000000
L 0.5673999 1.52624961 0.5681998 1.52291624 1 P 0 ;0,1=495,2=0.000000
L 0.5681998 1.52291624 0.56926663 1.52041604 1 P 0 ;0,1=495,2=0.000000
L 0.56926663 1.52041604 0.57086634 1.51833307 1 P 0 ;0,1=495,2=0.000000
L 0.57086634 1.51833307 0.5729997 1.5175 1 P 0 ;0,1=495,2=0.000000
L 0.5729997 1.5175 0.57513307 1.51833307 1 P 0 ;0,1=495,2=0.000000
L 0.57513307 1.51833307 0.57673327 1.52041604 1 P 0 ;0,1=495,2=0.000000
L 0.57673327 1.52041604 0.5778001 1.52291624 1 P 0 ;0,1=495,2=0.000000
L 0.5778001 1.52291624 0.5786 1.52624961 1 P 0 ;0,1=495,2=0.000000
L 0.5786 1.52624961 0.57886663 1.52999961 1 P 0 ;0,1=495,2=0.000000
L 0.57886663 1.52999961 0.5786 1.53374951 1 P 0 ;0,1=495,2=0.000000
L 0.5786 1.53374951 0.5778001 1.53708366 1 P 0 ;0,1=495,2=0.000000
L 0.5778001 1.53708366 0.57673327 1.53958317 1 P 0 ;0,1=495,2=0.000000
L 0.57673327 1.53958317 0.57513307 1.54166683 1 P 0 ;0,1=495,2=0.000000
L 0.57513307 1.54166683 0.5729997 1.5425 1 P 0 ;0,1=495,2=0.000000
L 0.54043002 1.0175 0.54043002 0.9825 1 P 0 
L 0.48756998 0.9825 0.48756998 1.0175 1 P 0 
L 0.48756998 1.0175 0.54043002 1.0175 1 P 0 
L 0.54043002 0.9825 0.48756998 0.9825 1 P 0 
L 0.37193327 1.01291624 0.36963307 1.01446683 1 P 0 ;0,1=496,2=0.000000
L 0.36963307 1.01446683 0.3669503 1.0155 1 P 0 ;0,1=496,2=0.000000
L 0.3669503 1.0155 0.36388356 1.0155 1 P 0 ;0,1=496,2=0.000000
L 0.36388356 1.0155 0.36043287 1.01394931 1 P 0 ;0,1=496,2=0.000000
L 0.36043287 1.01394931 0.3577501 1.01136654 1 P 0 ;0,1=496,2=0.000000
L 0.3577501 1.01136654 0.35583317 1.00826624 1 P 0 ;0,1=496,2=0.000000
L 0.35583317 1.00826624 0.35429951 1.0030998 1 P 0 ;0,1=496,2=0.000000
L 0.35429951 1.0030998 0.35391624 0.9984498 1 P 0 ;0,1=496,2=0.000000
L 0.35391624 0.9984498 0.35468337 0.9937999 1 P 0 ;0,1=496,2=0.000000
L 0.35468337 0.9937999 0.35583317 0.99069961 1 P 0 ;0,1=496,2=0.000000
L 0.35583317 0.99069961 0.35813337 0.98759931 1 P 0 ;0,1=496,2=0.000000
L 0.35813337 0.98759931 0.36081683 0.98553307 1 P 0 ;0,1=496,2=0.000000
L 0.36081683 0.98553307 0.36349961 0.9845 1 P 0 ;0,1=496,2=0.000000
L 0.36349961 0.9845 0.36618307 0.9845 1 P 0 ;0,1=496,2=0.000000
L 0.36618307 0.9845 0.36886654 0.98553307 1 P 0 ;0,1=496,2=0.000000
L 0.36886654 0.98553307 0.37116673 0.98708278 1 P 0 ;0,1=496,2=0.000000
L 0.37116673 0.98708278 0.37308366 0.98914892 1 P 0 ;0,1=496,2=0.000000
L 0.38606663 0.99069961 0.38836614 0.98708278 1 P 0 ;0,1=496,2=0.000000
L 0.38836614 0.98708278 0.39143287 0.98501654 1 P 0 ;0,1=496,2=0.000000
L 0.39143287 0.98501654 0.39488356 0.9845 1 P 0 ;0,1=496,2=0.000000
L 0.39488356 0.9845 0.3979503 0.98501654 1 P 0 ;0,1=496,2=0.000000
L 0.3979503 0.98501654 0.40101703 0.98759931 1 P 0 ;0,1=496,2=0.000000
L 0.40101703 0.98759931 0.40293327 0.99069961 1 P 0 ;0,1=496,2=0.000000
L 0.40293327 0.99069961 0.40331654 0.9937999 1 P 0 ;0,1=496,2=0.000000
L 0.40331654 0.9937999 0.40255 0.99741575 1 P 0 ;0,1=496,2=0.000000
L 0.40255 0.99741575 0.39986654 0.99999951 1 P 0 ;0,1=496,2=0.000000
L 0.39986654 0.99999951 0.39718307 1.00103356 1 P 0 ;0,1=496,2=0.000000
L 0.39718307 1.00103356 0.39373307 1.00103356 1 P 0 ;0,1=496,2=0.000000
L 0.39718307 1.00103356 0.39948327 1.00258317 1 P 0 ;0,1=496,2=0.000000
L 0.39948327 1.00258317 0.4014002 1.00516594 1 P 0 ;0,1=496,2=0.000000
L 0.4014002 1.00516594 0.40216673 1.00826624 1 P 0 ;0,1=496,2=0.000000
L 0.40216673 1.00826624 0.4014002 1.01136654 1 P 0 ;0,1=496,2=0.000000
L 0.4014002 1.01136654 0.39948327 1.01394931 1 P 0 ;0,1=496,2=0.000000
L 0.39948327 1.01394931 0.39603327 1.0155 1 P 0 ;0,1=496,2=0.000000
L 0.39603327 1.0155 0.39258337 1.01498337 1 P 0 ;0,1=496,2=0.000000
L 0.39258337 1.01498337 0.38913337 1.01291624 1 P 0 ;0,1=496,2=0.000000
L 0.42549961 0.9845 0.42549961 1.0155 1 P 0 ;0,1=496,2=0.000000
L 0.42549961 1.0155 0.4208999 1.0093003 1 P 0 ;0,1=496,2=0.000000
L 0.4208999 0.9845 0.43009931 0.9845 1 P 0 ;0,1=496,2=0.000000
L 0.45649961 0.9845 0.45649961 1.0155 1 P 0 ;0,1=496,2=0.000000
L 0.45649961 1.0155 0.4518999 1.0093003 1 P 0 ;0,1=496,2=0.000000
L 0.4518999 0.9845 0.46109931 0.9845 1 P 0 ;0,1=496,2=0.000000
L 0.53343002 2.6975 0.53343002 2.6625 1 P 0 
L 0.48056998 2.6975 0.53343002 2.6975 1 P 0 
L 0.48056998 2.6625 0.48056998 2.6975 1 P 0 
L 0.53343002 2.6625 0.48056998 2.6625 1 P 0 
L 0.48193327 2.91791624 0.47963307 2.91946683 1 P 0 ;0,1=497,2=0.000000
L 0.47963307 2.91946683 0.4769503 2.9205 1 P 0 ;0,1=497,2=0.000000
L 0.4769503 2.9205 0.47388356 2.9205 1 P 0 ;0,1=497,2=0.000000
L 0.47388356 2.9205 0.47043287 2.91894931 1 P 0 ;0,1=497,2=0.000000
L 0.47043287 2.91894931 0.4677501 2.91636654 1 P 0 ;0,1=497,2=0.000000
L 0.4677501 2.91636654 0.46583317 2.91326624 1 P 0 ;0,1=497,2=0.000000
L 0.46583317 2.91326624 0.46429951 2.9080998 1 P 0 ;0,1=497,2=0.000000
L 0.46429951 2.9080998 0.46391624 2.9034498 1 P 0 ;0,1=497,2=0.000000
L 0.46391624 2.9034498 0.46468337 2.8987999 1 P 0 ;0,1=497,2=0.000000
L 0.46468337 2.8987999 0.46583317 2.89569961 1 P 0 ;0,1=497,2=0.000000
L 0.46583317 2.89569961 0.46813337 2.89259931 1 P 0 ;0,1=497,2=0.000000
L 0.46813337 2.89259931 0.47081683 2.89053307 1 P 0 ;0,1=497,2=0.000000
L 0.47081683 2.89053307 0.47349961 2.8895 1 P 0 ;0,1=497,2=0.000000
L 0.47349961 2.8895 0.47618307 2.8895 1 P 0 ;0,1=497,2=0.000000
L 0.47618307 2.8895 0.47886654 2.89053307 1 P 0 ;0,1=497,2=0.000000
L 0.47886654 2.89053307 0.48116673 2.89208278 1 P 0 ;0,1=497,2=0.000000
L 0.48116673 2.89208278 0.48308366 2.89414892 1 P 0 ;0,1=497,2=0.000000
L 0.49606663 2.89569961 0.49836614 2.89208278 1 P 0 ;0,1=497,2=0.000000
L 0.49836614 2.89208278 0.50143287 2.89001654 1 P 0 ;0,1=497,2=0.000000
L 0.50143287 2.89001654 0.50488356 2.8895 1 P 0 ;0,1=497,2=0.000000
L 0.50488356 2.8895 0.5079503 2.89001654 1 P 0 ;0,1=497,2=0.000000
L 0.5079503 2.89001654 0.51101703 2.89259931 1 P 0 ;0,1=497,2=0.000000
L 0.51101703 2.89259931 0.51293327 2.89569961 1 P 0 ;0,1=497,2=0.000000
L 0.51293327 2.89569961 0.51331654 2.8987999 1 P 0 ;0,1=497,2=0.000000
L 0.51331654 2.8987999 0.51255 2.90241575 1 P 0 ;0,1=497,2=0.000000
L 0.51255 2.90241575 0.50986654 2.90499951 1 P 0 ;0,1=497,2=0.000000
L 0.50986654 2.90499951 0.50718307 2.90603356 1 P 0 ;0,1=497,2=0.000000
L 0.50718307 2.90603356 0.50373307 2.90603356 1 P 0 ;0,1=497,2=0.000000
L 0.50718307 2.90603356 0.50948327 2.90758317 1 P 0 ;0,1=497,2=0.000000
L 0.50948327 2.90758317 0.5114002 2.91016594 1 P 0 ;0,1=497,2=0.000000
L 0.5114002 2.91016594 0.51216673 2.91326624 1 P 0 ;0,1=497,2=0.000000
L 0.51216673 2.91326624 0.5114002 2.91636654 1 P 0 ;0,1=497,2=0.000000
L 0.5114002 2.91636654 0.50948327 2.91894931 1 P 0 ;0,1=497,2=0.000000
L 0.50948327 2.91894931 0.50603327 2.9205 1 P 0 ;0,1=497,2=0.000000
L 0.50603327 2.9205 0.50258337 2.91998337 1 P 0 ;0,1=497,2=0.000000
L 0.50258337 2.91998337 0.49913337 2.91791624 1 P 0 ;0,1=497,2=0.000000
L 0.53549961 2.8895 0.53549961 2.9205 1 P 0 ;0,1=497,2=0.000000
L 0.53549961 2.9205 0.5308999 2.9143003 1 P 0 ;0,1=497,2=0.000000
L 0.5308999 2.8895 0.54009931 2.8895 1 P 0 ;0,1=497,2=0.000000
L 0.56573307 2.8895 0.56649961 2.89621614 1 P 0 ;0,1=497,2=0.000000
L 0.56649961 2.89621614 0.5676501 2.90189921 1 P 0 ;0,1=497,2=0.000000
L 0.5676501 2.90189921 0.56918307 2.90706663 1 P 0 ;0,1=497,2=0.000000
L 0.56918307 2.90706663 0.5711 2.9127497 1 P 0 ;0,1=497,2=0.000000
L 0.5711 2.9127497 0.57416673 2.9205 1 P 0 ;0,1=497,2=0.000000
L 0.57416673 2.9205 0.55883317 2.9205 1 P 0 ;0,1=497,2=0.000000
L 0.53243002 2.1835 0.53243002 2.1485 1 P 0 
L 0.47956998 2.1835 0.53243002 2.1835 1 P 0 
L 0.53243002 2.1485 0.47956998 2.1485 1 P 0 
L 0.47956998 2.1485 0.47956998 2.1835 1 P 0 
L 0.38193327 2.17291624 0.37963307 2.17446683 1 P 0 ;0,1=498,2=0.000000
L 0.37963307 2.17446683 0.3769503 2.1755 1 P 0 ;0,1=498,2=0.000000
L 0.3769503 2.1755 0.37388356 2.1755 1 P 0 ;0,1=498,2=0.000000
L 0.37388356 2.1755 0.37043287 2.17394931 1 P 0 ;0,1=498,2=0.000000
L 0.37043287 2.17394931 0.3677501 2.17136654 1 P 0 ;0,1=498,2=0.000000
L 0.3677501 2.17136654 0.36583317 2.16826624 1 P 0 ;0,1=498,2=0.000000
L 0.36583317 2.16826624 0.36429951 2.1630998 1 P 0 ;0,1=498,2=0.000000
L 0.36429951 2.1630998 0.36391624 2.1584498 1 P 0 ;0,1=498,2=0.000000
L 0.36391624 2.1584498 0.36468337 2.1537999 1 P 0 ;0,1=498,2=0.000000
L 0.36468337 2.1537999 0.36583317 2.15069961 1 P 0 ;0,1=498,2=0.000000
L 0.36583317 2.15069961 0.36813337 2.14759931 1 P 0 ;0,1=498,2=0.000000
L 0.36813337 2.14759931 0.37081683 2.14553307 1 P 0 ;0,1=498,2=0.000000
L 0.37081683 2.14553307 0.37349961 2.1445 1 P 0 ;0,1=498,2=0.000000
L 0.37349961 2.1445 0.37618307 2.1445 1 P 0 ;0,1=498,2=0.000000
L 0.37618307 2.1445 0.37886654 2.14553307 1 P 0 ;0,1=498,2=0.000000
L 0.37886654 2.14553307 0.38116673 2.14708278 1 P 0 ;0,1=498,2=0.000000
L 0.38116673 2.14708278 0.38308366 2.14914892 1 P 0 ;0,1=498,2=0.000000
L 0.39606663 2.15069961 0.39836614 2.14708278 1 P 0 ;0,1=498,2=0.000000
L 0.39836614 2.14708278 0.40143287 2.14501654 1 P 0 ;0,1=498,2=0.000000
L 0.40143287 2.14501654 0.40488356 2.1445 1 P 0 ;0,1=498,2=0.000000
L 0.40488356 2.1445 0.4079503 2.14501654 1 P 0 ;0,1=498,2=0.000000
L 0.4079503 2.14501654 0.41101703 2.14759931 1 P 0 ;0,1=498,2=0.000000
L 0.41101703 2.14759931 0.41293327 2.15069961 1 P 0 ;0,1=498,2=0.000000
L 0.41293327 2.15069961 0.41331654 2.1537999 1 P 0 ;0,1=498,2=0.000000
L 0.41331654 2.1537999 0.41255 2.15741575 1 P 0 ;0,1=498,2=0.000000
L 0.41255 2.15741575 0.40986654 2.15999951 1 P 0 ;0,1=498,2=0.000000
L 0.40986654 2.15999951 0.40718307 2.16103356 1 P 0 ;0,1=498,2=0.000000
L 0.40718307 2.16103356 0.40373307 2.16103356 1 P 0 ;0,1=498,2=0.000000
L 0.40718307 2.16103356 0.40948327 2.16258317 1 P 0 ;0,1=498,2=0.000000
L 0.40948327 2.16258317 0.4114002 2.16516594 1 P 0 ;0,1=498,2=0.000000
L 0.4114002 2.16516594 0.41216673 2.16826624 1 P 0 ;0,1=498,2=0.000000
L 0.41216673 2.16826624 0.4114002 2.17136654 1 P 0 ;0,1=498,2=0.000000
L 0.4114002 2.17136654 0.40948327 2.17394931 1 P 0 ;0,1=498,2=0.000000
L 0.40948327 2.17394931 0.40603327 2.1755 1 P 0 ;0,1=498,2=0.000000
L 0.40603327 2.1755 0.40258337 2.17498337 1 P 0 ;0,1=498,2=0.000000
L 0.40258337 2.17498337 0.39913337 2.17291624 1 P 0 ;0,1=498,2=0.000000
L 0.43549961 2.1445 0.43549961 2.1755 1 P 0 ;0,1=498,2=0.000000
L 0.43549961 2.1755 0.4308999 2.1693003 1 P 0 ;0,1=498,2=0.000000
L 0.4308999 2.1445 0.44009931 2.1445 1 P 0 ;0,1=498,2=0.000000
L 0.46649961 2.1445 0.46918307 2.14501654 1 P 0 ;0,1=498,2=0.000000
L 0.46918307 2.14501654 0.4722498 2.14656614 1 P 0 ;0,1=498,2=0.000000
L 0.4722498 2.14656614 0.47416673 2.14914892 1 P 0 ;0,1=498,2=0.000000
L 0.47416673 2.14914892 0.47493327 2.15276673 1 P 0 ;0,1=498,2=0.000000
L 0.47493327 2.15276673 0.47416673 2.15638268 1 P 0 ;0,1=498,2=0.000000
L 0.47416673 2.15638268 0.47186654 2.15948287 1 P 0 ;0,1=498,2=0.000000
L 0.47186654 2.15948287 0.46841654 2.16103356 1 P 0 ;0,1=498,2=0.000000
L 0.46841654 2.16103356 0.46458337 2.16103356 1 P 0 ;0,1=498,2=0.000000
L 0.46458337 2.16103356 0.46228317 2.16206663 1 P 0 ;0,1=498,2=0.000000
L 0.46228317 2.16206663 0.46036614 2.16464941 1 P 0 ;0,1=498,2=0.000000
L 0.46036614 2.16464941 0.4595997 2.16826624 1 P 0 ;0,1=498,2=0.000000
L 0.4595997 2.16826624 0.4607501 2.17188307 1 P 0 ;0,1=498,2=0.000000
L 0.4607501 2.17188307 0.46343287 2.17446683 1 P 0 ;0,1=498,2=0.000000
L 0.46343287 2.17446683 0.46649961 2.1755 1 P 0 ;0,1=498,2=0.000000
L 0.46649961 2.1755 0.46956634 2.17446683 1 P 0 ;0,1=498,2=0.000000
L 0.46956634 2.17446683 0.4722498 2.17188307 1 P 0 ;0,1=498,2=0.000000
L 0.4722498 2.17188307 0.4734002 2.16826624 1 P 0 ;0,1=498,2=0.000000
L 0.4734002 2.16826624 0.47263307 2.16464941 1 P 0 ;0,1=498,2=0.000000
L 0.47263307 2.16464941 0.47071673 2.16206663 1 P 0 ;0,1=498,2=0.000000
L 0.47071673 2.16206663 0.46841654 2.16103356 1 P 0 ;0,1=498,2=0.000000
L 0.46841654 2.16103356 0.46458337 2.16103356 1 P 0 ;0,1=498,2=0.000000
L 0.46458337 2.16103356 0.46113337 2.15948287 1 P 0 ;0,1=498,2=0.000000
L 0.46113337 2.15948287 0.45883317 2.15638268 1 P 0 ;0,1=498,2=0.000000
L 0.45883317 2.15638268 0.45806663 2.15276673 1 P 0 ;0,1=498,2=0.000000
L 0.45806663 2.15276673 0.45883317 2.14914892 1 P 0 ;0,1=498,2=0.000000
L 0.45883317 2.14914892 0.4607501 2.14656614 1 P 0 ;0,1=498,2=0.000000
L 0.4607501 2.14656614 0.46381683 2.14501654 1 P 0 ;0,1=498,2=0.000000
L 0.46381683 2.14501654 0.46649961 2.1445 1 P 0 ;0,1=498,2=0.000000
L 1.75143002 2.9175 1.75143002 2.8825 1 P 0 
L 1.75143002 2.8825 1.69856998 2.8825 1 P 0 
L 1.69856998 2.8825 1.69856998 2.9175 1 P 0 
L 1.69856998 2.9175 1.75143002 2.9175 1 P 0 
L 1.71193327 2.86791624 1.70963307 2.86946683 1 P 0 ;0,1=499,2=0.000000
L 1.70963307 2.86946683 1.7069503 2.8705 1 P 0 ;0,1=499,2=0.000000
L 1.7069503 2.8705 1.70388356 2.8705 1 P 0 ;0,1=499,2=0.000000
L 1.70388356 2.8705 1.70043287 2.86894931 1 P 0 ;0,1=499,2=0.000000
L 1.70043287 2.86894931 1.6977501 2.86636654 1 P 0 ;0,1=499,2=0.000000
L 1.6977501 2.86636654 1.69583317 2.86326624 1 P 0 ;0,1=499,2=0.000000
L 1.69583317 2.86326624 1.69429951 2.8580998 1 P 0 ;0,1=499,2=0.000000
L 1.69429951 2.8580998 1.69391624 2.8534498 1 P 0 ;0,1=499,2=0.000000
L 1.69391624 2.8534498 1.69468337 2.8487999 1 P 0 ;0,1=499,2=0.000000
L 1.69468337 2.8487999 1.69583317 2.84569961 1 P 0 ;0,1=499,2=0.000000
L 1.69583317 2.84569961 1.69813337 2.84259931 1 P 0 ;0,1=499,2=0.000000
L 1.69813337 2.84259931 1.70081683 2.84053307 1 P 0 ;0,1=499,2=0.000000
L 1.70081683 2.84053307 1.70349961 2.8395 1 P 0 ;0,1=499,2=0.000000
L 1.70349961 2.8395 1.70618307 2.8395 1 P 0 ;0,1=499,2=0.000000
L 1.70618307 2.8395 1.70886654 2.84053307 1 P 0 ;0,1=499,2=0.000000
L 1.70886654 2.84053307 1.71116673 2.84208278 1 P 0 ;0,1=499,2=0.000000
L 1.71116673 2.84208278 1.71308366 2.84414892 1 P 0 ;0,1=499,2=0.000000
L 1.72606663 2.84569961 1.72836614 2.84208278 1 P 0 ;0,1=499,2=0.000000
L 1.72836614 2.84208278 1.73143287 2.84001654 1 P 0 ;0,1=499,2=0.000000
L 1.73143287 2.84001654 1.73488356 2.8395 1 P 0 ;0,1=499,2=0.000000
L 1.73488356 2.8395 1.7379503 2.84001654 1 P 0 ;0,1=499,2=0.000000
L 1.7379503 2.84001654 1.74101703 2.84259931 1 P 0 ;0,1=499,2=0.000000
L 1.74101703 2.84259931 1.74293327 2.84569961 1 P 0 ;0,1=499,2=0.000000
L 1.74293327 2.84569961 1.74331654 2.8487999 1 P 0 ;0,1=499,2=0.000000
L 1.74331654 2.8487999 1.74255 2.85241575 1 P 0 ;0,1=499,2=0.000000
L 1.74255 2.85241575 1.73986654 2.85499951 1 P 0 ;0,1=499,2=0.000000
L 1.73986654 2.85499951 1.73718307 2.85603356 1 P 0 ;0,1=499,2=0.000000
L 1.73718307 2.85603356 1.73373307 2.85603356 1 P 0 ;0,1=499,2=0.000000
L 1.73718307 2.85603356 1.73948327 2.85758317 1 P 0 ;0,1=499,2=0.000000
L 1.73948327 2.85758317 1.7414002 2.86016594 1 P 0 ;0,1=499,2=0.000000
L 1.7414002 2.86016594 1.74216673 2.86326624 1 P 0 ;0,1=499,2=0.000000
L 1.74216673 2.86326624 1.7414002 2.86636654 1 P 0 ;0,1=499,2=0.000000
L 1.7414002 2.86636654 1.73948327 2.86894931 1 P 0 ;0,1=499,2=0.000000
L 1.73948327 2.86894931 1.73603327 2.8705 1 P 0 ;0,1=499,2=0.000000
L 1.73603327 2.8705 1.73258337 2.86998337 1 P 0 ;0,1=499,2=0.000000
L 1.73258337 2.86998337 1.72913337 2.86791624 1 P 0 ;0,1=499,2=0.000000
L 1.76549961 2.8705 1.76243287 2.86946683 1 P 0 ;0,1=499,2=0.000000
L 1.76243287 2.86946683 1.76013337 2.86688307 1 P 0 ;0,1=499,2=0.000000
L 1.76013337 2.86688307 1.7585997 2.86378376 1 P 0 ;0,1=499,2=0.000000
L 1.7585997 2.86378376 1.7574499 2.85964941 1 P 0 ;0,1=499,2=0.000000
L 1.7574499 2.85964941 1.75706663 2.85499951 1 P 0 ;0,1=499,2=0.000000
L 1.75706663 2.85499951 1.7574499 2.85034951 1 P 0 ;0,1=499,2=0.000000
L 1.7574499 2.85034951 1.7585997 2.84621614 1 P 0 ;0,1=499,2=0.000000
L 1.7585997 2.84621614 1.76013337 2.84311585 1 P 0 ;0,1=499,2=0.000000
L 1.76013337 2.84311585 1.76243287 2.84053307 1 P 0 ;0,1=499,2=0.000000
L 1.76243287 2.84053307 1.76549961 2.8395 1 P 0 ;0,1=499,2=0.000000
L 1.76549961 2.8395 1.76856634 2.84053307 1 P 0 ;0,1=499,2=0.000000
L 1.76856634 2.84053307 1.77086654 2.84311585 1 P 0 ;0,1=499,2=0.000000
L 1.77086654 2.84311585 1.7724002 2.84621614 1 P 0 ;0,1=499,2=0.000000
L 1.7724002 2.84621614 1.77355 2.85034951 1 P 0 ;0,1=499,2=0.000000
L 1.77355 2.85034951 1.77393327 2.85499951 1 P 0 ;0,1=499,2=0.000000
L 1.77393327 2.85499951 1.77355 2.85964941 1 P 0 ;0,1=499,2=0.000000
L 1.77355 2.85964941 1.7724002 2.86378376 1 P 0 ;0,1=499,2=0.000000
L 1.7724002 2.86378376 1.77086654 2.86688307 1 P 0 ;0,1=499,2=0.000000
L 1.77086654 2.86688307 1.76856634 2.86946683 1 P 0 ;0,1=499,2=0.000000
L 1.76856634 2.86946683 1.76549961 2.8705 1 P 0 ;0,1=499,2=0.000000
L 1.79573307 2.8395 1.79649961 2.84621614 1 P 0 ;0,1=499,2=0.000000
L 1.79649961 2.84621614 1.7976501 2.85189921 1 P 0 ;0,1=499,2=0.000000
L 1.7976501 2.85189921 1.79918307 2.85706663 1 P 0 ;0,1=499,2=0.000000
L 1.79918307 2.85706663 1.8011 2.8627497 1 P 0 ;0,1=499,2=0.000000
L 1.8011 2.8627497 1.80416673 2.8705 1 P 0 ;0,1=499,2=0.000000
L 1.80416673 2.8705 1.78883317 2.8705 1 P 0 ;0,1=499,2=0.000000
L 5.69456998 3.7295 5.74743002 3.7295 1 P 0 
L 5.69456998 3.6945 5.69456998 3.7295 1 P 0 
L 5.74743002 3.6945 5.69456998 3.6945 1 P 0 
L 5.74743002 3.7295 5.74743002 3.6945 1 P 0 
L 5.72293327 3.37791624 5.72063307 3.37946683 1 P 0 ;0,1=500,2=0.000000
L 5.72063307 3.37946683 5.7179503 3.3805 1 P 0 ;0,1=500,2=0.000000
L 5.7179503 3.3805 5.71488356 3.3805 1 P 0 ;0,1=500,2=0.000000
L 5.71488356 3.3805 5.71143287 3.37894931 1 P 0 ;0,1=500,2=0.000000
L 5.71143287 3.37894931 5.7087501 3.37636654 1 P 0 ;0,1=500,2=0.000000
L 5.7087501 3.37636654 5.70683317 3.37326624 1 P 0 ;0,1=500,2=0.000000
L 5.70683317 3.37326624 5.70529951 3.3680998 1 P 0 ;0,1=500,2=0.000000
L 5.70529951 3.3680998 5.70491624 3.3634498 1 P 0 ;0,1=500,2=0.000000
L 5.70491624 3.3634498 5.70568337 3.3587999 1 P 0 ;0,1=500,2=0.000000
L 5.70568337 3.3587999 5.70683317 3.35569961 1 P 0 ;0,1=500,2=0.000000
L 5.70683317 3.35569961 5.70913337 3.35259931 1 P 0 ;0,1=500,2=0.000000
L 5.70913337 3.35259931 5.71181683 3.35053307 1 P 0 ;0,1=500,2=0.000000
L 5.71181683 3.35053307 5.71449961 3.3495 1 P 0 ;0,1=500,2=0.000000
L 5.71449961 3.3495 5.71718307 3.3495 1 P 0 ;0,1=500,2=0.000000
L 5.71718307 3.3495 5.71986654 3.35053307 1 P 0 ;0,1=500,2=0.000000
L 5.71986654 3.35053307 5.72216673 3.35208278 1 P 0 ;0,1=500,2=0.000000
L 5.72216673 3.35208278 5.72408366 3.35414892 1 P 0 ;0,1=500,2=0.000000
L 5.7501 3.3495 5.7501 3.3805 1 P 0 ;0,1=500,2=0.000000
L 5.7501 3.3805 5.73591624 3.35828327 1 P 0 ;0,1=500,2=0.000000
L 5.73591624 3.35828327 5.75508366 3.35828327 1 P 0 ;0,1=500,2=0.000000
L 5.46956998 3.9295 5.52243002 3.9295 1 P 0 
L 5.46956998 3.8945 5.46956998 3.9295 1 P 0 
L 5.52243002 3.8945 5.46956998 3.8945 1 P 0 
L 5.52243002 3.9295 5.52243002 3.8945 1 P 0 
L 5.42793327 3.92291624 5.42563307 3.92446683 1 P 0 ;0,1=501,2=0.000000
L 5.42563307 3.92446683 5.4229503 3.9255 1 P 0 ;0,1=501,2=0.000000
L 5.4229503 3.9255 5.41988356 3.9255 1 P 0 ;0,1=501,2=0.000000
L 5.41988356 3.9255 5.41643287 3.92394931 1 P 0 ;0,1=501,2=0.000000
L 5.41643287 3.92394931 5.4137501 3.92136654 1 P 0 ;0,1=501,2=0.000000
L 5.4137501 3.92136654 5.41183317 3.91826624 1 P 0 ;0,1=501,2=0.000000
L 5.41183317 3.91826624 5.41029951 3.9130998 1 P 0 ;0,1=501,2=0.000000
L 5.41029951 3.9130998 5.40991624 3.9084498 1 P 0 ;0,1=501,2=0.000000
L 5.40991624 3.9084498 5.41068337 3.9037999 1 P 0 ;0,1=501,2=0.000000
L 5.41068337 3.9037999 5.41183317 3.90069961 1 P 0 ;0,1=501,2=0.000000
L 5.41183317 3.90069961 5.41413337 3.89759931 1 P 0 ;0,1=501,2=0.000000
L 5.41413337 3.89759931 5.41681683 3.89553307 1 P 0 ;0,1=501,2=0.000000
L 5.41681683 3.89553307 5.41949961 3.8945 1 P 0 ;0,1=501,2=0.000000
L 5.41949961 3.8945 5.42218307 3.8945 1 P 0 ;0,1=501,2=0.000000
L 5.42218307 3.8945 5.42486654 3.89553307 1 P 0 ;0,1=501,2=0.000000
L 5.42486654 3.89553307 5.42716673 3.89708278 1 P 0 ;0,1=501,2=0.000000
L 5.42716673 3.89708278 5.42908366 3.89914892 1 P 0 ;0,1=501,2=0.000000
L 5.45049961 3.8945 5.45318307 3.89501654 1 P 0 ;0,1=501,2=0.000000
L 5.45318307 3.89501654 5.4562498 3.89656614 1 P 0 ;0,1=501,2=0.000000
L 5.4562498 3.89656614 5.45816673 3.89914892 1 P 0 ;0,1=501,2=0.000000
L 5.45816673 3.89914892 5.45893327 3.90276673 1 P 0 ;0,1=501,2=0.000000
L 5.45893327 3.90276673 5.45816673 3.90638268 1 P 0 ;0,1=501,2=0.000000
L 5.45816673 3.90638268 5.45586654 3.90948287 1 P 0 ;0,1=501,2=0.000000
L 5.45586654 3.90948287 5.45241654 3.91103356 1 P 0 ;0,1=501,2=0.000000
L 5.45241654 3.91103356 5.44858337 3.91103356 1 P 0 ;0,1=501,2=0.000000
L 5.44858337 3.91103356 5.44628317 3.91206663 1 P 0 ;0,1=501,2=0.000000
L 5.44628317 3.91206663 5.44436614 3.91464941 1 P 0 ;0,1=501,2=0.000000
L 5.44436614 3.91464941 5.4435997 3.91826624 1 P 0 ;0,1=501,2=0.000000
L 5.4435997 3.91826624 5.4447501 3.92188307 1 P 0 ;0,1=501,2=0.000000
L 5.4447501 3.92188307 5.44743287 3.92446683 1 P 0 ;0,1=501,2=0.000000
L 5.44743287 3.92446683 5.45049961 3.9255 1 P 0 ;0,1=501,2=0.000000
L 5.45049961 3.9255 5.45356634 3.92446683 1 P 0 ;0,1=501,2=0.000000
L 5.45356634 3.92446683 5.4562498 3.92188307 1 P 0 ;0,1=501,2=0.000000
L 5.4562498 3.92188307 5.4574002 3.91826624 1 P 0 ;0,1=501,2=0.000000
L 5.4574002 3.91826624 5.45663307 3.91464941 1 P 0 ;0,1=501,2=0.000000
L 5.45663307 3.91464941 5.45471673 3.91206663 1 P 0 ;0,1=501,2=0.000000
L 5.45471673 3.91206663 5.45241654 3.91103356 1 P 0 ;0,1=501,2=0.000000
L 5.45241654 3.91103356 5.44858337 3.91103356 1 P 0 ;0,1=501,2=0.000000
L 5.44858337 3.91103356 5.44513337 3.90948287 1 P 0 ;0,1=501,2=0.000000
L 5.44513337 3.90948287 5.44283317 3.90638268 1 P 0 ;0,1=501,2=0.000000
L 5.44283317 3.90638268 5.44206663 3.90276673 1 P 0 ;0,1=501,2=0.000000
L 5.44206663 3.90276673 5.44283317 3.89914892 1 P 0 ;0,1=501,2=0.000000
L 5.44283317 3.89914892 5.4447501 3.89656614 1 P 0 ;0,1=501,2=0.000000
L 5.4447501 3.89656614 5.44781683 3.89501654 1 P 0 ;0,1=501,2=0.000000
L 5.44781683 3.89501654 5.45049961 3.8945 1 P 0 ;0,1=501,2=0.000000
L 1.42956998 4.1035 1.48243002 4.1035 1 P 0 
L 1.42956998 4.0685 1.42956998 4.1035 1 P 0 
L 1.48243002 4.1035 1.48243002 4.0685 1 P 0 
L 1.48243002 4.0685 1.42956998 4.0685 1 P 0 
L 1.27243327 4.15291624 1.27013307 4.15446683 1 P 0 ;0,1=502,2=0.000000
L 1.27013307 4.15446683 1.2674503 4.1555 1 P 0 ;0,1=502,2=0.000000
L 1.2674503 4.1555 1.26438356 4.1555 1 P 0 ;0,1=502,2=0.000000
L 1.26438356 4.1555 1.26093287 4.15394931 1 P 0 ;0,1=502,2=0.000000
L 1.26093287 4.15394931 1.2582501 4.15136654 1 P 0 ;0,1=502,2=0.000000
L 1.2582501 4.15136654 1.25633317 4.14826624 1 P 0 ;0,1=502,2=0.000000
L 1.25633317 4.14826624 1.25479951 4.1430998 1 P 0 ;0,1=502,2=0.000000
L 1.25479951 4.1430998 1.25441624 4.1384498 1 P 0 ;0,1=502,2=0.000000
L 1.25441624 4.1384498 1.25518337 4.1337999 1 P 0 ;0,1=502,2=0.000000
L 1.25518337 4.1337999 1.25633317 4.13069961 1 P 0 ;0,1=502,2=0.000000
L 1.25633317 4.13069961 1.25863337 4.12759931 1 P 0 ;0,1=502,2=0.000000
L 1.25863337 4.12759931 1.26131683 4.12553307 1 P 0 ;0,1=502,2=0.000000
L 1.26131683 4.12553307 1.26399961 4.1245 1 P 0 ;0,1=502,2=0.000000
L 1.26399961 4.1245 1.26668307 4.1245 1 P 0 ;0,1=502,2=0.000000
L 1.26668307 4.1245 1.26936654 4.12553307 1 P 0 ;0,1=502,2=0.000000
L 1.26936654 4.12553307 1.27166673 4.12708278 1 P 0 ;0,1=502,2=0.000000
L 1.27166673 4.12708278 1.27358366 4.12914892 1 P 0 ;0,1=502,2=0.000000
L 1.29499961 4.1245 1.29499961 4.1555 1 P 0 ;0,1=502,2=0.000000
L 1.29499961 4.1555 1.2903999 4.1493003 1 P 0 ;0,1=502,2=0.000000
L 1.2903999 4.1245 1.29959931 4.1245 1 P 0 ;0,1=502,2=0.000000
L 1.32599961 4.1245 1.32599961 4.1555 1 P 0 ;0,1=502,2=0.000000
L 1.32599961 4.1555 1.3213999 4.1493003 1 P 0 ;0,1=502,2=0.000000
L 1.3213999 4.1245 1.33059931 4.1245 1 P 0 ;0,1=502,2=0.000000
L 1.48743002 4.0485 1.48743002 4.0135 1 P 0 
L 1.48743002 4.0135 1.43456998 4.0135 1 P 0 
L 1.43456998 4.0135 1.43456998 4.0485 1 P 0 
L 1.43456998 4.0485 1.48743002 4.0485 1 P 0 
L 1.27243327 4.11291624 1.27013307 4.11446683 1 P 0 ;0,1=503,2=0.000000
L 1.27013307 4.11446683 1.2674503 4.1155 1 P 0 ;0,1=503,2=0.000000
L 1.2674503 4.1155 1.26438356 4.1155 1 P 0 ;0,1=503,2=0.000000
L 1.26438356 4.1155 1.26093287 4.11394931 1 P 0 ;0,1=503,2=0.000000
L 1.26093287 4.11394931 1.2582501 4.11136654 1 P 0 ;0,1=503,2=0.000000
L 1.2582501 4.11136654 1.25633317 4.10826624 1 P 0 ;0,1=503,2=0.000000
L 1.25633317 4.10826624 1.25479951 4.1030998 1 P 0 ;0,1=503,2=0.000000
L 1.25479951 4.1030998 1.25441624 4.0984498 1 P 0 ;0,1=503,2=0.000000
L 1.25441624 4.0984498 1.25518337 4.0937999 1 P 0 ;0,1=503,2=0.000000
L 1.25518337 4.0937999 1.25633317 4.09069961 1 P 0 ;0,1=503,2=0.000000
L 1.25633317 4.09069961 1.25863337 4.08759931 1 P 0 ;0,1=503,2=0.000000
L 1.25863337 4.08759931 1.26131683 4.08553307 1 P 0 ;0,1=503,2=0.000000
L 1.26131683 4.08553307 1.26399961 4.0845 1 P 0 ;0,1=503,2=0.000000
L 1.26399961 4.0845 1.26668307 4.0845 1 P 0 ;0,1=503,2=0.000000
L 1.26668307 4.0845 1.26936654 4.08553307 1 P 0 ;0,1=503,2=0.000000
L 1.26936654 4.08553307 1.27166673 4.08708278 1 P 0 ;0,1=503,2=0.000000
L 1.27166673 4.08708278 1.27358366 4.08914892 1 P 0 ;0,1=503,2=0.000000
L 1.2996 4.0845 1.2996 4.1155 1 P 0 ;0,1=503,2=0.000000
L 1.2996 4.1155 1.28541624 4.09328327 1 P 0 ;0,1=503,2=0.000000
L 1.28541624 4.09328327 1.30458366 4.09328327 1 P 0 ;0,1=503,2=0.000000
L 1.31756663 4.09069961 1.31986614 4.08708278 1 P 0 ;0,1=503,2=0.000000
L 1.31986614 4.08708278 1.32293287 4.08501654 1 P 0 ;0,1=503,2=0.000000
L 1.32293287 4.08501654 1.32638356 4.0845 1 P 0 ;0,1=503,2=0.000000
L 1.32638356 4.0845 1.3294503 4.08501654 1 P 0 ;0,1=503,2=0.000000
L 1.3294503 4.08501654 1.33251703 4.08759931 1 P 0 ;0,1=503,2=0.000000
L 1.33251703 4.08759931 1.33443327 4.09069961 1 P 0 ;0,1=503,2=0.000000
L 1.33443327 4.09069961 1.33481654 4.0937999 1 P 0 ;0,1=503,2=0.000000
L 1.33481654 4.0937999 1.33405 4.09741575 1 P 0 ;0,1=503,2=0.000000
L 1.33405 4.09741575 1.33136654 4.09999951 1 P 0 ;0,1=503,2=0.000000
L 1.33136654 4.09999951 1.32868307 4.10103356 1 P 0 ;0,1=503,2=0.000000
L 1.32868307 4.10103356 1.32523307 4.10103356 1 P 0 ;0,1=503,2=0.000000
L 1.32868307 4.10103356 1.33098327 4.10258317 1 P 0 ;0,1=503,2=0.000000
L 1.33098327 4.10258317 1.3329002 4.10516594 1 P 0 ;0,1=503,2=0.000000
L 1.3329002 4.10516594 1.33366673 4.10826624 1 P 0 ;0,1=503,2=0.000000
L 1.33366673 4.10826624 1.3329002 4.11136654 1 P 0 ;0,1=503,2=0.000000
L 1.3329002 4.11136654 1.33098327 4.11394931 1 P 0 ;0,1=503,2=0.000000
L 1.33098327 4.11394931 1.32753327 4.1155 1 P 0 ;0,1=503,2=0.000000
L 1.32753327 4.1155 1.32408337 4.11498337 1 P 0 ;0,1=503,2=0.000000
L 1.32408337 4.11498337 1.32063337 4.11291624 1 P 0 ;0,1=503,2=0.000000
L 1.43456998 3.9185 1.48743002 3.9185 1 P 0 
L 1.43456998 3.8835 1.43456998 3.9185 1 P 0 
L 1.48743002 3.9185 1.48743002 3.8835 1 P 0 
L 1.48743002 3.8835 1.43456998 3.8835 1 P 0 
L 1.50243327 3.66791624 1.50013307 3.66946683 1 P 0 ;0,1=504,2=0.000000
L 1.50013307 3.66946683 1.4974503 3.6705 1 P 0 ;0,1=504,2=0.000000
L 1.4974503 3.6705 1.49438356 3.6705 1 P 0 ;0,1=504,2=0.000000
L 1.49438356 3.6705 1.49093287 3.66894931 1 P 0 ;0,1=504,2=0.000000
L 1.49093287 3.66894931 1.4882501 3.66636654 1 P 0 ;0,1=504,2=0.000000
L 1.4882501 3.66636654 1.48633317 3.66326624 1 P 0 ;0,1=504,2=0.000000
L 1.48633317 3.66326624 1.48479951 3.6580998 1 P 0 ;0,1=504,2=0.000000
L 1.48479951 3.6580998 1.48441624 3.6534498 1 P 0 ;0,1=504,2=0.000000
L 1.48441624 3.6534498 1.48518337 3.6487999 1 P 0 ;0,1=504,2=0.000000
L 1.48518337 3.6487999 1.48633317 3.64569961 1 P 0 ;0,1=504,2=0.000000
L 1.48633317 3.64569961 1.48863337 3.64259931 1 P 0 ;0,1=504,2=0.000000
L 1.48863337 3.64259931 1.49131683 3.64053307 1 P 0 ;0,1=504,2=0.000000
L 1.49131683 3.64053307 1.49399961 3.6395 1 P 0 ;0,1=504,2=0.000000
L 1.49399961 3.6395 1.49668307 3.6395 1 P 0 ;0,1=504,2=0.000000
L 1.49668307 3.6395 1.49936654 3.64053307 1 P 0 ;0,1=504,2=0.000000
L 1.49936654 3.64053307 1.50166673 3.64208278 1 P 0 ;0,1=504,2=0.000000
L 1.50166673 3.64208278 1.50358366 3.64414892 1 P 0 ;0,1=504,2=0.000000
L 1.52423307 3.6395 1.52499961 3.64621614 1 P 0 ;0,1=504,2=0.000000
L 1.52499961 3.64621614 1.5261501 3.65189921 1 P 0 ;0,1=504,2=0.000000
L 1.5261501 3.65189921 1.52768307 3.65706663 1 P 0 ;0,1=504,2=0.000000
L 1.52768307 3.65706663 1.5296 3.6627497 1 P 0 ;0,1=504,2=0.000000
L 1.5296 3.6627497 1.53266673 3.6705 1 P 0 ;0,1=504,2=0.000000
L 1.53266673 3.6705 1.51733317 3.6705 1 P 0 ;0,1=504,2=0.000000
L 1.54756663 3.64414892 1.54986614 3.64156614 1 P 0 ;0,1=504,2=0.000000
L 1.54986614 3.64156614 1.55254961 3.64001654 1 P 0 ;0,1=504,2=0.000000
L 1.55254961 3.64001654 1.55599961 3.6395 1 P 0 ;0,1=504,2=0.000000
L 1.55599961 3.6395 1.5594503 3.64053307 1 P 0 ;0,1=504,2=0.000000
L 1.5594503 3.64053307 1.56213307 3.64259931 1 P 0 ;0,1=504,2=0.000000
L 1.56213307 3.64259931 1.56405 3.64621614 1 P 0 ;0,1=504,2=0.000000
L 1.56405 3.64621614 1.56443327 3.65034951 1 P 0 ;0,1=504,2=0.000000
L 1.56443327 3.65034951 1.56366673 3.65448287 1 P 0 ;0,1=504,2=0.000000
L 1.56366673 3.65448287 1.5617498 3.65706663 1 P 0 ;0,1=504,2=0.000000
L 1.5617498 3.65706663 1.55906634 3.65913287 1 P 0 ;0,1=504,2=0.000000
L 1.55906634 3.65913287 1.55638356 3.65964941 1 P 0 ;0,1=504,2=0.000000
L 1.55638356 3.65964941 1.5537001 3.65913287 1 P 0 ;0,1=504,2=0.000000
L 1.5537001 3.65913287 1.5502501 3.65706663 1 P 0 ;0,1=504,2=0.000000
L 1.5502501 3.65706663 1.5513999 3.6705 1 P 0 ;0,1=504,2=0.000000
L 1.5513999 3.6705 1.5617498 3.6705 1 P 0 ;0,1=504,2=0.000000
L 1.30643002 3.8075 1.30643002 3.7725 1 P 0 
L 1.30643002 3.7725 1.25356998 3.7725 1 P 0 
L 1.25356998 3.7725 1.25356998 3.8075 1 P 0 
L 1.25356998 3.8075 1.30643002 3.8075 1 P 0 
L 1.37208376 3.72743327 1.37053317 3.72513307 1 P 0 ;0,1=505,2=270.000000
L 1.37053317 3.72513307 1.3695 3.7224503 1 P 0 ;0,1=505,2=270.000000
L 1.3695 3.7224503 1.3695 3.71938356 1 P 0 ;0,1=505,2=270.000000
L 1.3695 3.71938356 1.37105069 3.71593287 1 P 0 ;0,1=505,2=270.000000
L 1.37105069 3.71593287 1.37363346 3.7132501 1 P 0 ;0,1=505,2=270.000000
L 1.37363346 3.7132501 1.37673376 3.71133317 1 P 0 ;0,1=505,2=270.000000
L 1.37673376 3.71133317 1.3819002 3.70979951 1 P 0 ;0,1=505,2=270.000000
L 1.3819002 3.70979951 1.3865502 3.70941624 1 P 0 ;0,1=505,2=270.000000
L 1.3865502 3.70941624 1.3912001 3.71018337 1 P 0 ;0,1=505,2=270.000000
L 1.3912001 3.71018337 1.39430039 3.71133317 1 P 0 ;0,1=505,2=270.000000
L 1.39430039 3.71133317 1.39740069 3.71363337 1 P 0 ;0,1=505,2=270.000000
L 1.39740069 3.71363337 1.39946693 3.71631683 1 P 0 ;0,1=505,2=270.000000
L 1.39946693 3.71631683 1.4005 3.71899961 1 P 0 ;0,1=505,2=270.000000
L 1.4005 3.71899961 1.4005 3.72168307 1 P 0 ;0,1=505,2=270.000000
L 1.4005 3.72168307 1.39946693 3.72436654 1 P 0 ;0,1=505,2=270.000000
L 1.39946693 3.72436654 1.39791722 3.72666673 1 P 0 ;0,1=505,2=270.000000
L 1.39791722 3.72666673 1.39585108 3.72858366 1 P 0 ;0,1=505,2=270.000000
L 1.4005 3.74999961 1.39998346 3.75268307 1 P 0 ;0,1=505,2=270.000000
L 1.39998346 3.75268307 1.39843386 3.7557498 1 P 0 ;0,1=505,2=270.000000
L 1.39843386 3.7557498 1.39585108 3.75766673 1 P 0 ;0,1=505,2=270.000000
L 1.39585108 3.75766673 1.39223327 3.75843327 1 P 0 ;0,1=505,2=270.000000
L 1.39223327 3.75843327 1.38861732 3.75766673 1 P 0 ;0,1=505,2=270.000000
L 1.38861732 3.75766673 1.38551713 3.75536654 1 P 0 ;0,1=505,2=270.000000
L 1.38551713 3.75536654 1.38396644 3.75191654 1 P 0 ;0,1=505,2=270.000000
L 1.38396644 3.75191654 1.38396644 3.74808337 1 P 0 ;0,1=505,2=270.000000
L 1.38396644 3.74808337 1.38293337 3.74578317 1 P 0 ;0,1=505,2=270.000000
L 1.38293337 3.74578317 1.38035059 3.74386614 1 P 0 ;0,1=505,2=270.000000
L 1.38035059 3.74386614 1.37673376 3.7430997 1 P 0 ;0,1=505,2=270.000000
L 1.37673376 3.7430997 1.37311693 3.7442501 1 P 0 ;0,1=505,2=270.000000
L 1.37311693 3.7442501 1.37053317 3.74693287 1 P 0 ;0,1=505,2=270.000000
L 1.37053317 3.74693287 1.3695 3.74999961 1 P 0 ;0,1=505,2=270.000000
L 1.3695 3.74999961 1.37053317 3.75306634 1 P 0 ;0,1=505,2=270.000000
L 1.37053317 3.75306634 1.37311693 3.7557498 1 P 0 ;0,1=505,2=270.000000
L 1.37311693 3.7557498 1.37673376 3.7569002 1 P 0 ;0,1=505,2=270.000000
L 1.37673376 3.7569002 1.38035059 3.75613307 1 P 0 ;0,1=505,2=270.000000
L 1.38035059 3.75613307 1.38293337 3.75421673 1 P 0 ;0,1=505,2=270.000000
L 1.38293337 3.75421673 1.38396644 3.75191654 1 P 0 ;0,1=505,2=270.000000
L 1.38396644 3.75191654 1.38396644 3.74808337 1 P 0 ;0,1=505,2=270.000000
L 1.38396644 3.74808337 1.38551713 3.74463337 1 P 0 ;0,1=505,2=270.000000
L 1.38551713 3.74463337 1.38861732 3.74233317 1 P 0 ;0,1=505,2=270.000000
L 1.38861732 3.74233317 1.39223327 3.74156663 1 P 0 ;0,1=505,2=270.000000
L 1.39223327 3.74156663 1.39585108 3.74233317 1 P 0 ;0,1=505,2=270.000000
L 1.39585108 3.74233317 1.39843386 3.7442501 1 P 0 ;0,1=505,2=270.000000
L 1.39843386 3.7442501 1.39998346 3.74731683 1 P 0 ;0,1=505,2=270.000000
L 1.39998346 3.74731683 1.4005 3.74999961 1 P 0 ;0,1=505,2=270.000000
L 1.38758425 3.77371644 1.38396644 3.7763999 1 P 0 ;0,1=505,2=270.000000
L 1.38396644 3.7763999 1.3819002 3.7787001 1 P 0 ;0,1=505,2=270.000000
L 1.3819002 3.7787001 1.38086713 3.78176683 1 P 0 ;0,1=505,2=270.000000
L 1.38086713 3.78176683 1.3819002 3.7844503 1 P 0 ;0,1=505,2=270.000000
L 1.3819002 3.7844503 1.38396644 3.78636654 1 P 0 ;0,1=505,2=270.000000
L 1.38396644 3.78636654 1.38706673 3.7879002 1 P 0 ;0,1=505,2=270.000000
L 1.38706673 3.7879002 1.39068356 3.78828346 1 P 0 ;0,1=505,2=270.000000
L 1.39068356 3.78828346 1.39378386 3.7879002 1 P 0 ;0,1=505,2=270.000000
L 1.39378386 3.7879002 1.39688415 3.78636654 1 P 0 ;0,1=505,2=270.000000
L 1.39688415 3.78636654 1.39946693 3.78406634 1 P 0 ;0,1=505,2=270.000000
L 1.39946693 3.78406634 1.4005 3.78138356 1 P 0 ;0,1=505,2=270.000000
L 1.4005 3.78138356 1.39946693 3.77831683 1 P 0 ;0,1=505,2=270.000000
L 1.39946693 3.77831683 1.39636762 3.77563337 1 P 0 ;0,1=505,2=270.000000
L 1.39636762 3.77563337 1.39171673 3.7740997 1 P 0 ;0,1=505,2=270.000000
L 1.39171673 3.7740997 1.3865502 3.77371644 1 P 0 ;0,1=505,2=270.000000
L 1.3865502 3.77371644 1.37983406 3.77448287 1 P 0 ;0,1=505,2=270.000000
L 1.37983406 3.77448287 1.37621624 3.77563337 1 P 0 ;0,1=505,2=270.000000
L 1.37621624 3.77563337 1.3726003 3.77754961 1 P 0 ;0,1=505,2=270.000000
L 1.3726003 3.77754961 1.37001663 3.78023307 1 P 0 ;0,1=505,2=270.000000
L 1.37001663 3.78023307 1.3695 3.78291654 1 P 0 ;0,1=505,2=270.000000
L 1.3695 3.78291654 1.37053317 3.7856 1 P 0 ;0,1=505,2=270.000000
L 1.37053317 3.7856 1.37311693 3.78751703 1 P 0 ;0,1=505,2=270.000000
L 1.25143002 3.8075 1.25143002 3.7725 1 P 0 
L 1.19856998 3.7725 1.19856998 3.8075 1 P 0 
L 1.19856998 3.8075 1.25143002 3.8075 1 P 0 
L 1.25143002 3.7725 1.19856998 3.7725 1 P 0 
L 1.33208376 3.72743327 1.33053317 3.72513307 1 P 0 ;0,1=506,2=270.000000
L 1.33053317 3.72513307 1.3295 3.7224503 1 P 0 ;0,1=506,2=270.000000
L 1.3295 3.7224503 1.3295 3.71938356 1 P 0 ;0,1=506,2=270.000000
L 1.3295 3.71938356 1.33105069 3.71593287 1 P 0 ;0,1=506,2=270.000000
L 1.33105069 3.71593287 1.33363346 3.7132501 1 P 0 ;0,1=506,2=270.000000
L 1.33363346 3.7132501 1.33673376 3.71133317 1 P 0 ;0,1=506,2=270.000000
L 1.33673376 3.71133317 1.3419002 3.70979951 1 P 0 ;0,1=506,2=270.000000
L 1.3419002 3.70979951 1.3465502 3.70941624 1 P 0 ;0,1=506,2=270.000000
L 1.3465502 3.70941624 1.3512001 3.71018337 1 P 0 ;0,1=506,2=270.000000
L 1.3512001 3.71018337 1.35430039 3.71133317 1 P 0 ;0,1=506,2=270.000000
L 1.35430039 3.71133317 1.35740069 3.71363337 1 P 0 ;0,1=506,2=270.000000
L 1.35740069 3.71363337 1.35946693 3.71631683 1 P 0 ;0,1=506,2=270.000000
L 1.35946693 3.71631683 1.3605 3.71899961 1 P 0 ;0,1=506,2=270.000000
L 1.3605 3.71899961 1.3605 3.72168307 1 P 0 ;0,1=506,2=270.000000
L 1.3605 3.72168307 1.35946693 3.72436654 1 P 0 ;0,1=506,2=270.000000
L 1.35946693 3.72436654 1.35791722 3.72666673 1 P 0 ;0,1=506,2=270.000000
L 1.35791722 3.72666673 1.35585108 3.72858366 1 P 0 ;0,1=506,2=270.000000
L 1.3605 3.74999961 1.35998346 3.75268307 1 P 0 ;0,1=506,2=270.000000
L 1.35998346 3.75268307 1.35843386 3.7557498 1 P 0 ;0,1=506,2=270.000000
L 1.35843386 3.7557498 1.35585108 3.75766673 1 P 0 ;0,1=506,2=270.000000
L 1.35585108 3.75766673 1.35223327 3.75843327 1 P 0 ;0,1=506,2=270.000000
L 1.35223327 3.75843327 1.34861732 3.75766673 1 P 0 ;0,1=506,2=270.000000
L 1.34861732 3.75766673 1.34551713 3.75536654 1 P 0 ;0,1=506,2=270.000000
L 1.34551713 3.75536654 1.34396644 3.75191654 1 P 0 ;0,1=506,2=270.000000
L 1.34396644 3.75191654 1.34396644 3.74808337 1 P 0 ;0,1=506,2=270.000000
L 1.34396644 3.74808337 1.34293337 3.74578317 1 P 0 ;0,1=506,2=270.000000
L 1.34293337 3.74578317 1.34035059 3.74386614 1 P 0 ;0,1=506,2=270.000000
L 1.34035059 3.74386614 1.33673376 3.7430997 1 P 0 ;0,1=506,2=270.000000
L 1.33673376 3.7430997 1.33311693 3.7442501 1 P 0 ;0,1=506,2=270.000000
L 1.33311693 3.7442501 1.33053317 3.74693287 1 P 0 ;0,1=506,2=270.000000
L 1.33053317 3.74693287 1.3295 3.74999961 1 P 0 ;0,1=506,2=270.000000
L 1.3295 3.74999961 1.33053317 3.75306634 1 P 0 ;0,1=506,2=270.000000
L 1.33053317 3.75306634 1.33311693 3.7557498 1 P 0 ;0,1=506,2=270.000000
L 1.33311693 3.7557498 1.33673376 3.7569002 1 P 0 ;0,1=506,2=270.000000
L 1.33673376 3.7569002 1.34035059 3.75613307 1 P 0 ;0,1=506,2=270.000000
L 1.34035059 3.75613307 1.34293337 3.75421673 1 P 0 ;0,1=506,2=270.000000
L 1.34293337 3.75421673 1.34396644 3.75191654 1 P 0 ;0,1=506,2=270.000000
L 1.34396644 3.75191654 1.34396644 3.74808337 1 P 0 ;0,1=506,2=270.000000
L 1.34396644 3.74808337 1.34551713 3.74463337 1 P 0 ;0,1=506,2=270.000000
L 1.34551713 3.74463337 1.34861732 3.74233317 1 P 0 ;0,1=506,2=270.000000
L 1.34861732 3.74233317 1.35223327 3.74156663 1 P 0 ;0,1=506,2=270.000000
L 1.35223327 3.74156663 1.35585108 3.74233317 1 P 0 ;0,1=506,2=270.000000
L 1.35585108 3.74233317 1.35843386 3.7442501 1 P 0 ;0,1=506,2=270.000000
L 1.35843386 3.7442501 1.35998346 3.74731683 1 P 0 ;0,1=506,2=270.000000
L 1.35998346 3.74731683 1.3605 3.74999961 1 P 0 ;0,1=506,2=270.000000
L 1.3605 3.78023307 1.35378386 3.78099961 1 P 0 ;0,1=506,2=270.000000
L 1.35378386 3.78099961 1.34810079 3.7821501 1 P 0 ;0,1=506,2=270.000000
L 1.34810079 3.7821501 1.34293337 3.78368307 1 P 0 ;0,1=506,2=270.000000
L 1.34293337 3.78368307 1.3372503 3.7856 1 P 0 ;0,1=506,2=270.000000
L 1.3372503 3.7856 1.3295 3.78866673 1 P 0 ;0,1=506,2=270.000000
L 1.3295 3.78866673 1.3295 3.77333317 1 P 0 ;0,1=506,2=270.000000
L 3.65423002 2.42843002 3.65423002 2.37556998 1 P 0 
L 3.65423002 2.37556998 3.61923002 2.37556998 1 P 0 
L 3.61923002 2.37556998 3.61923002 2.42843002 1 P 0 
L 3.61923002 2.42843002 3.65423002 2.42843002 1 P 0 
L 3.63386663 2.29741634 3.63226644 2.29866683 1 P 0 ;0,1=507,2=0.000000
L 3.63226644 2.29866683 3.6304002 2.2995 1 P 0 ;0,1=507,2=0.000000
L 3.6304002 2.2995 3.62826683 2.2995 1 P 0 ;0,1=507,2=0.000000
L 3.62826683 2.2995 3.62586634 2.29824941 1 P 0 ;0,1=507,2=0.000000
L 3.62586634 2.29824941 3.6240001 2.29616654 1 P 0 ;0,1=507,2=0.000000
L 3.6240001 2.29616654 3.62266654 2.29366634 1 P 0 ;0,1=507,2=0.000000
L 3.62266654 2.29366634 3.62159961 2.2894998 1 P 0 ;0,1=507,2=0.000000
L 3.62159961 2.2894998 3.62133297 2.2857498 1 P 0 ;0,1=507,2=0.000000
L 3.62133297 2.2857498 3.62186673 2.2819999 1 P 0 ;0,1=507,2=0.000000
L 3.62186673 2.2819999 3.62266654 2.27949961 1 P 0 ;0,1=507,2=0.000000
L 3.62266654 2.27949961 3.62426663 2.27699941 1 P 0 ;0,1=507,2=0.000000
L 3.62426663 2.27699941 3.62613346 2.27533307 1 P 0 ;0,1=507,2=0.000000
L 3.62613346 2.27533307 3.6279997 2.2745 1 P 0 ;0,1=507,2=0.000000
L 3.6279997 2.2745 3.62986644 2.2745 1 P 0 ;0,1=507,2=0.000000
L 3.62986644 2.2745 3.63173327 2.27533307 1 P 0 ;0,1=507,2=0.000000
L 3.63173327 2.27533307 3.63333337 2.27658287 1 P 0 ;0,1=507,2=0.000000
L 3.63333337 2.27658287 3.63466693 2.27824911 1 P 0 ;0,1=507,2=0.000000
L 3.64413327 2.27824911 3.64573297 2.27616624 1 P 0 ;0,1=507,2=0.000000
L 3.64573297 2.27616624 3.6475997 2.27491654 1 P 0 ;0,1=507,2=0.000000
L 3.6475997 2.27491654 3.6499997 2.2745 1 P 0 ;0,1=507,2=0.000000
L 3.6499997 2.2745 3.6524002 2.27533307 1 P 0 ;0,1=507,2=0.000000
L 3.6524002 2.27533307 3.65426644 2.27699941 1 P 0 ;0,1=507,2=0.000000
L 3.65426644 2.27699941 3.6556 2.27991624 1 P 0 ;0,1=507,2=0.000000
L 3.6556 2.27991624 3.65586663 2.28324961 1 P 0 ;0,1=507,2=0.000000
L 3.65586663 2.28324961 3.65533337 2.28658297 1 P 0 ;0,1=507,2=0.000000
L 3.65533337 2.28658297 3.6539998 2.28866663 1 P 0 ;0,1=507,2=0.000000
L 3.6539998 2.28866663 3.65213307 2.29033297 1 P 0 ;0,1=507,2=0.000000
L 3.65213307 2.29033297 3.65026683 2.29074951 1 P 0 ;0,1=507,2=0.000000
L 3.65026683 2.29074951 3.6484 2.29033297 1 P 0 ;0,1=507,2=0.000000
L 3.6484 2.29033297 3.6460001 2.28866663 1 P 0 ;0,1=507,2=0.000000
L 3.6460001 2.28866663 3.6467999 2.2995 1 P 0 ;0,1=507,2=0.000000
L 3.6467999 2.2995 3.6539998 2.2995 1 P 0 ;0,1=507,2=0.000000
L 3.6719997 2.2745 3.6719997 2.2995 1 P 0 ;0,1=507,2=0.000000
L 3.6719997 2.2995 3.6687999 2.2945003 1 P 0 ;0,1=507,2=0.000000
L 3.6687999 2.2745 3.67519951 2.2745 1 P 0 ;0,1=507,2=0.000000
L 3.65423002 2.36243002 3.65423002 2.30956998 1 P 0 
L 3.61923002 2.36243002 3.65423002 2.36243002 1 P 0 
L 3.65423002 2.30956998 3.61923002 2.30956998 1 P 0 
L 3.61923002 2.30956998 3.61923002 2.36243002 1 P 0 
L 3.63386663 2.25741634 3.63226644 2.25866683 1 P 0 ;0,1=508,2=0.000000
L 3.63226644 2.25866683 3.6304002 2.2595 1 P 0 ;0,1=508,2=0.000000
L 3.6304002 2.2595 3.62826683 2.2595 1 P 0 ;0,1=508,2=0.000000
L 3.62826683 2.2595 3.62586634 2.25824941 1 P 0 ;0,1=508,2=0.000000
L 3.62586634 2.25824941 3.6240001 2.25616654 1 P 0 ;0,1=508,2=0.000000
L 3.6240001 2.25616654 3.62266654 2.25366634 1 P 0 ;0,1=508,2=0.000000
L 3.62266654 2.25366634 3.62159961 2.2494998 1 P 0 ;0,1=508,2=0.000000
L 3.62159961 2.2494998 3.62133297 2.2457498 1 P 0 ;0,1=508,2=0.000000
L 3.62133297 2.2457498 3.62186673 2.2419999 1 P 0 ;0,1=508,2=0.000000
L 3.62186673 2.2419999 3.62266654 2.23949961 1 P 0 ;0,1=508,2=0.000000
L 3.62266654 2.23949961 3.62426663 2.23699941 1 P 0 ;0,1=508,2=0.000000
L 3.62426663 2.23699941 3.62613346 2.23533307 1 P 0 ;0,1=508,2=0.000000
L 3.62613346 2.23533307 3.6279997 2.2345 1 P 0 ;0,1=508,2=0.000000
L 3.6279997 2.2345 3.62986644 2.2345 1 P 0 ;0,1=508,2=0.000000
L 3.62986644 2.2345 3.63173327 2.23533307 1 P 0 ;0,1=508,2=0.000000
L 3.63173327 2.23533307 3.63333337 2.23658287 1 P 0 ;0,1=508,2=0.000000
L 3.63333337 2.23658287 3.63466693 2.23824911 1 P 0 ;0,1=508,2=0.000000
L 3.6532 2.2345 3.6532 2.2595 1 P 0 ;0,1=508,2=0.000000
L 3.6532 2.2595 3.64333297 2.24158327 1 P 0 ;0,1=508,2=0.000000
L 3.64333297 2.24158327 3.65666693 2.24158327 1 P 0 ;0,1=508,2=0.000000
L 3.67146654 2.2345 3.6719997 2.23991624 1 P 0 ;0,1=508,2=0.000000
L 3.6719997 2.23991624 3.6728 2.24449931 1 P 0 ;0,1=508,2=0.000000
L 3.6728 2.24449931 3.67386644 2.24866663 1 P 0 ;0,1=508,2=0.000000
L 3.67386644 2.24866663 3.6752 2.2532498 1 P 0 ;0,1=508,2=0.000000
L 3.6752 2.2532498 3.67733337 2.2595 1 P 0 ;0,1=508,2=0.000000
L 3.67733337 2.2595 3.66666654 2.2595 1 P 0 ;0,1=508,2=0.000000
L 5.42356998 0.6525 5.47643002 0.6525 1 P 0 
L 5.42356998 0.6175 5.42356998 0.6525 1 P 0 
L 5.47643002 0.6175 5.42356998 0.6175 1 P 0 
L 5.47643002 0.6525 5.47643002 0.6175 1 P 0 
L 5.33193327 0.58791624 5.32963307 0.58946683 1 P 0 ;0,1=509,2=0.000000
L 5.32963307 0.58946683 5.3269503 0.5905 1 P 0 ;0,1=509,2=0.000000
L 5.3269503 0.5905 5.32388356 0.5905 1 P 0 ;0,1=509,2=0.000000
L 5.32388356 0.5905 5.32043287 0.58894931 1 P 0 ;0,1=509,2=0.000000
L 5.32043287 0.58894931 5.3177501 0.58636654 1 P 0 ;0,1=509,2=0.000000
L 5.3177501 0.58636654 5.31583317 0.58326624 1 P 0 ;0,1=509,2=0.000000
L 5.31583317 0.58326624 5.31429951 0.5780998 1 P 0 ;0,1=509,2=0.000000
L 5.31429951 0.5780998 5.31391624 0.5734498 1 P 0 ;0,1=509,2=0.000000
L 5.31391624 0.5734498 5.31468337 0.5687999 1 P 0 ;0,1=509,2=0.000000
L 5.31468337 0.5687999 5.31583317 0.56569961 1 P 0 ;0,1=509,2=0.000000
L 5.31583317 0.56569961 5.31813337 0.56259931 1 P 0 ;0,1=509,2=0.000000
L 5.31813337 0.56259931 5.32081683 0.56053307 1 P 0 ;0,1=509,2=0.000000
L 5.32081683 0.56053307 5.32349961 0.5595 1 P 0 ;0,1=509,2=0.000000
L 5.32349961 0.5595 5.32618307 0.5595 1 P 0 ;0,1=509,2=0.000000
L 5.32618307 0.5595 5.32886654 0.56053307 1 P 0 ;0,1=509,2=0.000000
L 5.32886654 0.56053307 5.33116673 0.56208278 1 P 0 ;0,1=509,2=0.000000
L 5.33116673 0.56208278 5.33308366 0.56414892 1 P 0 ;0,1=509,2=0.000000
L 5.34721644 0.58533346 5.34951663 0.58843278 1 P 0 ;0,1=509,2=0.000000
L 5.34951663 0.58843278 5.3522001 0.58998337 1 P 0 ;0,1=509,2=0.000000
L 5.3522001 0.58998337 5.35526683 0.5905 1 P 0 ;0,1=509,2=0.000000
L 5.35526683 0.5905 5.3591 0.58946683 1 P 0 ;0,1=509,2=0.000000
L 5.3591 0.58946683 5.36178346 0.58688307 1 P 0 ;0,1=509,2=0.000000
L 5.36178346 0.58688307 5.36255 0.58378376 1 P 0 ;0,1=509,2=0.000000
L 5.36255 0.58378376 5.36216673 0.58068258 1 P 0 ;0,1=509,2=0.000000
L 5.36216673 0.58068258 5.36063307 0.5780998 1 P 0 ;0,1=509,2=0.000000
L 5.36063307 0.5780998 5.35296663 0.57293327 1 P 0 ;0,1=509,2=0.000000
L 5.35296663 0.57293327 5.34951663 0.56931644 1 P 0 ;0,1=509,2=0.000000
L 5.34951663 0.56931644 5.34721644 0.56414892 1 P 0 ;0,1=509,2=0.000000
L 5.34721644 0.56414892 5.3464499 0.5595 1 P 0 ;0,1=509,2=0.000000
L 5.3464499 0.5595 5.36255 0.5595 1 P 0 ;0,1=509,2=0.000000
L 5.37706663 0.56569961 5.37936614 0.56208278 1 P 0 ;0,1=509,2=0.000000
L 5.37936614 0.56208278 5.38243287 0.56001654 1 P 0 ;0,1=509,2=0.000000
L 5.38243287 0.56001654 5.38588356 0.5595 1 P 0 ;0,1=509,2=0.000000
L 5.38588356 0.5595 5.3889503 0.56001654 1 P 0 ;0,1=509,2=0.000000
L 5.3889503 0.56001654 5.39201703 0.56259931 1 P 0 ;0,1=509,2=0.000000
L 5.39201703 0.56259931 5.39393327 0.56569961 1 P 0 ;0,1=509,2=0.000000
L 5.39393327 0.56569961 5.39431654 0.5687999 1 P 0 ;0,1=509,2=0.000000
L 5.39431654 0.5687999 5.39355 0.57241575 1 P 0 ;0,1=509,2=0.000000
L 5.39355 0.57241575 5.39086654 0.57499951 1 P 0 ;0,1=509,2=0.000000
L 5.39086654 0.57499951 5.38818307 0.57603356 1 P 0 ;0,1=509,2=0.000000
L 5.38818307 0.57603356 5.38473307 0.57603356 1 P 0 ;0,1=509,2=0.000000
L 5.38818307 0.57603356 5.39048327 0.57758317 1 P 0 ;0,1=509,2=0.000000
L 5.39048327 0.57758317 5.3924002 0.58016594 1 P 0 ;0,1=509,2=0.000000
L 5.3924002 0.58016594 5.39316673 0.58326624 1 P 0 ;0,1=509,2=0.000000
L 5.39316673 0.58326624 5.3924002 0.58636654 1 P 0 ;0,1=509,2=0.000000
L 5.3924002 0.58636654 5.39048327 0.58894931 1 P 0 ;0,1=509,2=0.000000
L 5.39048327 0.58894931 5.38703327 0.5905 1 P 0 ;0,1=509,2=0.000000
L 5.38703327 0.5905 5.38358337 0.58998337 1 P 0 ;0,1=509,2=0.000000
L 5.38358337 0.58998337 5.38013337 0.58791624 1 P 0 ;0,1=509,2=0.000000
L 5.4211 0.5595 5.4211 0.5905 1 P 0 ;0,1=509,2=0.000000
L 5.4211 0.5905 5.40691624 0.56828327 1 P 0 ;0,1=509,2=0.000000
L 5.40691624 0.56828327 5.42608366 0.56828327 1 P 0 ;0,1=509,2=0.000000
L 5.79643002 0.6265 5.79643002 0.5915 1 P 0 
L 5.74356998 0.5915 5.74356998 0.6265 1 P 0 
L 5.74356998 0.6265 5.79643002 0.6265 1 P 0 
L 5.79643002 0.5915 5.74356998 0.5915 1 P 0 
L 5.83693327 0.58291624 5.83463307 0.58446683 1 P 0 ;0,1=510,2=0.000000
L 5.83463307 0.58446683 5.8319503 0.5855 1 P 0 ;0,1=510,2=0.000000
L 5.8319503 0.5855 5.82888356 0.5855 1 P 0 ;0,1=510,2=0.000000
L 5.82888356 0.5855 5.82543287 0.58394931 1 P 0 ;0,1=510,2=0.000000
L 5.82543287 0.58394931 5.8227501 0.58136654 1 P 0 ;0,1=510,2=0.000000
L 5.8227501 0.58136654 5.82083317 0.57826624 1 P 0 ;0,1=510,2=0.000000
L 5.82083317 0.57826624 5.81929951 0.5730998 1 P 0 ;0,1=510,2=0.000000
L 5.81929951 0.5730998 5.81891624 0.5684498 1 P 0 ;0,1=510,2=0.000000
L 5.81891624 0.5684498 5.81968337 0.5637999 1 P 0 ;0,1=510,2=0.000000
L 5.81968337 0.5637999 5.82083317 0.56069961 1 P 0 ;0,1=510,2=0.000000
L 5.82083317 0.56069961 5.82313337 0.55759931 1 P 0 ;0,1=510,2=0.000000
L 5.82313337 0.55759931 5.82581683 0.55553307 1 P 0 ;0,1=510,2=0.000000
L 5.82581683 0.55553307 5.82849961 0.5545 1 P 0 ;0,1=510,2=0.000000
L 5.82849961 0.5545 5.83118307 0.5545 1 P 0 ;0,1=510,2=0.000000
L 5.83118307 0.5545 5.83386654 0.55553307 1 P 0 ;0,1=510,2=0.000000
L 5.83386654 0.55553307 5.83616673 0.55708278 1 P 0 ;0,1=510,2=0.000000
L 5.83616673 0.55708278 5.83808366 0.55914892 1 P 0 ;0,1=510,2=0.000000
L 5.85221644 0.58033346 5.85451663 0.58343278 1 P 0 ;0,1=510,2=0.000000
L 5.85451663 0.58343278 5.8572001 0.58498337 1 P 0 ;0,1=510,2=0.000000
L 5.8572001 0.58498337 5.86026683 0.5855 1 P 0 ;0,1=510,2=0.000000
L 5.86026683 0.5855 5.8641 0.58446683 1 P 0 ;0,1=510,2=0.000000
L 5.8641 0.58446683 5.86678346 0.58188307 1 P 0 ;0,1=510,2=0.000000
L 5.86678346 0.58188307 5.86755 0.57878376 1 P 0 ;0,1=510,2=0.000000
L 5.86755 0.57878376 5.86716673 0.57568258 1 P 0 ;0,1=510,2=0.000000
L 5.86716673 0.57568258 5.86563307 0.5730998 1 P 0 ;0,1=510,2=0.000000
L 5.86563307 0.5730998 5.85796663 0.56793327 1 P 0 ;0,1=510,2=0.000000
L 5.85796663 0.56793327 5.85451663 0.56431644 1 P 0 ;0,1=510,2=0.000000
L 5.85451663 0.56431644 5.85221644 0.55914892 1 P 0 ;0,1=510,2=0.000000
L 5.85221644 0.55914892 5.8514499 0.5545 1 P 0 ;0,1=510,2=0.000000
L 5.8514499 0.5545 5.86755 0.5545 1 P 0 ;0,1=510,2=0.000000
L 5.88206663 0.56069961 5.88436614 0.55708278 1 P 0 ;0,1=510,2=0.000000
L 5.88436614 0.55708278 5.88743287 0.55501654 1 P 0 ;0,1=510,2=0.000000
L 5.88743287 0.55501654 5.89088356 0.5545 1 P 0 ;0,1=510,2=0.000000
L 5.89088356 0.5545 5.8939503 0.55501654 1 P 0 ;0,1=510,2=0.000000
L 5.8939503 0.55501654 5.89701703 0.55759931 1 P 0 ;0,1=510,2=0.000000
L 5.89701703 0.55759931 5.89893327 0.56069961 1 P 0 ;0,1=510,2=0.000000
L 5.89893327 0.56069961 5.89931654 0.5637999 1 P 0 ;0,1=510,2=0.000000
L 5.89931654 0.5637999 5.89855 0.56741575 1 P 0 ;0,1=510,2=0.000000
L 5.89855 0.56741575 5.89586654 0.56999951 1 P 0 ;0,1=510,2=0.000000
L 5.89586654 0.56999951 5.89318307 0.57103356 1 P 0 ;0,1=510,2=0.000000
L 5.89318307 0.57103356 5.88973307 0.57103356 1 P 0 ;0,1=510,2=0.000000
L 5.89318307 0.57103356 5.89548327 0.57258317 1 P 0 ;0,1=510,2=0.000000
L 5.89548327 0.57258317 5.8974002 0.57516594 1 P 0 ;0,1=510,2=0.000000
L 5.8974002 0.57516594 5.89816673 0.57826624 1 P 0 ;0,1=510,2=0.000000
L 5.89816673 0.57826624 5.8974002 0.58136654 1 P 0 ;0,1=510,2=0.000000
L 5.8974002 0.58136654 5.89548327 0.58394931 1 P 0 ;0,1=510,2=0.000000
L 5.89548327 0.58394931 5.89203327 0.5855 1 P 0 ;0,1=510,2=0.000000
L 5.89203327 0.5855 5.88858337 0.58498337 1 P 0 ;0,1=510,2=0.000000
L 5.88858337 0.58498337 5.88513337 0.58291624 1 P 0 ;0,1=510,2=0.000000
L 5.92149961 0.5545 5.92149961 0.5855 1 P 0 ;0,1=510,2=0.000000
L 5.92149961 0.5855 5.9168999 0.5793003 1 P 0 ;0,1=510,2=0.000000
L 5.9168999 0.5545 5.92609931 0.5545 1 P 0 ;0,1=510,2=0.000000
L 3.97843002 2.7565 3.92556998 2.7565 1 P 0 
L 3.97843002 2.7915 3.97843002 2.7565 1 P 0 
L 3.92556998 2.7915 3.97843002 2.7915 1 P 0 
L 3.92556998 2.7565 3.92556998 2.7915 1 P 0 
L 4.02193327 2.78291624 4.01963307 2.78446683 1 P 0 ;0,1=511,2=0.000000
L 4.01963307 2.78446683 4.0169503 2.7855 1 P 0 ;0,1=511,2=0.000000
L 4.0169503 2.7855 4.01388356 2.7855 1 P 0 ;0,1=511,2=0.000000
L 4.01388356 2.7855 4.01043287 2.78394931 1 P 0 ;0,1=511,2=0.000000
L 4.01043287 2.78394931 4.0077501 2.78136654 1 P 0 ;0,1=511,2=0.000000
L 4.0077501 2.78136654 4.00583317 2.77826624 1 P 0 ;0,1=511,2=0.000000
L 4.00583317 2.77826624 4.00429951 2.7730998 1 P 0 ;0,1=511,2=0.000000
L 4.00429951 2.7730998 4.00391624 2.7684498 1 P 0 ;0,1=511,2=0.000000
L 4.00391624 2.7684498 4.00468337 2.7637999 1 P 0 ;0,1=511,2=0.000000
L 4.00468337 2.7637999 4.00583317 2.76069961 1 P 0 ;0,1=511,2=0.000000
L 4.00583317 2.76069961 4.00813337 2.75759931 1 P 0 ;0,1=511,2=0.000000
L 4.00813337 2.75759931 4.01081683 2.75553307 1 P 0 ;0,1=511,2=0.000000
L 4.01081683 2.75553307 4.01349961 2.7545 1 P 0 ;0,1=511,2=0.000000
L 4.01349961 2.7545 4.01618307 2.7545 1 P 0 ;0,1=511,2=0.000000
L 4.01618307 2.7545 4.01886654 2.75553307 1 P 0 ;0,1=511,2=0.000000
L 4.01886654 2.75553307 4.02116673 2.75708278 1 P 0 ;0,1=511,2=0.000000
L 4.02116673 2.75708278 4.02308366 2.75914892 1 P 0 ;0,1=511,2=0.000000
L 4.04449961 2.7545 4.04449961 2.7855 1 P 0 ;0,1=511,2=0.000000
L 4.04449961 2.7855 4.0398999 2.7793003 1 P 0 ;0,1=511,2=0.000000
L 4.0398999 2.7545 4.04909931 2.7545 1 P 0 ;0,1=511,2=0.000000
L 4.06898287 2.75811585 4.07166634 2.75553307 1 P 0 ;0,1=511,2=0.000000
L 4.07166634 2.75553307 4.07473307 2.7545 1 P 0 ;0,1=511,2=0.000000
L 4.07473307 2.7545 4.0777998 2.75553307 1 P 0 ;0,1=511,2=0.000000
L 4.0777998 2.75553307 4.08048327 2.75863238 1 P 0 ;0,1=511,2=0.000000
L 4.08048327 2.75863238 4.0824002 2.76328327 1 P 0 ;0,1=511,2=0.000000
L 4.0824002 2.76328327 4.08316673 2.76793327 1 P 0 ;0,1=511,2=0.000000
L 4.08316673 2.76793327 4.08316673 2.77361634 1 P 0 ;0,1=511,2=0.000000
L 4.08316673 2.77361634 4.0824002 2.77826624 1 P 0 ;0,1=511,2=0.000000
L 4.0824002 2.77826624 4.08048327 2.7823997 1 P 0 ;0,1=511,2=0.000000
L 4.08048327 2.7823997 4.07818307 2.78446683 1 P 0 ;0,1=511,2=0.000000
L 4.07818307 2.78446683 4.07549961 2.7855 1 P 0 ;0,1=511,2=0.000000
L 4.07549961 2.7855 4.07243287 2.78446683 1 P 0 ;0,1=511,2=0.000000
L 4.07243287 2.78446683 4.07013337 2.7823997 1 P 0 ;0,1=511,2=0.000000
L 4.07013337 2.7823997 4.0685997 2.7793003 1 P 0 ;0,1=511,2=0.000000
L 4.0685997 2.7793003 4.06783317 2.77516594 1 P 0 ;0,1=511,2=0.000000
L 4.06783317 2.77516594 4.0685997 2.7715501 1 P 0 ;0,1=511,2=0.000000
L 4.0685997 2.7715501 4.07051663 2.76793327 1 P 0 ;0,1=511,2=0.000000
L 4.07051663 2.76793327 4.07281683 2.76586604 1 P 0 ;0,1=511,2=0.000000
L 4.07281683 2.76586604 4.07549961 2.76534951 1 P 0 ;0,1=511,2=0.000000
L 4.07549961 2.76534951 4.07856634 2.76638268 1 P 0 ;0,1=511,2=0.000000
L 4.07856634 2.76638268 4.08086654 2.76896634 1 P 0 ;0,1=511,2=0.000000
L 4.08086654 2.76896634 4.08316673 2.77361634 1 P 0 ;0,1=511,2=0.000000
L 4.09921644 2.78033346 4.10151663 2.78343278 1 P 0 ;0,1=511,2=0.000000
L 4.10151663 2.78343278 4.1042001 2.78498337 1 P 0 ;0,1=511,2=0.000000
L 4.1042001 2.78498337 4.10726683 2.7855 1 P 0 ;0,1=511,2=0.000000
L 4.10726683 2.7855 4.1111 2.78446683 1 P 0 ;0,1=511,2=0.000000
L 4.1111 2.78446683 4.11378346 2.78188307 1 P 0 ;0,1=511,2=0.000000
L 4.11378346 2.78188307 4.11455 2.77878376 1 P 0 ;0,1=511,2=0.000000
L 4.11455 2.77878376 4.11416673 2.77568258 1 P 0 ;0,1=511,2=0.000000
L 4.11416673 2.77568258 4.11263307 2.7730998 1 P 0 ;0,1=511,2=0.000000
L 4.11263307 2.7730998 4.10496663 2.76793327 1 P 0 ;0,1=511,2=0.000000
L 4.10496663 2.76793327 4.10151663 2.76431644 1 P 0 ;0,1=511,2=0.000000
L 4.10151663 2.76431644 4.09921644 2.75914892 1 P 0 ;0,1=511,2=0.000000
L 4.09921644 2.75914892 4.0984499 2.7545 1 P 0 ;0,1=511,2=0.000000
L 4.0984499 2.7545 4.11455 2.7545 1 P 0 ;0,1=511,2=0.000000
L 4.98943002 2.7945 4.98943002 2.7595 1 P 0 
L 4.98943002 2.7595 4.93656998 2.7595 1 P 0 
L 4.93656998 2.7595 4.93656998 2.7945 1 P 0 
L 4.93656998 2.7945 4.98943002 2.7945 1 P 0 
L 4.92193327 2.92291624 4.91963307 2.92446683 1 P 0 ;0,1=512,2=0.000000
L 4.91963307 2.92446683 4.9169503 2.9255 1 P 0 ;0,1=512,2=0.000000
L 4.9169503 2.9255 4.91388356 2.9255 1 P 0 ;0,1=512,2=0.000000
L 4.91388356 2.9255 4.91043287 2.92394931 1 P 0 ;0,1=512,2=0.000000
L 4.91043287 2.92394931 4.9077501 2.92136654 1 P 0 ;0,1=512,2=0.000000
L 4.9077501 2.92136654 4.90583317 2.91826624 1 P 0 ;0,1=512,2=0.000000
L 4.90583317 2.91826624 4.90429951 2.9130998 1 P 0 ;0,1=512,2=0.000000
L 4.90429951 2.9130998 4.90391624 2.9084498 1 P 0 ;0,1=512,2=0.000000
L 4.90391624 2.9084498 4.90468337 2.9037999 1 P 0 ;0,1=512,2=0.000000
L 4.90468337 2.9037999 4.90583317 2.90069961 1 P 0 ;0,1=512,2=0.000000
L 4.90583317 2.90069961 4.90813337 2.89759931 1 P 0 ;0,1=512,2=0.000000
L 4.90813337 2.89759931 4.91081683 2.89553307 1 P 0 ;0,1=512,2=0.000000
L 4.91081683 2.89553307 4.91349961 2.8945 1 P 0 ;0,1=512,2=0.000000
L 4.91349961 2.8945 4.91618307 2.8945 1 P 0 ;0,1=512,2=0.000000
L 4.91618307 2.8945 4.91886654 2.89553307 1 P 0 ;0,1=512,2=0.000000
L 4.91886654 2.89553307 4.92116673 2.89708278 1 P 0 ;0,1=512,2=0.000000
L 4.92116673 2.89708278 4.92308366 2.89914892 1 P 0 ;0,1=512,2=0.000000
L 4.94449961 2.8945 4.94449961 2.9255 1 P 0 ;0,1=512,2=0.000000
L 4.94449961 2.9255 4.9398999 2.9193003 1 P 0 ;0,1=512,2=0.000000
L 4.9398999 2.8945 4.94909931 2.8945 1 P 0 ;0,1=512,2=0.000000
L 4.96898287 2.89811585 4.97166634 2.89553307 1 P 0 ;0,1=512,2=0.000000
L 4.97166634 2.89553307 4.97473307 2.8945 1 P 0 ;0,1=512,2=0.000000
L 4.97473307 2.8945 4.9777998 2.89553307 1 P 0 ;0,1=512,2=0.000000
L 4.9777998 2.89553307 4.98048327 2.89863238 1 P 0 ;0,1=512,2=0.000000
L 4.98048327 2.89863238 4.9824002 2.90328327 1 P 0 ;0,1=512,2=0.000000
L 4.9824002 2.90328327 4.98316673 2.90793327 1 P 0 ;0,1=512,2=0.000000
L 4.98316673 2.90793327 4.98316673 2.91361634 1 P 0 ;0,1=512,2=0.000000
L 4.98316673 2.91361634 4.9824002 2.91826624 1 P 0 ;0,1=512,2=0.000000
L 4.9824002 2.91826624 4.98048327 2.9223997 1 P 0 ;0,1=512,2=0.000000
L 4.98048327 2.9223997 4.97818307 2.92446683 1 P 0 ;0,1=512,2=0.000000
L 4.97818307 2.92446683 4.97549961 2.9255 1 P 0 ;0,1=512,2=0.000000
L 4.97549961 2.9255 4.97243287 2.92446683 1 P 0 ;0,1=512,2=0.000000
L 4.97243287 2.92446683 4.97013337 2.9223997 1 P 0 ;0,1=512,2=0.000000
L 4.97013337 2.9223997 4.9685997 2.9193003 1 P 0 ;0,1=512,2=0.000000
L 4.9685997 2.9193003 4.96783317 2.91516594 1 P 0 ;0,1=512,2=0.000000
L 4.96783317 2.91516594 4.9685997 2.9115501 1 P 0 ;0,1=512,2=0.000000
L 4.9685997 2.9115501 4.97051663 2.90793327 1 P 0 ;0,1=512,2=0.000000
L 4.97051663 2.90793327 4.97281683 2.90586604 1 P 0 ;0,1=512,2=0.000000
L 4.97281683 2.90586604 4.97549961 2.90534951 1 P 0 ;0,1=512,2=0.000000
L 4.97549961 2.90534951 4.97856634 2.90638268 1 P 0 ;0,1=512,2=0.000000
L 4.97856634 2.90638268 4.98086654 2.90896634 1 P 0 ;0,1=512,2=0.000000
L 4.98086654 2.90896634 4.98316673 2.91361634 1 P 0 ;0,1=512,2=0.000000
L 5.00649961 2.8945 5.00649961 2.9255 1 P 0 ;0,1=512,2=0.000000
L 5.00649961 2.9255 5.0018999 2.9193003 1 P 0 ;0,1=512,2=0.000000
L 5.0018999 2.8945 5.01109931 2.8945 1 P 0 ;0,1=512,2=0.000000
L 3.9995 3.06356998 3.9645 3.06356998 1 P 0 
L 3.9645 3.06356998 3.9645 3.11643002 1 P 0 
L 3.9645 3.11643002 3.9995 3.11643002 1 P 0 
L 3.9995 3.11643002 3.9995 3.06356998 1 P 0 
L 4.04708376 3.11193327 4.04553317 3.10963307 1 P 0 ;0,1=513,2=270.000000
L 4.04553317 3.10963307 4.0445 3.1069503 1 P 0 ;0,1=513,2=270.000000
L 4.0445 3.1069503 4.0445 3.10388356 1 P 0 ;0,1=513,2=270.000000
L 4.0445 3.10388356 4.04605069 3.10043287 1 P 0 ;0,1=513,2=270.000000
L 4.04605069 3.10043287 4.04863346 3.0977501 1 P 0 ;0,1=513,2=270.000000
L 4.04863346 3.0977501 4.05173376 3.09583317 1 P 0 ;0,1=513,2=270.000000
L 4.05173376 3.09583317 4.0569002 3.09429951 1 P 0 ;0,1=513,2=270.000000
L 4.0569002 3.09429951 4.0615502 3.09391624 1 P 0 ;0,1=513,2=270.000000
L 4.0615502 3.09391624 4.0662001 3.09468337 1 P 0 ;0,1=513,2=270.000000
L 4.0662001 3.09468337 4.06930039 3.09583317 1 P 0 ;0,1=513,2=270.000000
L 4.06930039 3.09583317 4.07240069 3.09813337 1 P 0 ;0,1=513,2=270.000000
L 4.07240069 3.09813337 4.07446693 3.10081683 1 P 0 ;0,1=513,2=270.000000
L 4.07446693 3.10081683 4.0755 3.10349961 1 P 0 ;0,1=513,2=270.000000
L 4.0755 3.10349961 4.0755 3.10618307 1 P 0 ;0,1=513,2=270.000000
L 4.0755 3.10618307 4.07446693 3.10886654 1 P 0 ;0,1=513,2=270.000000
L 4.07446693 3.10886654 4.07291722 3.11116673 1 P 0 ;0,1=513,2=270.000000
L 4.07291722 3.11116673 4.07085108 3.11308366 1 P 0 ;0,1=513,2=270.000000
L 4.0755 3.13449961 4.0445 3.13449961 1 P 0 ;0,1=513,2=270.000000
L 4.0445 3.13449961 4.0506997 3.1298999 1 P 0 ;0,1=513,2=270.000000
L 4.0755 3.1298999 4.0755 3.13909931 1 P 0 ;0,1=513,2=270.000000
L 4.07188415 3.15898287 4.07446693 3.16166634 1 P 0 ;0,1=513,2=270.000000
L 4.07446693 3.16166634 4.0755 3.16473307 1 P 0 ;0,1=513,2=270.000000
L 4.0755 3.16473307 4.07446693 3.1677998 1 P 0 ;0,1=513,2=270.000000
L 4.07446693 3.1677998 4.07136762 3.17048327 1 P 0 ;0,1=513,2=270.000000
L 4.07136762 3.17048327 4.06671673 3.1724002 1 P 0 ;0,1=513,2=270.000000
L 4.06671673 3.1724002 4.06206673 3.17316673 1 P 0 ;0,1=513,2=270.000000
L 4.06206673 3.17316673 4.05638366 3.17316673 1 P 0 ;0,1=513,2=270.000000
L 4.05638366 3.17316673 4.05173376 3.1724002 1 P 0 ;0,1=513,2=270.000000
L 4.05173376 3.1724002 4.0476003 3.17048327 1 P 0 ;0,1=513,2=270.000000
L 4.0476003 3.17048327 4.04553317 3.16818307 1 P 0 ;0,1=513,2=270.000000
L 4.04553317 3.16818307 4.0445 3.16549961 1 P 0 ;0,1=513,2=270.000000
L 4.0445 3.16549961 4.04553317 3.16243287 1 P 0 ;0,1=513,2=270.000000
L 4.04553317 3.16243287 4.0476003 3.16013337 1 P 0 ;0,1=513,2=270.000000
L 4.0476003 3.16013337 4.0506997 3.1585997 1 P 0 ;0,1=513,2=270.000000
L 4.0506997 3.1585997 4.05483406 3.15783317 1 P 0 ;0,1=513,2=270.000000
L 4.05483406 3.15783317 4.0584499 3.1585997 1 P 0 ;0,1=513,2=270.000000
L 4.0584499 3.1585997 4.06206673 3.16051663 1 P 0 ;0,1=513,2=270.000000
L 4.06206673 3.16051663 4.06413396 3.16281683 1 P 0 ;0,1=513,2=270.000000
L 4.06413396 3.16281683 4.06465049 3.16549961 1 P 0 ;0,1=513,2=270.000000
L 4.06465049 3.16549961 4.06361732 3.16856634 1 P 0 ;0,1=513,2=270.000000
L 4.06361732 3.16856634 4.06103366 3.17086654 1 P 0 ;0,1=513,2=270.000000
L 4.06103366 3.17086654 4.05638366 3.17316673 1 P 0 ;0,1=513,2=270.000000
L 4.0445 3.19649961 4.04553317 3.19343287 1 P 0 ;0,1=513,2=270.000000
L 4.04553317 3.19343287 4.04811693 3.19113337 1 P 0 ;0,1=513,2=270.000000
L 4.04811693 3.19113337 4.05121624 3.1895997 1 P 0 ;0,1=513,2=270.000000
L 4.05121624 3.1895997 4.05535059 3.1884499 1 P 0 ;0,1=513,2=270.000000
L 4.05535059 3.1884499 4.06000049 3.18806663 1 P 0 ;0,1=513,2=270.000000
L 4.06000049 3.18806663 4.06465049 3.1884499 1 P 0 ;0,1=513,2=270.000000
L 4.06465049 3.1884499 4.06878386 3.1895997 1 P 0 ;0,1=513,2=270.000000
L 4.06878386 3.1895997 4.07188415 3.19113337 1 P 0 ;0,1=513,2=270.000000
L 4.07188415 3.19113337 4.07446693 3.19343287 1 P 0 ;0,1=513,2=270.000000
L 4.07446693 3.19343287 4.0755 3.19649961 1 P 0 ;0,1=513,2=270.000000
L 4.0755 3.19649961 4.07446693 3.19956634 1 P 0 ;0,1=513,2=270.000000
L 4.07446693 3.19956634 4.07188415 3.20186654 1 P 0 ;0,1=513,2=270.000000
L 4.07188415 3.20186654 4.06878386 3.2034002 1 P 0 ;0,1=513,2=270.000000
L 4.06878386 3.2034002 4.06465049 3.20455 1 P 0 ;0,1=513,2=270.000000
L 4.06465049 3.20455 4.06000049 3.20493327 1 P 0 ;0,1=513,2=270.000000
L 4.06000049 3.20493327 4.05535059 3.20455 1 P 0 ;0,1=513,2=270.000000
L 4.05535059 3.20455 4.05121624 3.2034002 1 P 0 ;0,1=513,2=270.000000
L 4.05121624 3.2034002 4.04811693 3.20186654 1 P 0 ;0,1=513,2=270.000000
L 4.04811693 3.20186654 4.04553317 3.19956634 1 P 0 ;0,1=513,2=270.000000
L 4.04553317 3.19956634 4.0445 3.19649961 1 P 0 ;0,1=513,2=270.000000
L 3.51156998 3.9295 3.51156998 3.9645 1 P 0 
L 3.51156998 3.9645 3.56443002 3.9645 1 P 0 
L 3.56443002 3.9645 3.56443002 3.9295 1 P 0 
L 3.56443002 3.9295 3.51156998 3.9295 1 P 0 
L 3.59043327 3.95491624 3.58813307 3.95646683 1 P 0 ;0,1=514,2=0.000000
L 3.58813307 3.95646683 3.5854503 3.9575 1 P 0 ;0,1=514,2=0.000000
L 3.5854503 3.9575 3.58238356 3.9575 1 P 0 ;0,1=514,2=0.000000
L 3.58238356 3.9575 3.57893287 3.95594931 1 P 0 ;0,1=514,2=0.000000
L 3.57893287 3.95594931 3.5762501 3.95336654 1 P 0 ;0,1=514,2=0.000000
L 3.5762501 3.95336654 3.57433317 3.95026624 1 P 0 ;0,1=514,2=0.000000
L 3.57433317 3.95026624 3.57279951 3.9450998 1 P 0 ;0,1=514,2=0.000000
L 3.57279951 3.9450998 3.57241624 3.9404498 1 P 0 ;0,1=514,2=0.000000
L 3.57241624 3.9404498 3.57318337 3.9357999 1 P 0 ;0,1=514,2=0.000000
L 3.57318337 3.9357999 3.57433317 3.93269961 1 P 0 ;0,1=514,2=0.000000
L 3.57433317 3.93269961 3.57663337 3.92959931 1 P 0 ;0,1=514,2=0.000000
L 3.57663337 3.92959931 3.57931683 3.92753307 1 P 0 ;0,1=514,2=0.000000
L 3.57931683 3.92753307 3.58199961 3.9265 1 P 0 ;0,1=514,2=0.000000
L 3.58199961 3.9265 3.58468307 3.9265 1 P 0 ;0,1=514,2=0.000000
L 3.58468307 3.9265 3.58736654 3.92753307 1 P 0 ;0,1=514,2=0.000000
L 3.58736654 3.92753307 3.58966673 3.92908278 1 P 0 ;0,1=514,2=0.000000
L 3.58966673 3.92908278 3.59158366 3.93114892 1 P 0 ;0,1=514,2=0.000000
L 3.60456663 3.93114892 3.60686614 3.92856614 1 P 0 ;0,1=514,2=0.000000
L 3.60686614 3.92856614 3.60954961 3.92701654 1 P 0 ;0,1=514,2=0.000000
L 3.60954961 3.92701654 3.61299961 3.9265 1 P 0 ;0,1=514,2=0.000000
L 3.61299961 3.9265 3.6164503 3.92753307 1 P 0 ;0,1=514,2=0.000000
L 3.6164503 3.92753307 3.61913307 3.92959931 1 P 0 ;0,1=514,2=0.000000
L 3.61913307 3.92959931 3.62105 3.93321614 1 P 0 ;0,1=514,2=0.000000
L 3.62105 3.93321614 3.62143327 3.93734951 1 P 0 ;0,1=514,2=0.000000
L 3.62143327 3.93734951 3.62066673 3.94148287 1 P 0 ;0,1=514,2=0.000000
L 3.62066673 3.94148287 3.6187498 3.94406663 1 P 0 ;0,1=514,2=0.000000
L 3.6187498 3.94406663 3.61606634 3.94613287 1 P 0 ;0,1=514,2=0.000000
L 3.61606634 3.94613287 3.61338356 3.94664941 1 P 0 ;0,1=514,2=0.000000
L 3.61338356 3.94664941 3.6107001 3.94613287 1 P 0 ;0,1=514,2=0.000000
L 3.6107001 3.94613287 3.6072501 3.94406663 1 P 0 ;0,1=514,2=0.000000
L 3.6072501 3.94406663 3.6083999 3.9575 1 P 0 ;0,1=514,2=0.000000
L 3.6083999 3.9575 3.6187498 3.9575 1 P 0 ;0,1=514,2=0.000000
L 3.63556663 3.93114892 3.63786614 3.92856614 1 P 0 ;0,1=514,2=0.000000
L 3.63786614 3.92856614 3.64054961 3.92701654 1 P 0 ;0,1=514,2=0.000000
L 3.64054961 3.92701654 3.64399961 3.9265 1 P 0 ;0,1=514,2=0.000000
L 3.64399961 3.9265 3.6474503 3.92753307 1 P 0 ;0,1=514,2=0.000000
L 3.6474503 3.92753307 3.65013307 3.92959931 1 P 0 ;0,1=514,2=0.000000
L 3.65013307 3.92959931 3.65205 3.93321614 1 P 0 ;0,1=514,2=0.000000
L 3.65205 3.93321614 3.65243327 3.93734951 1 P 0 ;0,1=514,2=0.000000
L 3.65243327 3.93734951 3.65166673 3.94148287 1 P 0 ;0,1=514,2=0.000000
L 3.65166673 3.94148287 3.6497498 3.94406663 1 P 0 ;0,1=514,2=0.000000
L 3.6497498 3.94406663 3.64706634 3.94613287 1 P 0 ;0,1=514,2=0.000000
L 3.64706634 3.94613287 3.64438356 3.94664941 1 P 0 ;0,1=514,2=0.000000
L 3.64438356 3.94664941 3.6417001 3.94613287 1 P 0 ;0,1=514,2=0.000000
L 3.6417001 3.94613287 3.6382501 3.94406663 1 P 0 ;0,1=514,2=0.000000
L 3.6382501 3.94406663 3.6393999 3.9575 1 P 0 ;0,1=514,2=0.000000
L 3.6393999 3.9575 3.6497498 3.9575 1 P 0 ;0,1=514,2=0.000000
L 3.51156998 3.9095 3.56443002 3.9095 1 P 0 
L 3.56443002 3.9095 3.56443002 3.8745 1 P 0 
L 3.56443002 3.8745 3.51156998 3.8745 1 P 0 
L 3.51156998 3.8745 3.51156998 3.9095 1 P 0 
L 3.59043327 3.79491624 3.58813307 3.79646683 1 P 0 ;0,1=515,2=0.000000
L 3.58813307 3.79646683 3.5854503 3.7975 1 P 0 ;0,1=515,2=0.000000
L 3.5854503 3.7975 3.58238356 3.7975 1 P 0 ;0,1=515,2=0.000000
L 3.58238356 3.7975 3.57893287 3.79594931 1 P 0 ;0,1=515,2=0.000000
L 3.57893287 3.79594931 3.5762501 3.79336654 1 P 0 ;0,1=515,2=0.000000
L 3.5762501 3.79336654 3.57433317 3.79026624 1 P 0 ;0,1=515,2=0.000000
L 3.57433317 3.79026624 3.57279951 3.7850998 1 P 0 ;0,1=515,2=0.000000
L 3.57279951 3.7850998 3.57241624 3.7804498 1 P 0 ;0,1=515,2=0.000000
L 3.57241624 3.7804498 3.57318337 3.7757999 1 P 0 ;0,1=515,2=0.000000
L 3.57318337 3.7757999 3.57433317 3.77269961 1 P 0 ;0,1=515,2=0.000000
L 3.57433317 3.77269961 3.57663337 3.76959931 1 P 0 ;0,1=515,2=0.000000
L 3.57663337 3.76959931 3.57931683 3.76753307 1 P 0 ;0,1=515,2=0.000000
L 3.57931683 3.76753307 3.58199961 3.7665 1 P 0 ;0,1=515,2=0.000000
L 3.58199961 3.7665 3.58468307 3.7665 1 P 0 ;0,1=515,2=0.000000
L 3.58468307 3.7665 3.58736654 3.76753307 1 P 0 ;0,1=515,2=0.000000
L 3.58736654 3.76753307 3.58966673 3.76908278 1 P 0 ;0,1=515,2=0.000000
L 3.58966673 3.76908278 3.59158366 3.77114892 1 P 0 ;0,1=515,2=0.000000
L 3.61299961 3.7665 3.61299961 3.7975 1 P 0 ;0,1=515,2=0.000000
L 3.61299961 3.7975 3.6083999 3.7913003 1 P 0 ;0,1=515,2=0.000000
L 3.6083999 3.7665 3.61759931 3.7665 1 P 0 ;0,1=515,2=0.000000
L 3.63671644 3.77941575 3.6393999 3.78303356 1 P 0 ;0,1=515,2=0.000000
L 3.6393999 3.78303356 3.6417001 3.7850998 1 P 0 ;0,1=515,2=0.000000
L 3.6417001 3.7850998 3.64476683 3.78613287 1 P 0 ;0,1=515,2=0.000000
L 3.64476683 3.78613287 3.6474503 3.7850998 1 P 0 ;0,1=515,2=0.000000
L 3.6474503 3.7850998 3.64936654 3.78303356 1 P 0 ;0,1=515,2=0.000000
L 3.64936654 3.78303356 3.6509002 3.77993327 1 P 0 ;0,1=515,2=0.000000
L 3.6509002 3.77993327 3.65128346 3.77631644 1 P 0 ;0,1=515,2=0.000000
L 3.65128346 3.77631644 3.6509002 3.77321614 1 P 0 ;0,1=515,2=0.000000
L 3.6509002 3.77321614 3.64936654 3.77011585 1 P 0 ;0,1=515,2=0.000000
L 3.64936654 3.77011585 3.64706634 3.76753307 1 P 0 ;0,1=515,2=0.000000
L 3.64706634 3.76753307 3.64438356 3.7665 1 P 0 ;0,1=515,2=0.000000
L 3.64438356 3.7665 3.64131683 3.76753307 1 P 0 ;0,1=515,2=0.000000
L 3.64131683 3.76753307 3.63863337 3.77063238 1 P 0 ;0,1=515,2=0.000000
L 3.63863337 3.77063238 3.6370997 3.77528327 1 P 0 ;0,1=515,2=0.000000
L 3.6370997 3.77528327 3.63671644 3.7804498 1 P 0 ;0,1=515,2=0.000000
L 3.63671644 3.7804498 3.63748287 3.78716594 1 P 0 ;0,1=515,2=0.000000
L 3.63748287 3.78716594 3.63863337 3.79078376 1 P 0 ;0,1=515,2=0.000000
L 3.63863337 3.79078376 3.64054961 3.7943997 1 P 0 ;0,1=515,2=0.000000
L 3.64054961 3.7943997 3.64323307 3.79698337 1 P 0 ;0,1=515,2=0.000000
L 3.64323307 3.79698337 3.64591654 3.7975 1 P 0 ;0,1=515,2=0.000000
L 3.64591654 3.7975 3.6486 3.79646683 1 P 0 ;0,1=515,2=0.000000
L 3.6486 3.79646683 3.65051703 3.79388307 1 P 0 ;0,1=515,2=0.000000
L 3.56343002 4.1385 3.56343002 4.1035 1 P 0 
L 3.56343002 4.1035 3.51056998 4.1035 1 P 0 
L 3.51056998 4.1035 3.51056998 4.1385 1 P 0 
L 3.51056998 4.1385 3.56343002 4.1385 1 P 0 
L 3.58243327 4.16291624 3.58013307 4.16446683 1 P 0 ;0,1=516,2=0.000000
L 3.58013307 4.16446683 3.5774503 4.1655 1 P 0 ;0,1=516,2=0.000000
L 3.5774503 4.1655 3.57438356 4.1655 1 P 0 ;0,1=516,2=0.000000
L 3.57438356 4.1655 3.57093287 4.16394931 1 P 0 ;0,1=516,2=0.000000
L 3.57093287 4.16394931 3.5682501 4.16136654 1 P 0 ;0,1=516,2=0.000000
L 3.5682501 4.16136654 3.56633317 4.15826624 1 P 0 ;0,1=516,2=0.000000
L 3.56633317 4.15826624 3.56479951 4.1530998 1 P 0 ;0,1=516,2=0.000000
L 3.56479951 4.1530998 3.56441624 4.1484498 1 P 0 ;0,1=516,2=0.000000
L 3.56441624 4.1484498 3.56518337 4.1437999 1 P 0 ;0,1=516,2=0.000000
L 3.56518337 4.1437999 3.56633317 4.14069961 1 P 0 ;0,1=516,2=0.000000
L 3.56633317 4.14069961 3.56863337 4.13759931 1 P 0 ;0,1=516,2=0.000000
L 3.56863337 4.13759931 3.57131683 4.13553307 1 P 0 ;0,1=516,2=0.000000
L 3.57131683 4.13553307 3.57399961 4.1345 1 P 0 ;0,1=516,2=0.000000
L 3.57399961 4.1345 3.57668307 4.1345 1 P 0 ;0,1=516,2=0.000000
L 3.57668307 4.1345 3.57936654 4.13553307 1 P 0 ;0,1=516,2=0.000000
L 3.57936654 4.13553307 3.58166673 4.13708278 1 P 0 ;0,1=516,2=0.000000
L 3.58166673 4.13708278 3.58358366 4.13914892 1 P 0 ;0,1=516,2=0.000000
L 3.60423307 4.1345 3.60499961 4.14121614 1 P 0 ;0,1=516,2=0.000000
L 3.60499961 4.14121614 3.6061501 4.14689921 1 P 0 ;0,1=516,2=0.000000
L 3.6061501 4.14689921 3.60768307 4.15206663 1 P 0 ;0,1=516,2=0.000000
L 3.60768307 4.15206663 3.6096 4.1577497 1 P 0 ;0,1=516,2=0.000000
L 3.6096 4.1577497 3.61266673 4.1655 1 P 0 ;0,1=516,2=0.000000
L 3.61266673 4.1655 3.59733317 4.1655 1 P 0 ;0,1=516,2=0.000000
L 3.63523307 4.1345 3.63599961 4.14121614 1 P 0 ;0,1=516,2=0.000000
L 3.63599961 4.14121614 3.6371501 4.14689921 1 P 0 ;0,1=516,2=0.000000
L 3.6371501 4.14689921 3.63868307 4.15206663 1 P 0 ;0,1=516,2=0.000000
L 3.63868307 4.15206663 3.6406 4.1577497 1 P 0 ;0,1=516,2=0.000000
L 3.6406 4.1577497 3.64366673 4.1655 1 P 0 ;0,1=516,2=0.000000
L 3.64366673 4.1655 3.62833317 4.1655 1 P 0 ;0,1=516,2=0.000000
L 5.25356998 2.7075 5.25356998 2.7425 1 P 0 
L 5.25356998 2.7425 5.30643002 2.7425 1 P 0 
L 5.30643002 2.7425 5.30643002 2.7075 1 P 0 
L 5.30643002 2.7075 5.25356998 2.7075 1 P 0 
L 5.27693327 2.87291624 5.27463307 2.87446683 1 P 0 ;0,1=517,2=0.000000
L 5.27463307 2.87446683 5.2719503 2.8755 1 P 0 ;0,1=517,2=0.000000
L 5.2719503 2.8755 5.26888356 2.8755 1 P 0 ;0,1=517,2=0.000000
L 5.26888356 2.8755 5.26543287 2.87394931 1 P 0 ;0,1=517,2=0.000000
L 5.26543287 2.87394931 5.2627501 2.87136654 1 P 0 ;0,1=517,2=0.000000
L 5.2627501 2.87136654 5.26083317 2.86826624 1 P 0 ;0,1=517,2=0.000000
L 5.26083317 2.86826624 5.25929951 2.8630998 1 P 0 ;0,1=517,2=0.000000
L 5.25929951 2.8630998 5.25891624 2.8584498 1 P 0 ;0,1=517,2=0.000000
L 5.25891624 2.8584498 5.25968337 2.8537999 1 P 0 ;0,1=517,2=0.000000
L 5.25968337 2.8537999 5.26083317 2.85069961 1 P 0 ;0,1=517,2=0.000000
L 5.26083317 2.85069961 5.26313337 2.84759931 1 P 0 ;0,1=517,2=0.000000
L 5.26313337 2.84759931 5.26581683 2.84553307 1 P 0 ;0,1=517,2=0.000000
L 5.26581683 2.84553307 5.26849961 2.8445 1 P 0 ;0,1=517,2=0.000000
L 5.26849961 2.8445 5.27118307 2.8445 1 P 0 ;0,1=517,2=0.000000
L 5.27118307 2.8445 5.27386654 2.84553307 1 P 0 ;0,1=517,2=0.000000
L 5.27386654 2.84553307 5.27616673 2.84708278 1 P 0 ;0,1=517,2=0.000000
L 5.27616673 2.84708278 5.27808366 2.84914892 1 P 0 ;0,1=517,2=0.000000
L 5.29949961 2.8445 5.29949961 2.8755 1 P 0 ;0,1=517,2=0.000000
L 5.29949961 2.8755 5.2948999 2.8693003 1 P 0 ;0,1=517,2=0.000000
L 5.2948999 2.8445 5.30409931 2.8445 1 P 0 ;0,1=517,2=0.000000
L 5.32398287 2.84811585 5.32666634 2.84553307 1 P 0 ;0,1=517,2=0.000000
L 5.32666634 2.84553307 5.32973307 2.8445 1 P 0 ;0,1=517,2=0.000000
L 5.32973307 2.8445 5.3327998 2.84553307 1 P 0 ;0,1=517,2=0.000000
L 5.3327998 2.84553307 5.33548327 2.84863238 1 P 0 ;0,1=517,2=0.000000
L 5.33548327 2.84863238 5.3374002 2.85328327 1 P 0 ;0,1=517,2=0.000000
L 5.3374002 2.85328327 5.33816673 2.85793327 1 P 0 ;0,1=517,2=0.000000
L 5.33816673 2.85793327 5.33816673 2.86361634 1 P 0 ;0,1=517,2=0.000000
L 5.33816673 2.86361634 5.3374002 2.86826624 1 P 0 ;0,1=517,2=0.000000
L 5.3374002 2.86826624 5.33548327 2.8723997 1 P 0 ;0,1=517,2=0.000000
L 5.33548327 2.8723997 5.33318307 2.87446683 1 P 0 ;0,1=517,2=0.000000
L 5.33318307 2.87446683 5.33049961 2.8755 1 P 0 ;0,1=517,2=0.000000
L 5.33049961 2.8755 5.32743287 2.87446683 1 P 0 ;0,1=517,2=0.000000
L 5.32743287 2.87446683 5.32513337 2.8723997 1 P 0 ;0,1=517,2=0.000000
L 5.32513337 2.8723997 5.3235997 2.8693003 1 P 0 ;0,1=517,2=0.000000
L 5.3235997 2.8693003 5.32283317 2.86516594 1 P 0 ;0,1=517,2=0.000000
L 5.32283317 2.86516594 5.3235997 2.8615501 1 P 0 ;0,1=517,2=0.000000
L 5.3235997 2.8615501 5.32551663 2.85793327 1 P 0 ;0,1=517,2=0.000000
L 5.32551663 2.85793327 5.32781683 2.85586604 1 P 0 ;0,1=517,2=0.000000
L 5.32781683 2.85586604 5.33049961 2.85534951 1 P 0 ;0,1=517,2=0.000000
L 5.33049961 2.85534951 5.33356634 2.85638268 1 P 0 ;0,1=517,2=0.000000
L 5.33356634 2.85638268 5.33586654 2.85896634 1 P 0 ;0,1=517,2=0.000000
L 5.33586654 2.85896634 5.33816673 2.86361634 1 P 0 ;0,1=517,2=0.000000
L 5.35306663 2.85069961 5.35536614 2.84708278 1 P 0 ;0,1=517,2=0.000000
L 5.35536614 2.84708278 5.35843287 2.84501654 1 P 0 ;0,1=517,2=0.000000
L 5.35843287 2.84501654 5.36188356 2.8445 1 P 0 ;0,1=517,2=0.000000
L 5.36188356 2.8445 5.3649503 2.84501654 1 P 0 ;0,1=517,2=0.000000
L 5.3649503 2.84501654 5.36801703 2.84759931 1 P 0 ;0,1=517,2=0.000000
L 5.36801703 2.84759931 5.36993327 2.85069961 1 P 0 ;0,1=517,2=0.000000
L 5.36993327 2.85069961 5.37031654 2.8537999 1 P 0 ;0,1=517,2=0.000000
L 5.37031654 2.8537999 5.36955 2.85741575 1 P 0 ;0,1=517,2=0.000000
L 5.36955 2.85741575 5.36686654 2.85999951 1 P 0 ;0,1=517,2=0.000000
L 5.36686654 2.85999951 5.36418307 2.86103356 1 P 0 ;0,1=517,2=0.000000
L 5.36418307 2.86103356 5.36073307 2.86103356 1 P 0 ;0,1=517,2=0.000000
L 5.36418307 2.86103356 5.36648327 2.86258317 1 P 0 ;0,1=517,2=0.000000
L 5.36648327 2.86258317 5.3684002 2.86516594 1 P 0 ;0,1=517,2=0.000000
L 5.3684002 2.86516594 5.36916673 2.86826624 1 P 0 ;0,1=517,2=0.000000
L 5.36916673 2.86826624 5.3684002 2.87136654 1 P 0 ;0,1=517,2=0.000000
L 5.3684002 2.87136654 5.36648327 2.87394931 1 P 0 ;0,1=517,2=0.000000
L 5.36648327 2.87394931 5.36303327 2.8755 1 P 0 ;0,1=517,2=0.000000
L 5.36303327 2.8755 5.35958337 2.87498337 1 P 0 ;0,1=517,2=0.000000
L 5.35958337 2.87498337 5.35613337 2.87291624 1 P 0 ;0,1=517,2=0.000000
L 5.4925 2.36643002 5.5275 2.36643002 1 P 0 
L 5.4925 2.31356998 5.4925 2.36643002 1 P 0 
L 5.5275 2.31356998 5.4925 2.31356998 1 P 0 
L 5.5275 2.36643002 5.5275 2.31356998 1 P 0 
L 5.43208376 2.42693327 5.43053317 2.42463307 1 P 0 ;0,1=518,2=270.000000
L 5.43053317 2.42463307 5.4295 2.4219503 1 P 0 ;0,1=518,2=270.000000
L 5.4295 2.4219503 5.4295 2.41888356 1 P 0 ;0,1=518,2=270.000000
L 5.4295 2.41888356 5.43105069 2.41543287 1 P 0 ;0,1=518,2=270.000000
L 5.43105069 2.41543287 5.43363346 2.4127501 1 P 0 ;0,1=518,2=270.000000
L 5.43363346 2.4127501 5.43673376 2.41083317 1 P 0 ;0,1=518,2=270.000000
L 5.43673376 2.41083317 5.4419002 2.40929951 1 P 0 ;0,1=518,2=270.000000
L 5.4419002 2.40929951 5.4465502 2.40891624 1 P 0 ;0,1=518,2=270.000000
L 5.4465502 2.40891624 5.4512001 2.40968337 1 P 0 ;0,1=518,2=270.000000
L 5.4512001 2.40968337 5.45430039 2.41083317 1 P 0 ;0,1=518,2=270.000000
L 5.45430039 2.41083317 5.45740069 2.41313337 1 P 0 ;0,1=518,2=270.000000
L 5.45740069 2.41313337 5.45946693 2.41581683 1 P 0 ;0,1=518,2=270.000000
L 5.45946693 2.41581683 5.4605 2.41849961 1 P 0 ;0,1=518,2=270.000000
L 5.4605 2.41849961 5.4605 2.42118307 1 P 0 ;0,1=518,2=270.000000
L 5.4605 2.42118307 5.45946693 2.42386654 1 P 0 ;0,1=518,2=270.000000
L 5.45946693 2.42386654 5.45791722 2.42616673 1 P 0 ;0,1=518,2=270.000000
L 5.45791722 2.42616673 5.45585108 2.42808366 1 P 0 ;0,1=518,2=270.000000
L 5.43466654 2.44221644 5.43156722 2.44451663 1 P 0 ;0,1=518,2=270.000000
L 5.43156722 2.44451663 5.43001663 2.4472001 1 P 0 ;0,1=518,2=270.000000
L 5.43001663 2.4472001 5.4295 2.45026683 1 P 0 ;0,1=518,2=270.000000
L 5.4295 2.45026683 5.43053317 2.4541 1 P 0 ;0,1=518,2=270.000000
L 5.43053317 2.4541 5.43311693 2.45678346 1 P 0 ;0,1=518,2=270.000000
L 5.43311693 2.45678346 5.43621624 2.45755 1 P 0 ;0,1=518,2=270.000000
L 5.43621624 2.45755 5.43931742 2.45716673 1 P 0 ;0,1=518,2=270.000000
L 5.43931742 2.45716673 5.4419002 2.45563307 1 P 0 ;0,1=518,2=270.000000
L 5.4419002 2.45563307 5.44706673 2.44796663 1 P 0 ;0,1=518,2=270.000000
L 5.44706673 2.44796663 5.45068356 2.44451663 1 P 0 ;0,1=518,2=270.000000
L 5.45068356 2.44451663 5.45585108 2.44221644 1 P 0 ;0,1=518,2=270.000000
L 5.45585108 2.44221644 5.4605 2.4414499 1 P 0 ;0,1=518,2=270.000000
L 5.4605 2.4414499 5.4605 2.45755 1 P 0 ;0,1=518,2=270.000000
L 5.45585108 2.47206663 5.45843386 2.47436614 1 P 0 ;0,1=518,2=270.000000
L 5.45843386 2.47436614 5.45998346 2.47704961 1 P 0 ;0,1=518,2=270.000000
L 5.45998346 2.47704961 5.4605 2.48049961 1 P 0 ;0,1=518,2=270.000000
L 5.4605 2.48049961 5.45946693 2.4839503 1 P 0 ;0,1=518,2=270.000000
L 5.45946693 2.4839503 5.45740069 2.48663307 1 P 0 ;0,1=518,2=270.000000
L 5.45740069 2.48663307 5.45378386 2.48855 1 P 0 ;0,1=518,2=270.000000
L 5.45378386 2.48855 5.44965049 2.48893327 1 P 0 ;0,1=518,2=270.000000
L 5.44965049 2.48893327 5.44551713 2.48816673 1 P 0 ;0,1=518,2=270.000000
L 5.44551713 2.48816673 5.44293337 2.4862498 1 P 0 ;0,1=518,2=270.000000
L 5.44293337 2.4862498 5.44086713 2.48356634 1 P 0 ;0,1=518,2=270.000000
L 5.44086713 2.48356634 5.44035059 2.48088356 1 P 0 ;0,1=518,2=270.000000
L 5.44035059 2.48088356 5.44086713 2.4782001 1 P 0 ;0,1=518,2=270.000000
L 5.44086713 2.4782001 5.44293337 2.4747501 1 P 0 ;0,1=518,2=270.000000
L 5.44293337 2.4747501 5.4295 2.4758999 1 P 0 ;0,1=518,2=270.000000
L 5.4295 2.4758999 5.4295 2.4862498 1 P 0 ;0,1=518,2=270.000000
L 5.4605 2.51149961 5.45998346 2.51418307 1 P 0 ;0,1=518,2=270.000000
L 5.45998346 2.51418307 5.45843386 2.5172498 1 P 0 ;0,1=518,2=270.000000
L 5.45843386 2.5172498 5.45585108 2.51916673 1 P 0 ;0,1=518,2=270.000000
L 5.45585108 2.51916673 5.45223327 2.51993327 1 P 0 ;0,1=518,2=270.000000
L 5.45223327 2.51993327 5.44861732 2.51916673 1 P 0 ;0,1=518,2=270.000000
L 5.44861732 2.51916673 5.44551713 2.51686654 1 P 0 ;0,1=518,2=270.000000
L 5.44551713 2.51686654 5.44396644 2.51341654 1 P 0 ;0,1=518,2=270.000000
L 5.44396644 2.51341654 5.44396644 2.50958337 1 P 0 ;0,1=518,2=270.000000
L 5.44396644 2.50958337 5.44293337 2.50728317 1 P 0 ;0,1=518,2=270.000000
L 5.44293337 2.50728317 5.44035059 2.50536614 1 P 0 ;0,1=518,2=270.000000
L 5.44035059 2.50536614 5.43673376 2.5045997 1 P 0 ;0,1=518,2=270.000000
L 5.43673376 2.5045997 5.43311693 2.5057501 1 P 0 ;0,1=518,2=270.000000
L 5.43311693 2.5057501 5.43053317 2.50843287 1 P 0 ;0,1=518,2=270.000000
L 5.43053317 2.50843287 5.4295 2.51149961 1 P 0 ;0,1=518,2=270.000000
L 5.4295 2.51149961 5.43053317 2.51456634 1 P 0 ;0,1=518,2=270.000000
L 5.43053317 2.51456634 5.43311693 2.5172498 1 P 0 ;0,1=518,2=270.000000
L 5.43311693 2.5172498 5.43673376 2.5184002 1 P 0 ;0,1=518,2=270.000000
L 5.43673376 2.5184002 5.44035059 2.51763307 1 P 0 ;0,1=518,2=270.000000
L 5.44035059 2.51763307 5.44293337 2.51571673 1 P 0 ;0,1=518,2=270.000000
L 5.44293337 2.51571673 5.44396644 2.51341654 1 P 0 ;0,1=518,2=270.000000
L 5.44396644 2.51341654 5.44396644 2.50958337 1 P 0 ;0,1=518,2=270.000000
L 5.44396644 2.50958337 5.44551713 2.50613337 1 P 0 ;0,1=518,2=270.000000
L 5.44551713 2.50613337 5.44861732 2.50383317 1 P 0 ;0,1=518,2=270.000000
L 5.44861732 2.50383317 5.45223327 2.50306663 1 P 0 ;0,1=518,2=270.000000
L 5.45223327 2.50306663 5.45585108 2.50383317 1 P 0 ;0,1=518,2=270.000000
L 5.45585108 2.50383317 5.45843386 2.5057501 1 P 0 ;0,1=518,2=270.000000
L 5.45843386 2.5057501 5.45998346 2.50881683 1 P 0 ;0,1=518,2=270.000000
L 5.45998346 2.50881683 5.4605 2.51149961 1 P 0 ;0,1=518,2=270.000000
L 5.6225 2.36643002 5.6575 2.36643002 1 P 0 
L 5.6575 2.36643002 5.6575 2.31356998 1 P 0 
L 5.6225 2.31356998 5.6225 2.36643002 1 P 0 
L 5.6575 2.31356998 5.6225 2.31356998 1 P 0 
L 5.55208376 2.42693327 5.55053317 2.42463307 1 P 0 ;0,1=519,2=270.000000
L 5.55053317 2.42463307 5.5495 2.4219503 1 P 0 ;0,1=519,2=270.000000
L 5.5495 2.4219503 5.5495 2.41888356 1 P 0 ;0,1=519,2=270.000000
L 5.5495 2.41888356 5.55105069 2.41543287 1 P 0 ;0,1=519,2=270.000000
L 5.55105069 2.41543287 5.55363346 2.4127501 1 P 0 ;0,1=519,2=270.000000
L 5.55363346 2.4127501 5.55673376 2.41083317 1 P 0 ;0,1=519,2=270.000000
L 5.55673376 2.41083317 5.5619002 2.40929951 1 P 0 ;0,1=519,2=270.000000
L 5.5619002 2.40929951 5.5665502 2.40891624 1 P 0 ;0,1=519,2=270.000000
L 5.5665502 2.40891624 5.5712001 2.40968337 1 P 0 ;0,1=519,2=270.000000
L 5.5712001 2.40968337 5.57430039 2.41083317 1 P 0 ;0,1=519,2=270.000000
L 5.57430039 2.41083317 5.57740069 2.41313337 1 P 0 ;0,1=519,2=270.000000
L 5.57740069 2.41313337 5.57946693 2.41581683 1 P 0 ;0,1=519,2=270.000000
L 5.57946693 2.41581683 5.5805 2.41849961 1 P 0 ;0,1=519,2=270.000000
L 5.5805 2.41849961 5.5805 2.42118307 1 P 0 ;0,1=519,2=270.000000
L 5.5805 2.42118307 5.57946693 2.42386654 1 P 0 ;0,1=519,2=270.000000
L 5.57946693 2.42386654 5.57791722 2.42616673 1 P 0 ;0,1=519,2=270.000000
L 5.57791722 2.42616673 5.57585108 2.42808366 1 P 0 ;0,1=519,2=270.000000
L 5.55466654 2.44221644 5.55156722 2.44451663 1 P 0 ;0,1=519,2=270.000000
L 5.55156722 2.44451663 5.55001663 2.4472001 1 P 0 ;0,1=519,2=270.000000
L 5.55001663 2.4472001 5.5495 2.45026683 1 P 0 ;0,1=519,2=270.000000
L 5.5495 2.45026683 5.55053317 2.4541 1 P 0 ;0,1=519,2=270.000000
L 5.55053317 2.4541 5.55311693 2.45678346 1 P 0 ;0,1=519,2=270.000000
L 5.55311693 2.45678346 5.55621624 2.45755 1 P 0 ;0,1=519,2=270.000000
L 5.55621624 2.45755 5.55931742 2.45716673 1 P 0 ;0,1=519,2=270.000000
L 5.55931742 2.45716673 5.5619002 2.45563307 1 P 0 ;0,1=519,2=270.000000
L 5.5619002 2.45563307 5.56706673 2.44796663 1 P 0 ;0,1=519,2=270.000000
L 5.56706673 2.44796663 5.57068356 2.44451663 1 P 0 ;0,1=519,2=270.000000
L 5.57068356 2.44451663 5.57585108 2.44221644 1 P 0 ;0,1=519,2=270.000000
L 5.57585108 2.44221644 5.5805 2.4414499 1 P 0 ;0,1=519,2=270.000000
L 5.5805 2.4414499 5.5805 2.45755 1 P 0 ;0,1=519,2=270.000000
L 5.56758425 2.47321644 5.56396644 2.4758999 1 P 0 ;0,1=519,2=270.000000
L 5.56396644 2.4758999 5.5619002 2.4782001 1 P 0 ;0,1=519,2=270.000000
L 5.5619002 2.4782001 5.56086713 2.48126683 1 P 0 ;0,1=519,2=270.000000
L 5.56086713 2.48126683 5.5619002 2.4839503 1 P 0 ;0,1=519,2=270.000000
L 5.5619002 2.4839503 5.56396644 2.48586654 1 P 0 ;0,1=519,2=270.000000
L 5.56396644 2.48586654 5.56706673 2.4874002 1 P 0 ;0,1=519,2=270.000000
L 5.56706673 2.4874002 5.57068356 2.48778346 1 P 0 ;0,1=519,2=270.000000
L 5.57068356 2.48778346 5.57378386 2.4874002 1 P 0 ;0,1=519,2=270.000000
L 5.57378386 2.4874002 5.57688415 2.48586654 1 P 0 ;0,1=519,2=270.000000
L 5.57688415 2.48586654 5.57946693 2.48356634 1 P 0 ;0,1=519,2=270.000000
L 5.57946693 2.48356634 5.5805 2.48088356 1 P 0 ;0,1=519,2=270.000000
L 5.5805 2.48088356 5.57946693 2.47781683 1 P 0 ;0,1=519,2=270.000000
L 5.57946693 2.47781683 5.57636762 2.47513337 1 P 0 ;0,1=519,2=270.000000
L 5.57636762 2.47513337 5.57171673 2.4735997 1 P 0 ;0,1=519,2=270.000000
L 5.57171673 2.4735997 5.5665502 2.47321644 1 P 0 ;0,1=519,2=270.000000
L 5.5665502 2.47321644 5.55983406 2.47398287 1 P 0 ;0,1=519,2=270.000000
L 5.55983406 2.47398287 5.55621624 2.47513337 1 P 0 ;0,1=519,2=270.000000
L 5.55621624 2.47513337 5.5526003 2.47704961 1 P 0 ;0,1=519,2=270.000000
L 5.5526003 2.47704961 5.55001663 2.47973307 1 P 0 ;0,1=519,2=270.000000
L 5.55001663 2.47973307 5.5495 2.48241654 1 P 0 ;0,1=519,2=270.000000
L 5.5495 2.48241654 5.55053317 2.4851 1 P 0 ;0,1=519,2=270.000000
L 5.55053317 2.4851 5.55311693 2.48701703 1 P 0 ;0,1=519,2=270.000000
L 5.5805 2.5161 5.5495 2.5161 1 P 0 ;0,1=519,2=270.000000
L 5.5495 2.5161 5.57171673 2.50191624 1 P 0 ;0,1=519,2=270.000000
L 5.57171673 2.50191624 5.57171673 2.52108366 1 P 0 ;0,1=519,2=270.000000
L 5.6775 2.37143002 5.7125 2.37143002 1 P 0 
L 5.6775 2.31856998 5.6775 2.37143002 1 P 0 
L 5.7125 2.31856998 5.6775 2.31856998 1 P 0 
L 5.7125 2.37143002 5.7125 2.31856998 1 P 0 
L 5.59708376 2.42693327 5.59553317 2.42463307 1 P 0 ;0,1=520,2=270.000000
L 5.59553317 2.42463307 5.5945 2.4219503 1 P 0 ;0,1=520,2=270.000000
L 5.5945 2.4219503 5.5945 2.41888356 1 P 0 ;0,1=520,2=270.000000
L 5.5945 2.41888356 5.59605069 2.41543287 1 P 0 ;0,1=520,2=270.000000
L 5.59605069 2.41543287 5.59863346 2.4127501 1 P 0 ;0,1=520,2=270.000000
L 5.59863346 2.4127501 5.60173376 2.41083317 1 P 0 ;0,1=520,2=270.000000
L 5.60173376 2.41083317 5.6069002 2.40929951 1 P 0 ;0,1=520,2=270.000000
L 5.6069002 2.40929951 5.6115502 2.40891624 1 P 0 ;0,1=520,2=270.000000
L 5.6115502 2.40891624 5.6162001 2.40968337 1 P 0 ;0,1=520,2=270.000000
L 5.6162001 2.40968337 5.61930039 2.41083317 1 P 0 ;0,1=520,2=270.000000
L 5.61930039 2.41083317 5.62240069 2.41313337 1 P 0 ;0,1=520,2=270.000000
L 5.62240069 2.41313337 5.62446693 2.41581683 1 P 0 ;0,1=520,2=270.000000
L 5.62446693 2.41581683 5.6255 2.41849961 1 P 0 ;0,1=520,2=270.000000
L 5.6255 2.41849961 5.6255 2.42118307 1 P 0 ;0,1=520,2=270.000000
L 5.6255 2.42118307 5.62446693 2.42386654 1 P 0 ;0,1=520,2=270.000000
L 5.62446693 2.42386654 5.62291722 2.42616673 1 P 0 ;0,1=520,2=270.000000
L 5.62291722 2.42616673 5.62085108 2.42808366 1 P 0 ;0,1=520,2=270.000000
L 5.59966654 2.44221644 5.59656722 2.44451663 1 P 0 ;0,1=520,2=270.000000
L 5.59656722 2.44451663 5.59501663 2.4472001 1 P 0 ;0,1=520,2=270.000000
L 5.59501663 2.4472001 5.5945 2.45026683 1 P 0 ;0,1=520,2=270.000000
L 5.5945 2.45026683 5.59553317 2.4541 1 P 0 ;0,1=520,2=270.000000
L 5.59553317 2.4541 5.59811693 2.45678346 1 P 0 ;0,1=520,2=270.000000
L 5.59811693 2.45678346 5.60121624 2.45755 1 P 0 ;0,1=520,2=270.000000
L 5.60121624 2.45755 5.60431742 2.45716673 1 P 0 ;0,1=520,2=270.000000
L 5.60431742 2.45716673 5.6069002 2.45563307 1 P 0 ;0,1=520,2=270.000000
L 5.6069002 2.45563307 5.61206673 2.44796663 1 P 0 ;0,1=520,2=270.000000
L 5.61206673 2.44796663 5.61568356 2.44451663 1 P 0 ;0,1=520,2=270.000000
L 5.61568356 2.44451663 5.62085108 2.44221644 1 P 0 ;0,1=520,2=270.000000
L 5.62085108 2.44221644 5.6255 2.4414499 1 P 0 ;0,1=520,2=270.000000
L 5.6255 2.4414499 5.6255 2.45755 1 P 0 ;0,1=520,2=270.000000
L 5.61258425 2.47321644 5.60896644 2.4758999 1 P 0 ;0,1=520,2=270.000000
L 5.60896644 2.4758999 5.6069002 2.4782001 1 P 0 ;0,1=520,2=270.000000
L 5.6069002 2.4782001 5.60586713 2.48126683 1 P 0 ;0,1=520,2=270.000000
L 5.60586713 2.48126683 5.6069002 2.4839503 1 P 0 ;0,1=520,2=270.000000
L 5.6069002 2.4839503 5.60896644 2.48586654 1 P 0 ;0,1=520,2=270.000000
L 5.60896644 2.48586654 5.61206673 2.4874002 1 P 0 ;0,1=520,2=270.000000
L 5.61206673 2.4874002 5.61568356 2.48778346 1 P 0 ;0,1=520,2=270.000000
L 5.61568356 2.48778346 5.61878386 2.4874002 1 P 0 ;0,1=520,2=270.000000
L 5.61878386 2.4874002 5.62188415 2.48586654 1 P 0 ;0,1=520,2=270.000000
L 5.62188415 2.48586654 5.62446693 2.48356634 1 P 0 ;0,1=520,2=270.000000
L 5.62446693 2.48356634 5.6255 2.48088356 1 P 0 ;0,1=520,2=270.000000
L 5.6255 2.48088356 5.62446693 2.47781683 1 P 0 ;0,1=520,2=270.000000
L 5.62446693 2.47781683 5.62136762 2.47513337 1 P 0 ;0,1=520,2=270.000000
L 5.62136762 2.47513337 5.61671673 2.4735997 1 P 0 ;0,1=520,2=270.000000
L 5.61671673 2.4735997 5.6115502 2.47321644 1 P 0 ;0,1=520,2=270.000000
L 5.6115502 2.47321644 5.60483406 2.47398287 1 P 0 ;0,1=520,2=270.000000
L 5.60483406 2.47398287 5.60121624 2.47513337 1 P 0 ;0,1=520,2=270.000000
L 5.60121624 2.47513337 5.5976003 2.47704961 1 P 0 ;0,1=520,2=270.000000
L 5.5976003 2.47704961 5.59501663 2.47973307 1 P 0 ;0,1=520,2=270.000000
L 5.59501663 2.47973307 5.5945 2.48241654 1 P 0 ;0,1=520,2=270.000000
L 5.5945 2.48241654 5.59553317 2.4851 1 P 0 ;0,1=520,2=270.000000
L 5.59553317 2.4851 5.59811693 2.48701703 1 P 0 ;0,1=520,2=270.000000
L 5.6255 2.51073307 5.61878386 2.51149961 1 P 0 ;0,1=520,2=270.000000
L 5.61878386 2.51149961 5.61310079 2.5126501 1 P 0 ;0,1=520,2=270.000000
L 5.61310079 2.5126501 5.60793337 2.51418307 1 P 0 ;0,1=520,2=270.000000
L 5.60793337 2.51418307 5.6022503 2.5161 1 P 0 ;0,1=520,2=270.000000
L 5.6022503 2.5161 5.5945 2.51916673 1 P 0 ;0,1=520,2=270.000000
L 5.5945 2.51916673 5.5945 2.50383317 1 P 0 ;0,1=520,2=270.000000
L 3.703 1.097 3.703 1.023 1 P 0 
L 3.827 1.097 3.703 1.097 1 P 0 
L 3.827 1.023 3.827 1.097 1 P 0 
L 3.703 1.023 3.827 1.023 1 P 0 
L 3.67193327 1.14291624 3.66963307 1.14446683 1 P 0 ;0,1=521,2=0.000000
L 3.66963307 1.14446683 3.6669503 1.1455 1 P 0 ;0,1=521,2=0.000000
L 3.6669503 1.1455 3.66388356 1.1455 1 P 0 ;0,1=521,2=0.000000
L 3.66388356 1.1455 3.66043287 1.14394931 1 P 0 ;0,1=521,2=0.000000
L 3.66043287 1.14394931 3.6577501 1.14136654 1 P 0 ;0,1=521,2=0.000000
L 3.6577501 1.14136654 3.65583317 1.13826624 1 P 0 ;0,1=521,2=0.000000
L 3.65583317 1.13826624 3.65429951 1.1330998 1 P 0 ;0,1=521,2=0.000000
L 3.65429951 1.1330998 3.65391624 1.1284498 1 P 0 ;0,1=521,2=0.000000
L 3.65391624 1.1284498 3.65468337 1.1237999 1 P 0 ;0,1=521,2=0.000000
L 3.65468337 1.1237999 3.65583317 1.12069961 1 P 0 ;0,1=521,2=0.000000
L 3.65583317 1.12069961 3.65813337 1.11759931 1 P 0 ;0,1=521,2=0.000000
L 3.65813337 1.11759931 3.66081683 1.11553307 1 P 0 ;0,1=521,2=0.000000
L 3.66081683 1.11553307 3.66349961 1.1145 1 P 0 ;0,1=521,2=0.000000
L 3.66349961 1.1145 3.66618307 1.1145 1 P 0 ;0,1=521,2=0.000000
L 3.66618307 1.1145 3.66886654 1.11553307 1 P 0 ;0,1=521,2=0.000000
L 3.66886654 1.11553307 3.67116673 1.11708278 1 P 0 ;0,1=521,2=0.000000
L 3.67116673 1.11708278 3.67308366 1.11914892 1 P 0 ;0,1=521,2=0.000000
L 3.68721644 1.14033346 3.68951663 1.14343278 1 P 0 ;0,1=521,2=0.000000
L 3.68951663 1.14343278 3.6922001 1.14498337 1 P 0 ;0,1=521,2=0.000000
L 3.6922001 1.14498337 3.69526683 1.1455 1 P 0 ;0,1=521,2=0.000000
L 3.69526683 1.1455 3.6991 1.14446683 1 P 0 ;0,1=521,2=0.000000
L 3.6991 1.14446683 3.70178346 1.14188307 1 P 0 ;0,1=521,2=0.000000
L 3.70178346 1.14188307 3.70255 1.13878376 1 P 0 ;0,1=521,2=0.000000
L 3.70255 1.13878376 3.70216673 1.13568258 1 P 0 ;0,1=521,2=0.000000
L 3.70216673 1.13568258 3.70063307 1.1330998 1 P 0 ;0,1=521,2=0.000000
L 3.70063307 1.1330998 3.69296663 1.12793327 1 P 0 ;0,1=521,2=0.000000
L 3.69296663 1.12793327 3.68951663 1.12431644 1 P 0 ;0,1=521,2=0.000000
L 3.68951663 1.12431644 3.68721644 1.11914892 1 P 0 ;0,1=521,2=0.000000
L 3.68721644 1.11914892 3.6864499 1.1145 1 P 0 ;0,1=521,2=0.000000
L 3.6864499 1.1145 3.70255 1.1145 1 P 0 ;0,1=521,2=0.000000
L 3.71898287 1.11811585 3.72166634 1.11553307 1 P 0 ;0,1=521,2=0.000000
L 3.72166634 1.11553307 3.72473307 1.1145 1 P 0 ;0,1=521,2=0.000000
L 3.72473307 1.1145 3.7277998 1.11553307 1 P 0 ;0,1=521,2=0.000000
L 3.7277998 1.11553307 3.73048327 1.11863238 1 P 0 ;0,1=521,2=0.000000
L 3.73048327 1.11863238 3.7324002 1.12328327 1 P 0 ;0,1=521,2=0.000000
L 3.7324002 1.12328327 3.73316673 1.12793327 1 P 0 ;0,1=521,2=0.000000
L 3.73316673 1.12793327 3.73316673 1.13361634 1 P 0 ;0,1=521,2=0.000000
L 3.73316673 1.13361634 3.7324002 1.13826624 1 P 0 ;0,1=521,2=0.000000
L 3.7324002 1.13826624 3.73048327 1.1423997 1 P 0 ;0,1=521,2=0.000000
L 3.73048327 1.1423997 3.72818307 1.14446683 1 P 0 ;0,1=521,2=0.000000
L 3.72818307 1.14446683 3.72549961 1.1455 1 P 0 ;0,1=521,2=0.000000
L 3.72549961 1.1455 3.72243287 1.14446683 1 P 0 ;0,1=521,2=0.000000
L 3.72243287 1.14446683 3.72013337 1.1423997 1 P 0 ;0,1=521,2=0.000000
L 3.72013337 1.1423997 3.7185997 1.1393003 1 P 0 ;0,1=521,2=0.000000
L 3.7185997 1.1393003 3.71783317 1.13516594 1 P 0 ;0,1=521,2=0.000000
L 3.71783317 1.13516594 3.7185997 1.1315501 1 P 0 ;0,1=521,2=0.000000
L 3.7185997 1.1315501 3.72051663 1.12793327 1 P 0 ;0,1=521,2=0.000000
L 3.72051663 1.12793327 3.72281683 1.12586604 1 P 0 ;0,1=521,2=0.000000
L 3.72281683 1.12586604 3.72549961 1.12534951 1 P 0 ;0,1=521,2=0.000000
L 3.72549961 1.12534951 3.72856634 1.12638268 1 P 0 ;0,1=521,2=0.000000
L 3.72856634 1.12638268 3.73086654 1.12896634 1 P 0 ;0,1=521,2=0.000000
L 3.73086654 1.12896634 3.73316673 1.13361634 1 P 0 ;0,1=521,2=0.000000
L 3.75649961 1.1145 3.75649961 1.1455 1 P 0 ;0,1=521,2=0.000000
L 3.75649961 1.1455 3.7518999 1.1393003 1 P 0 ;0,1=521,2=0.000000
L 3.7518999 1.1145 3.76109931 1.1145 1 P 0 ;0,1=521,2=0.000000
L 3.478 1.553 3.552 1.553 1 P 0 
L 3.478 1.677 3.478 1.553 1 P 0 
L 3.552 1.553 3.552 1.677 1 P 0 
L 3.552 1.677 3.478 1.677 1 P 0 
L 3.49208376 1.44193327 3.49053317 1.43963307 1 P 0 ;0,1=522,2=270.000000
L 3.49053317 1.43963307 3.4895 1.4369503 1 P 0 ;0,1=522,2=270.000000
L 3.4895 1.4369503 3.4895 1.43388356 1 P 0 ;0,1=522,2=270.000000
L 3.4895 1.43388356 3.49105069 1.43043287 1 P 0 ;0,1=522,2=270.000000
L 3.49105069 1.43043287 3.49363346 1.4277501 1 P 0 ;0,1=522,2=270.000000
L 3.49363346 1.4277501 3.49673376 1.42583317 1 P 0 ;0,1=522,2=270.000000
L 3.49673376 1.42583317 3.5019002 1.42429951 1 P 0 ;0,1=522,2=270.000000
L 3.5019002 1.42429951 3.5065502 1.42391624 1 P 0 ;0,1=522,2=270.000000
L 3.5065502 1.42391624 3.5112001 1.42468337 1 P 0 ;0,1=522,2=270.000000
L 3.5112001 1.42468337 3.51430039 1.42583317 1 P 0 ;0,1=522,2=270.000000
L 3.51430039 1.42583317 3.51740069 1.42813337 1 P 0 ;0,1=522,2=270.000000
L 3.51740069 1.42813337 3.51946693 1.43081683 1 P 0 ;0,1=522,2=270.000000
L 3.51946693 1.43081683 3.5205 1.43349961 1 P 0 ;0,1=522,2=270.000000
L 3.5205 1.43349961 3.5205 1.43618307 1 P 0 ;0,1=522,2=270.000000
L 3.5205 1.43618307 3.51946693 1.43886654 1 P 0 ;0,1=522,2=270.000000
L 3.51946693 1.43886654 3.51791722 1.44116673 1 P 0 ;0,1=522,2=270.000000
L 3.51791722 1.44116673 3.51585108 1.44308366 1 P 0 ;0,1=522,2=270.000000
L 3.5205 1.46449961 3.4895 1.46449961 1 P 0 ;0,1=522,2=270.000000
L 3.4895 1.46449961 3.4956997 1.4598999 1 P 0 ;0,1=522,2=270.000000
L 3.5205 1.4598999 3.5205 1.46909931 1 P 0 ;0,1=522,2=270.000000
L 3.51585108 1.48706663 3.51843386 1.48936614 1 P 0 ;0,1=522,2=270.000000
L 3.51843386 1.48936614 3.51998346 1.49204961 1 P 0 ;0,1=522,2=270.000000
L 3.51998346 1.49204961 3.5205 1.49549961 1 P 0 ;0,1=522,2=270.000000
L 3.5205 1.49549961 3.51946693 1.4989503 1 P 0 ;0,1=522,2=270.000000
L 3.51946693 1.4989503 3.51740069 1.50163307 1 P 0 ;0,1=522,2=270.000000
L 3.51740069 1.50163307 3.51378386 1.50355 1 P 0 ;0,1=522,2=270.000000
L 3.51378386 1.50355 3.50965049 1.50393327 1 P 0 ;0,1=522,2=270.000000
L 3.50965049 1.50393327 3.50551713 1.50316673 1 P 0 ;0,1=522,2=270.000000
L 3.50551713 1.50316673 3.50293337 1.5012498 1 P 0 ;0,1=522,2=270.000000
L 3.50293337 1.5012498 3.50086713 1.49856634 1 P 0 ;0,1=522,2=270.000000
L 3.50086713 1.49856634 3.50035059 1.49588356 1 P 0 ;0,1=522,2=270.000000
L 3.50035059 1.49588356 3.50086713 1.4932001 1 P 0 ;0,1=522,2=270.000000
L 3.50086713 1.4932001 3.50293337 1.4897501 1 P 0 ;0,1=522,2=270.000000
L 3.50293337 1.4897501 3.4895 1.4908999 1 P 0 ;0,1=522,2=270.000000
L 3.4895 1.4908999 3.4895 1.5012498 1 P 0 ;0,1=522,2=270.000000
L 3.51585108 1.51806663 3.51843386 1.52036614 1 P 0 ;0,1=522,2=270.000000
L 3.51843386 1.52036614 3.51998346 1.52304961 1 P 0 ;0,1=522,2=270.000000
L 3.51998346 1.52304961 3.5205 1.52649961 1 P 0 ;0,1=522,2=270.000000
L 3.5205 1.52649961 3.51946693 1.5299503 1 P 0 ;0,1=522,2=270.000000
L 3.51946693 1.5299503 3.51740069 1.53263307 1 P 0 ;0,1=522,2=270.000000
L 3.51740069 1.53263307 3.51378386 1.53455 1 P 0 ;0,1=522,2=270.000000
L 3.51378386 1.53455 3.50965049 1.53493327 1 P 0 ;0,1=522,2=270.000000
L 3.50965049 1.53493327 3.50551713 1.53416673 1 P 0 ;0,1=522,2=270.000000
L 3.50551713 1.53416673 3.50293337 1.5322498 1 P 0 ;0,1=522,2=270.000000
L 3.50293337 1.5322498 3.50086713 1.52956634 1 P 0 ;0,1=522,2=270.000000
L 3.50086713 1.52956634 3.50035059 1.52688356 1 P 0 ;0,1=522,2=270.000000
L 3.50035059 1.52688356 3.50086713 1.5242001 1 P 0 ;0,1=522,2=270.000000
L 3.50086713 1.5242001 3.50293337 1.5207501 1 P 0 ;0,1=522,2=270.000000
L 3.50293337 1.5207501 3.4895 1.5218999 1 P 0 ;0,1=522,2=270.000000
L 3.4895 1.5218999 3.4895 1.5322498 1 P 0 ;0,1=522,2=270.000000
L 3.668 1.553 3.742 1.553 1 P 0 
L 3.668 1.677 3.668 1.553 1 P 0 
L 3.742 1.553 3.742 1.677 1 P 0 
L 3.742 1.677 3.668 1.677 1 P 0 
L 3.63208376 1.57693327 3.63053317 1.57463307 1 P 0 ;0,1=523,2=270.000000
L 3.63053317 1.57463307 3.6295 1.5719503 1 P 0 ;0,1=523,2=270.000000
L 3.6295 1.5719503 3.6295 1.56888356 1 P 0 ;0,1=523,2=270.000000
L 3.6295 1.56888356 3.63105069 1.56543287 1 P 0 ;0,1=523,2=270.000000
L 3.63105069 1.56543287 3.63363346 1.5627501 1 P 0 ;0,1=523,2=270.000000
L 3.63363346 1.5627501 3.63673376 1.56083317 1 P 0 ;0,1=523,2=270.000000
L 3.63673376 1.56083317 3.6419002 1.55929951 1 P 0 ;0,1=523,2=270.000000
L 3.6419002 1.55929951 3.6465502 1.55891624 1 P 0 ;0,1=523,2=270.000000
L 3.6465502 1.55891624 3.6512001 1.55968337 1 P 0 ;0,1=523,2=270.000000
L 3.6512001 1.55968337 3.65430039 1.56083317 1 P 0 ;0,1=523,2=270.000000
L 3.65430039 1.56083317 3.65740069 1.56313337 1 P 0 ;0,1=523,2=270.000000
L 3.65740069 1.56313337 3.65946693 1.56581683 1 P 0 ;0,1=523,2=270.000000
L 3.65946693 1.56581683 3.6605 1.56849961 1 P 0 ;0,1=523,2=270.000000
L 3.6605 1.56849961 3.6605 1.57118307 1 P 0 ;0,1=523,2=270.000000
L 3.6605 1.57118307 3.65946693 1.57386654 1 P 0 ;0,1=523,2=270.000000
L 3.65946693 1.57386654 3.65791722 1.57616673 1 P 0 ;0,1=523,2=270.000000
L 3.65791722 1.57616673 3.65585108 1.57808366 1 P 0 ;0,1=523,2=270.000000
L 3.6605 1.59949961 3.6295 1.59949961 1 P 0 ;0,1=523,2=270.000000
L 3.6295 1.59949961 3.6356997 1.5948999 1 P 0 ;0,1=523,2=270.000000
L 3.6605 1.5948999 3.6605 1.60409931 1 P 0 ;0,1=523,2=270.000000
L 3.65430039 1.62206663 3.65791722 1.62436614 1 P 0 ;0,1=523,2=270.000000
L 3.65791722 1.62436614 3.65998346 1.62743287 1 P 0 ;0,1=523,2=270.000000
L 3.65998346 1.62743287 3.6605 1.63088356 1 P 0 ;0,1=523,2=270.000000
L 3.6605 1.63088356 3.65998346 1.6339503 1 P 0 ;0,1=523,2=270.000000
L 3.65998346 1.6339503 3.65740069 1.63701703 1 P 0 ;0,1=523,2=270.000000
L 3.65740069 1.63701703 3.65430039 1.63893327 1 P 0 ;0,1=523,2=270.000000
L 3.65430039 1.63893327 3.6512001 1.63931654 1 P 0 ;0,1=523,2=270.000000
L 3.6512001 1.63931654 3.64758425 1.63855 1 P 0 ;0,1=523,2=270.000000
L 3.64758425 1.63855 3.64500049 1.63586654 1 P 0 ;0,1=523,2=270.000000
L 3.64500049 1.63586654 3.64396644 1.63318307 1 P 0 ;0,1=523,2=270.000000
L 3.64396644 1.63318307 3.64396644 1.62973307 1 P 0 ;0,1=523,2=270.000000
L 3.64396644 1.63318307 3.64241683 1.63548327 1 P 0 ;0,1=523,2=270.000000
L 3.64241683 1.63548327 3.63983406 1.6374002 1 P 0 ;0,1=523,2=270.000000
L 3.63983406 1.6374002 3.63673376 1.63816673 1 P 0 ;0,1=523,2=270.000000
L 3.63673376 1.63816673 3.63363346 1.6374002 1 P 0 ;0,1=523,2=270.000000
L 3.63363346 1.6374002 3.63105069 1.63548327 1 P 0 ;0,1=523,2=270.000000
L 3.63105069 1.63548327 3.6295 1.63203327 1 P 0 ;0,1=523,2=270.000000
L 3.6295 1.63203327 3.63001663 1.62858337 1 P 0 ;0,1=523,2=270.000000
L 3.63001663 1.62858337 3.63208376 1.62513337 1 P 0 ;0,1=523,2=270.000000
L 3.6605 1.66073307 3.65378386 1.66149961 1 P 0 ;0,1=523,2=270.000000
L 3.65378386 1.66149961 3.64810079 1.6626501 1 P 0 ;0,1=523,2=270.000000
L 3.64810079 1.6626501 3.64293337 1.66418307 1 P 0 ;0,1=523,2=270.000000
L 3.64293337 1.66418307 3.6372503 1.6661 1 P 0 ;0,1=523,2=270.000000
L 3.6372503 1.6661 3.6295 1.66916673 1 P 0 ;0,1=523,2=270.000000
L 3.6295 1.66916673 3.6295 1.65383317 1 P 0 ;0,1=523,2=270.000000
L 1.497 3.102 1.423 3.102 1 P 0 
L 1.423 3.102 1.423 2.978 1 P 0 
L 1.423 2.978 1.497 2.978 1 P 0 
L 1.497 2.978 1.497 3.102 1 P 0 
L 1.32708376 2.95193327 1.32553317 2.94963307 1 P 0 ;0,1=524,2=270.000000
L 1.32553317 2.94963307 1.3245 2.9469503 1 P 0 ;0,1=524,2=270.000000
L 1.3245 2.9469503 1.3245 2.94388356 1 P 0 ;0,1=524,2=270.000000
L 1.3245 2.94388356 1.32605069 2.94043287 1 P 0 ;0,1=524,2=270.000000
L 1.32605069 2.94043287 1.32863346 2.9377501 1 P 0 ;0,1=524,2=270.000000
L 1.32863346 2.9377501 1.33173376 2.93583317 1 P 0 ;0,1=524,2=270.000000
L 1.33173376 2.93583317 1.3369002 2.93429951 1 P 0 ;0,1=524,2=270.000000
L 1.3369002 2.93429951 1.3415502 2.93391624 1 P 0 ;0,1=524,2=270.000000
L 1.3415502 2.93391624 1.3462001 2.93468337 1 P 0 ;0,1=524,2=270.000000
L 1.3462001 2.93468337 1.34930039 2.93583317 1 P 0 ;0,1=524,2=270.000000
L 1.34930039 2.93583317 1.35240069 2.93813337 1 P 0 ;0,1=524,2=270.000000
L 1.35240069 2.93813337 1.35446693 2.94081683 1 P 0 ;0,1=524,2=270.000000
L 1.35446693 2.94081683 1.3555 2.94349961 1 P 0 ;0,1=524,2=270.000000
L 1.3555 2.94349961 1.3555 2.94618307 1 P 0 ;0,1=524,2=270.000000
L 1.3555 2.94618307 1.35446693 2.94886654 1 P 0 ;0,1=524,2=270.000000
L 1.35446693 2.94886654 1.35291722 2.95116673 1 P 0 ;0,1=524,2=270.000000
L 1.35291722 2.95116673 1.35085108 2.95308366 1 P 0 ;0,1=524,2=270.000000
L 1.34930039 2.96606663 1.35291722 2.96836614 1 P 0 ;0,1=524,2=270.000000
L 1.35291722 2.96836614 1.35498346 2.97143287 1 P 0 ;0,1=524,2=270.000000
L 1.35498346 2.97143287 1.3555 2.97488356 1 P 0 ;0,1=524,2=270.000000
L 1.3555 2.97488356 1.35498346 2.9779503 1 P 0 ;0,1=524,2=270.000000
L 1.35498346 2.9779503 1.35240069 2.98101703 1 P 0 ;0,1=524,2=270.000000
L 1.35240069 2.98101703 1.34930039 2.98293327 1 P 0 ;0,1=524,2=270.000000
L 1.34930039 2.98293327 1.3462001 2.98331654 1 P 0 ;0,1=524,2=270.000000
L 1.3462001 2.98331654 1.34258425 2.98255 1 P 0 ;0,1=524,2=270.000000
L 1.34258425 2.98255 1.34000049 2.97986654 1 P 0 ;0,1=524,2=270.000000
L 1.34000049 2.97986654 1.33896644 2.97718307 1 P 0 ;0,1=524,2=270.000000
L 1.33896644 2.97718307 1.33896644 2.97373307 1 P 0 ;0,1=524,2=270.000000
L 1.33896644 2.97718307 1.33741683 2.97948327 1 P 0 ;0,1=524,2=270.000000
L 1.33741683 2.97948327 1.33483406 2.9814002 1 P 0 ;0,1=524,2=270.000000
L 1.33483406 2.9814002 1.33173376 2.98216673 1 P 0 ;0,1=524,2=270.000000
L 1.33173376 2.98216673 1.32863346 2.9814002 1 P 0 ;0,1=524,2=270.000000
L 1.32863346 2.9814002 1.32605069 2.97948327 1 P 0 ;0,1=524,2=270.000000
L 1.32605069 2.97948327 1.3245 2.97603327 1 P 0 ;0,1=524,2=270.000000
L 1.3245 2.97603327 1.32501663 2.97258337 1 P 0 ;0,1=524,2=270.000000
L 1.32501663 2.97258337 1.32708376 2.96913337 1 P 0 ;0,1=524,2=270.000000
L 1.3245 3.00549961 1.32553317 3.00243287 1 P 0 ;0,1=524,2=270.000000
L 1.32553317 3.00243287 1.32811693 3.00013337 1 P 0 ;0,1=524,2=270.000000
L 1.32811693 3.00013337 1.33121624 2.9985997 1 P 0 ;0,1=524,2=270.000000
L 1.33121624 2.9985997 1.33535059 2.9974499 1 P 0 ;0,1=524,2=270.000000
L 1.33535059 2.9974499 1.34000049 2.99706663 1 P 0 ;0,1=524,2=270.000000
L 1.34000049 2.99706663 1.34465049 2.9974499 1 P 0 ;0,1=524,2=270.000000
L 1.34465049 2.9974499 1.34878386 2.9985997 1 P 0 ;0,1=524,2=270.000000
L 1.34878386 2.9985997 1.35188415 3.00013337 1 P 0 ;0,1=524,2=270.000000
L 1.35188415 3.00013337 1.35446693 3.00243287 1 P 0 ;0,1=524,2=270.000000
L 1.35446693 3.00243287 1.3555 3.00549961 1 P 0 ;0,1=524,2=270.000000
L 1.3555 3.00549961 1.35446693 3.00856634 1 P 0 ;0,1=524,2=270.000000
L 1.35446693 3.00856634 1.35188415 3.01086654 1 P 0 ;0,1=524,2=270.000000
L 1.35188415 3.01086654 1.34878386 3.0124002 1 P 0 ;0,1=524,2=270.000000
L 1.34878386 3.0124002 1.34465049 3.01355 1 P 0 ;0,1=524,2=270.000000
L 1.34465049 3.01355 1.34000049 3.01393327 1 P 0 ;0,1=524,2=270.000000
L 1.34000049 3.01393327 1.33535059 3.01355 1 P 0 ;0,1=524,2=270.000000
L 1.33535059 3.01355 1.33121624 3.0124002 1 P 0 ;0,1=524,2=270.000000
L 1.33121624 3.0124002 1.32811693 3.01086654 1 P 0 ;0,1=524,2=270.000000
L 1.32811693 3.01086654 1.32553317 3.00856634 1 P 0 ;0,1=524,2=270.000000
L 1.32553317 3.00856634 1.3245 3.00549961 1 P 0 ;0,1=524,2=270.000000
L 1.3555 3.03649961 1.35498346 3.03918307 1 P 0 ;0,1=524,2=270.000000
L 1.35498346 3.03918307 1.35343386 3.0422498 1 P 0 ;0,1=524,2=270.000000
L 1.35343386 3.0422498 1.35085108 3.04416673 1 P 0 ;0,1=524,2=270.000000
L 1.35085108 3.04416673 1.34723327 3.04493327 1 P 0 ;0,1=524,2=270.000000
L 1.34723327 3.04493327 1.34361732 3.04416673 1 P 0 ;0,1=524,2=270.000000
L 1.34361732 3.04416673 1.34051713 3.04186654 1 P 0 ;0,1=524,2=270.000000
L 1.34051713 3.04186654 1.33896644 3.03841654 1 P 0 ;0,1=524,2=270.000000
L 1.33896644 3.03841654 1.33896644 3.03458337 1 P 0 ;0,1=524,2=270.000000
L 1.33896644 3.03458337 1.33793337 3.03228317 1 P 0 ;0,1=524,2=270.000000
L 1.33793337 3.03228317 1.33535059 3.03036614 1 P 0 ;0,1=524,2=270.000000
L 1.33535059 3.03036614 1.33173376 3.0295997 1 P 0 ;0,1=524,2=270.000000
L 1.33173376 3.0295997 1.32811693 3.0307501 1 P 0 ;0,1=524,2=270.000000
L 1.32811693 3.0307501 1.32553317 3.03343287 1 P 0 ;0,1=524,2=270.000000
L 1.32553317 3.03343287 1.3245 3.03649961 1 P 0 ;0,1=524,2=270.000000
L 1.3245 3.03649961 1.32553317 3.03956634 1 P 0 ;0,1=524,2=270.000000
L 1.32553317 3.03956634 1.32811693 3.0422498 1 P 0 ;0,1=524,2=270.000000
L 1.32811693 3.0422498 1.33173376 3.0434002 1 P 0 ;0,1=524,2=270.000000
L 1.33173376 3.0434002 1.33535059 3.04263307 1 P 0 ;0,1=524,2=270.000000
L 1.33535059 3.04263307 1.33793337 3.04071673 1 P 0 ;0,1=524,2=270.000000
L 1.33793337 3.04071673 1.33896644 3.03841654 1 P 0 ;0,1=524,2=270.000000
L 1.33896644 3.03841654 1.33896644 3.03458337 1 P 0 ;0,1=524,2=270.000000
L 1.33896644 3.03458337 1.34051713 3.03113337 1 P 0 ;0,1=524,2=270.000000
L 1.34051713 3.03113337 1.34361732 3.02883317 1 P 0 ;0,1=524,2=270.000000
L 1.34361732 3.02883317 1.34723327 3.02806663 1 P 0 ;0,1=524,2=270.000000
L 1.34723327 3.02806663 1.35085108 3.02883317 1 P 0 ;0,1=524,2=270.000000
L 1.35085108 3.02883317 1.35343386 3.0307501 1 P 0 ;0,1=524,2=270.000000
L 1.35343386 3.0307501 1.35498346 3.03381683 1 P 0 ;0,1=524,2=270.000000
L 1.35498346 3.03381683 1.3555 3.03649961 1 P 0 ;0,1=524,2=270.000000
L 1.753 3.223 1.877 3.223 1 P 0 
L 1.877 3.223 1.877 3.297 1 P 0 
L 1.877 3.297 1.753 3.297 1 P 0 
L 1.753 3.297 1.753 3.223 1 P 0 
L 1.78193327 3.36291624 1.77963307 3.36446683 1 P 0 ;0,1=525,2=0.000000
L 1.77963307 3.36446683 1.7769503 3.3655 1 P 0 ;0,1=525,2=0.000000
L 1.7769503 3.3655 1.77388356 3.3655 1 P 0 ;0,1=525,2=0.000000
L 1.77388356 3.3655 1.77043287 3.36394931 1 P 0 ;0,1=525,2=0.000000
L 1.77043287 3.36394931 1.7677501 3.36136654 1 P 0 ;0,1=525,2=0.000000
L 1.7677501 3.36136654 1.76583317 3.35826624 1 P 0 ;0,1=525,2=0.000000
L 1.76583317 3.35826624 1.76429951 3.3530998 1 P 0 ;0,1=525,2=0.000000
L 1.76429951 3.3530998 1.76391624 3.3484498 1 P 0 ;0,1=525,2=0.000000
L 1.76391624 3.3484498 1.76468337 3.3437999 1 P 0 ;0,1=525,2=0.000000
L 1.76468337 3.3437999 1.76583317 3.34069961 1 P 0 ;0,1=525,2=0.000000
L 1.76583317 3.34069961 1.76813337 3.33759931 1 P 0 ;0,1=525,2=0.000000
L 1.76813337 3.33759931 1.77081683 3.33553307 1 P 0 ;0,1=525,2=0.000000
L 1.77081683 3.33553307 1.77349961 3.3345 1 P 0 ;0,1=525,2=0.000000
L 1.77349961 3.3345 1.77618307 3.3345 1 P 0 ;0,1=525,2=0.000000
L 1.77618307 3.3345 1.77886654 3.33553307 1 P 0 ;0,1=525,2=0.000000
L 1.77886654 3.33553307 1.78116673 3.33708278 1 P 0 ;0,1=525,2=0.000000
L 1.78116673 3.33708278 1.78308366 3.33914892 1 P 0 ;0,1=525,2=0.000000
L 1.79721644 3.36033346 1.79951663 3.36343278 1 P 0 ;0,1=525,2=0.000000
L 1.79951663 3.36343278 1.8022001 3.36498337 1 P 0 ;0,1=525,2=0.000000
L 1.8022001 3.36498337 1.80526683 3.3655 1 P 0 ;0,1=525,2=0.000000
L 1.80526683 3.3655 1.8091 3.36446683 1 P 0 ;0,1=525,2=0.000000
L 1.8091 3.36446683 1.81178346 3.36188307 1 P 0 ;0,1=525,2=0.000000
L 1.81178346 3.36188307 1.81255 3.35878376 1 P 0 ;0,1=525,2=0.000000
L 1.81255 3.35878376 1.81216673 3.35568258 1 P 0 ;0,1=525,2=0.000000
L 1.81216673 3.35568258 1.81063307 3.3530998 1 P 0 ;0,1=525,2=0.000000
L 1.81063307 3.3530998 1.80296663 3.34793327 1 P 0 ;0,1=525,2=0.000000
L 1.80296663 3.34793327 1.79951663 3.34431644 1 P 0 ;0,1=525,2=0.000000
L 1.79951663 3.34431644 1.79721644 3.33914892 1 P 0 ;0,1=525,2=0.000000
L 1.79721644 3.33914892 1.7964499 3.3345 1 P 0 ;0,1=525,2=0.000000
L 1.7964499 3.3345 1.81255 3.3345 1 P 0 ;0,1=525,2=0.000000
L 1.83549961 3.3345 1.83818307 3.33501654 1 P 0 ;0,1=525,2=0.000000
L 1.83818307 3.33501654 1.8412498 3.33656614 1 P 0 ;0,1=525,2=0.000000
L 1.8412498 3.33656614 1.84316673 3.33914892 1 P 0 ;0,1=525,2=0.000000
L 1.84316673 3.33914892 1.84393327 3.34276673 1 P 0 ;0,1=525,2=0.000000
L 1.84393327 3.34276673 1.84316673 3.34638268 1 P 0 ;0,1=525,2=0.000000
L 1.84316673 3.34638268 1.84086654 3.34948287 1 P 0 ;0,1=525,2=0.000000
L 1.84086654 3.34948287 1.83741654 3.35103356 1 P 0 ;0,1=525,2=0.000000
L 1.83741654 3.35103356 1.83358337 3.35103356 1 P 0 ;0,1=525,2=0.000000
L 1.83358337 3.35103356 1.83128317 3.35206663 1 P 0 ;0,1=525,2=0.000000
L 1.83128317 3.35206663 1.82936614 3.35464941 1 P 0 ;0,1=525,2=0.000000
L 1.82936614 3.35464941 1.8285997 3.35826624 1 P 0 ;0,1=525,2=0.000000
L 1.8285997 3.35826624 1.8297501 3.36188307 1 P 0 ;0,1=525,2=0.000000
L 1.8297501 3.36188307 1.83243287 3.36446683 1 P 0 ;0,1=525,2=0.000000
L 1.83243287 3.36446683 1.83549961 3.3655 1 P 0 ;0,1=525,2=0.000000
L 1.83549961 3.3655 1.83856634 3.36446683 1 P 0 ;0,1=525,2=0.000000
L 1.83856634 3.36446683 1.8412498 3.36188307 1 P 0 ;0,1=525,2=0.000000
L 1.8412498 3.36188307 1.8424002 3.35826624 1 P 0 ;0,1=525,2=0.000000
L 1.8424002 3.35826624 1.84163307 3.35464941 1 P 0 ;0,1=525,2=0.000000
L 1.84163307 3.35464941 1.83971673 3.35206663 1 P 0 ;0,1=525,2=0.000000
L 1.83971673 3.35206663 1.83741654 3.35103356 1 P 0 ;0,1=525,2=0.000000
L 1.83741654 3.35103356 1.83358337 3.35103356 1 P 0 ;0,1=525,2=0.000000
L 1.83358337 3.35103356 1.83013337 3.34948287 1 P 0 ;0,1=525,2=0.000000
L 1.83013337 3.34948287 1.82783317 3.34638268 1 P 0 ;0,1=525,2=0.000000
L 1.82783317 3.34638268 1.82706663 3.34276673 1 P 0 ;0,1=525,2=0.000000
L 1.82706663 3.34276673 1.82783317 3.33914892 1 P 0 ;0,1=525,2=0.000000
L 1.82783317 3.33914892 1.8297501 3.33656614 1 P 0 ;0,1=525,2=0.000000
L 1.8297501 3.33656614 1.83281683 3.33501654 1 P 0 ;0,1=525,2=0.000000
L 1.83281683 3.33501654 1.83549961 3.3345 1 P 0 ;0,1=525,2=0.000000
L 1.8711 3.3345 1.8711 3.3655 1 P 0 ;0,1=525,2=0.000000
L 1.8711 3.3655 1.85691624 3.34328327 1 P 0 ;0,1=525,2=0.000000
L 1.85691624 3.34328327 1.87608366 3.34328327 1 P 0 ;0,1=525,2=0.000000
L 5.373 3.767 5.299 3.767 1 P 0 
L 5.373 3.643 5.373 3.767 1 P 0 
L 5.299 3.767 5.299 3.643 1 P 0 
L 5.299 3.643 5.373 3.643 1 P 0 
L 5.32208376 3.58293327 5.32053317 3.58063307 1 P 0 ;0,1=526,2=270.000000
L 5.32053317 3.58063307 5.3195 3.5779503 1 P 0 ;0,1=526,2=270.000000
L 5.3195 3.5779503 5.3195 3.57488356 1 P 0 ;0,1=526,2=270.000000
L 5.3195 3.57488356 5.32105069 3.57143287 1 P 0 ;0,1=526,2=270.000000
L 5.32105069 3.57143287 5.32363346 3.5687501 1 P 0 ;0,1=526,2=270.000000
L 5.32363346 3.5687501 5.32673376 3.56683317 1 P 0 ;0,1=526,2=270.000000
L 5.32673376 3.56683317 5.3319002 3.56529951 1 P 0 ;0,1=526,2=270.000000
L 5.3319002 3.56529951 5.3365502 3.56491624 1 P 0 ;0,1=526,2=270.000000
L 5.3365502 3.56491624 5.3412001 3.56568337 1 P 0 ;0,1=526,2=270.000000
L 5.3412001 3.56568337 5.34430039 3.56683317 1 P 0 ;0,1=526,2=270.000000
L 5.34430039 3.56683317 5.34740069 3.56913337 1 P 0 ;0,1=526,2=270.000000
L 5.34740069 3.56913337 5.34946693 3.57181683 1 P 0 ;0,1=526,2=270.000000
L 5.34946693 3.57181683 5.3505 3.57449961 1 P 0 ;0,1=526,2=270.000000
L 5.3505 3.57449961 5.3505 3.57718307 1 P 0 ;0,1=526,2=270.000000
L 5.3505 3.57718307 5.34946693 3.57986654 1 P 0 ;0,1=526,2=270.000000
L 5.34946693 3.57986654 5.34791722 3.58216673 1 P 0 ;0,1=526,2=270.000000
L 5.34791722 3.58216673 5.34585108 3.58408366 1 P 0 ;0,1=526,2=270.000000
L 5.34688415 3.59898287 5.34946693 3.60166634 1 P 0 ;0,1=526,2=270.000000
L 5.34946693 3.60166634 5.3505 3.60473307 1 P 0 ;0,1=526,2=270.000000
L 5.3505 3.60473307 5.34946693 3.6077998 1 P 0 ;0,1=526,2=270.000000
L 5.34946693 3.6077998 5.34636762 3.61048327 1 P 0 ;0,1=526,2=270.000000
L 5.34636762 3.61048327 5.34171673 3.6124002 1 P 0 ;0,1=526,2=270.000000
L 5.34171673 3.6124002 5.33706673 3.61316673 1 P 0 ;0,1=526,2=270.000000
L 5.33706673 3.61316673 5.33138366 3.61316673 1 P 0 ;0,1=526,2=270.000000
L 5.33138366 3.61316673 5.32673376 3.6124002 1 P 0 ;0,1=526,2=270.000000
L 5.32673376 3.6124002 5.3226003 3.61048327 1 P 0 ;0,1=526,2=270.000000
L 5.3226003 3.61048327 5.32053317 3.60818307 1 P 0 ;0,1=526,2=270.000000
L 5.32053317 3.60818307 5.3195 3.60549961 1 P 0 ;0,1=526,2=270.000000
L 5.3195 3.60549961 5.32053317 3.60243287 1 P 0 ;0,1=526,2=270.000000
L 5.32053317 3.60243287 5.3226003 3.60013337 1 P 0 ;0,1=526,2=270.000000
L 5.3226003 3.60013337 5.3256997 3.5985997 1 P 0 ;0,1=526,2=270.000000
L 5.3256997 3.5985997 5.32983406 3.59783317 1 P 0 ;0,1=526,2=270.000000
L 5.32983406 3.59783317 5.3334499 3.5985997 1 P 0 ;0,1=526,2=270.000000
L 5.3334499 3.5985997 5.33706673 3.60051663 1 P 0 ;0,1=526,2=270.000000
L 5.33706673 3.60051663 5.33913396 3.60281683 1 P 0 ;0,1=526,2=270.000000
L 5.33913396 3.60281683 5.33965049 3.60549961 1 P 0 ;0,1=526,2=270.000000
L 5.33965049 3.60549961 5.33861732 3.60856634 1 P 0 ;0,1=526,2=270.000000
L 5.33861732 3.60856634 5.33603366 3.61086654 1 P 0 ;0,1=526,2=270.000000
L 5.33603366 3.61086654 5.33138366 3.61316673 1 P 0 ;0,1=526,2=270.000000
L 5.291 3.643 5.291 3.767 1 P 0 
L 5.291 3.767 5.217 3.767 1 P 0 
L 5.217 3.767 5.217 3.643 1 P 0 
L 5.217 3.643 5.291 3.643 1 P 0 
L 5.25708376 3.56743327 5.25553317 3.56513307 1 P 0 ;0,1=527,2=270.000000
L 5.25553317 3.56513307 5.2545 3.5624503 1 P 0 ;0,1=527,2=270.000000
L 5.2545 3.5624503 5.2545 3.55938356 1 P 0 ;0,1=527,2=270.000000
L 5.2545 3.55938356 5.25605069 3.55593287 1 P 0 ;0,1=527,2=270.000000
L 5.25605069 3.55593287 5.25863346 3.5532501 1 P 0 ;0,1=527,2=270.000000
L 5.25863346 3.5532501 5.26173376 3.55133317 1 P 0 ;0,1=527,2=270.000000
L 5.26173376 3.55133317 5.2669002 3.54979951 1 P 0 ;0,1=527,2=270.000000
L 5.2669002 3.54979951 5.2715502 3.54941624 1 P 0 ;0,1=527,2=270.000000
L 5.2715502 3.54941624 5.2762001 3.55018337 1 P 0 ;0,1=527,2=270.000000
L 5.2762001 3.55018337 5.27930039 3.55133317 1 P 0 ;0,1=527,2=270.000000
L 5.27930039 3.55133317 5.28240069 3.55363337 1 P 0 ;0,1=527,2=270.000000
L 5.28240069 3.55363337 5.28446693 3.55631683 1 P 0 ;0,1=527,2=270.000000
L 5.28446693 3.55631683 5.2855 3.55899961 1 P 0 ;0,1=527,2=270.000000
L 5.2855 3.55899961 5.2855 3.56168307 1 P 0 ;0,1=527,2=270.000000
L 5.2855 3.56168307 5.28446693 3.56436654 1 P 0 ;0,1=527,2=270.000000
L 5.28446693 3.56436654 5.28291722 3.56666673 1 P 0 ;0,1=527,2=270.000000
L 5.28291722 3.56666673 5.28085108 3.56858366 1 P 0 ;0,1=527,2=270.000000
L 5.2855 3.58999961 5.2545 3.58999961 1 P 0 ;0,1=527,2=270.000000
L 5.2545 3.58999961 5.2606997 3.5853999 1 P 0 ;0,1=527,2=270.000000
L 5.2855 3.5853999 5.2855 3.59459931 1 P 0 ;0,1=527,2=270.000000
L 5.2545 3.62099961 5.25553317 3.61793287 1 P 0 ;0,1=527,2=270.000000
L 5.25553317 3.61793287 5.25811693 3.61563337 1 P 0 ;0,1=527,2=270.000000
L 5.25811693 3.61563337 5.26121624 3.6140997 1 P 0 ;0,1=527,2=270.000000
L 5.26121624 3.6140997 5.26535059 3.6129499 1 P 0 ;0,1=527,2=270.000000
L 5.26535059 3.6129499 5.27000049 3.61256663 1 P 0 ;0,1=527,2=270.000000
L 5.27000049 3.61256663 5.27465049 3.6129499 1 P 0 ;0,1=527,2=270.000000
L 5.27465049 3.6129499 5.27878386 3.6140997 1 P 0 ;0,1=527,2=270.000000
L 5.27878386 3.6140997 5.28188415 3.61563337 1 P 0 ;0,1=527,2=270.000000
L 5.28188415 3.61563337 5.28446693 3.61793287 1 P 0 ;0,1=527,2=270.000000
L 5.28446693 3.61793287 5.2855 3.62099961 1 P 0 ;0,1=527,2=270.000000
L 5.2855 3.62099961 5.28446693 3.62406634 1 P 0 ;0,1=527,2=270.000000
L 5.28446693 3.62406634 5.28188415 3.62636654 1 P 0 ;0,1=527,2=270.000000
L 5.28188415 3.62636654 5.27878386 3.6279002 1 P 0 ;0,1=527,2=270.000000
L 5.27878386 3.6279002 5.27465049 3.62905 1 P 0 ;0,1=527,2=270.000000
L 5.27465049 3.62905 5.27000049 3.62943327 1 P 0 ;0,1=527,2=270.000000
L 5.27000049 3.62943327 5.26535059 3.62905 1 P 0 ;0,1=527,2=270.000000
L 5.26535059 3.62905 5.26121624 3.6279002 1 P 0 ;0,1=527,2=270.000000
L 5.26121624 3.6279002 5.25811693 3.62636654 1 P 0 ;0,1=527,2=270.000000
L 5.25811693 3.62636654 5.25553317 3.62406634 1 P 0 ;0,1=527,2=270.000000
L 5.25553317 3.62406634 5.2545 3.62099961 1 P 0 ;0,1=527,2=270.000000
L 5.393 3.864 5.269 3.864 1 P 0 
L 5.269 3.864 5.269 3.79 1 P 0 
L 5.269 3.79 5.393 3.79 1 P 0 
L 5.393 3.79 5.393 3.864 1 P 0 
L 5.23393327 3.82491624 5.23163307 3.82646683 1 P 0 ;0,1=528,2=0.000000
L 5.23163307 3.82646683 5.2289503 3.8275 1 P 0 ;0,1=528,2=0.000000
L 5.2289503 3.8275 5.22588356 3.8275 1 P 0 ;0,1=528,2=0.000000
L 5.22588356 3.8275 5.22243287 3.82594931 1 P 0 ;0,1=528,2=0.000000
L 5.22243287 3.82594931 5.2197501 3.82336654 1 P 0 ;0,1=528,2=0.000000
L 5.2197501 3.82336654 5.21783317 3.82026624 1 P 0 ;0,1=528,2=0.000000
L 5.21783317 3.82026624 5.21629951 3.8150998 1 P 0 ;0,1=528,2=0.000000
L 5.21629951 3.8150998 5.21591624 3.8104498 1 P 0 ;0,1=528,2=0.000000
L 5.21591624 3.8104498 5.21668337 3.8057999 1 P 0 ;0,1=528,2=0.000000
L 5.21668337 3.8057999 5.21783317 3.80269961 1 P 0 ;0,1=528,2=0.000000
L 5.21783317 3.80269961 5.22013337 3.79959931 1 P 0 ;0,1=528,2=0.000000
L 5.22013337 3.79959931 5.22281683 3.79753307 1 P 0 ;0,1=528,2=0.000000
L 5.22281683 3.79753307 5.22549961 3.7965 1 P 0 ;0,1=528,2=0.000000
L 5.22549961 3.7965 5.22818307 3.7965 1 P 0 ;0,1=528,2=0.000000
L 5.22818307 3.7965 5.23086654 3.79753307 1 P 0 ;0,1=528,2=0.000000
L 5.23086654 3.79753307 5.23316673 3.79908278 1 P 0 ;0,1=528,2=0.000000
L 5.23316673 3.79908278 5.23508366 3.80114892 1 P 0 ;0,1=528,2=0.000000
L 5.24921644 3.80941575 5.2518999 3.81303356 1 P 0 ;0,1=528,2=0.000000
L 5.2518999 3.81303356 5.2542001 3.8150998 1 P 0 ;0,1=528,2=0.000000
L 5.2542001 3.8150998 5.25726683 3.81613287 1 P 0 ;0,1=528,2=0.000000
L 5.25726683 3.81613287 5.2599503 3.8150998 1 P 0 ;0,1=528,2=0.000000
L 5.2599503 3.8150998 5.26186654 3.81303356 1 P 0 ;0,1=528,2=0.000000
L 5.26186654 3.81303356 5.2634002 3.80993327 1 P 0 ;0,1=528,2=0.000000
L 5.2634002 3.80993327 5.26378346 3.80631644 1 P 0 ;0,1=528,2=0.000000
L 5.26378346 3.80631644 5.2634002 3.80321614 1 P 0 ;0,1=528,2=0.000000
L 5.2634002 3.80321614 5.26186654 3.80011585 1 P 0 ;0,1=528,2=0.000000
L 5.26186654 3.80011585 5.25956634 3.79753307 1 P 0 ;0,1=528,2=0.000000
L 5.25956634 3.79753307 5.25688356 3.7965 1 P 0 ;0,1=528,2=0.000000
L 5.25688356 3.7965 5.25381683 3.79753307 1 P 0 ;0,1=528,2=0.000000
L 5.25381683 3.79753307 5.25113337 3.80063238 1 P 0 ;0,1=528,2=0.000000
L 5.25113337 3.80063238 5.2495997 3.80528327 1 P 0 ;0,1=528,2=0.000000
L 5.2495997 3.80528327 5.24921644 3.8104498 1 P 0 ;0,1=528,2=0.000000
L 5.24921644 3.8104498 5.24998287 3.81716594 1 P 0 ;0,1=528,2=0.000000
L 5.24998287 3.81716594 5.25113337 3.82078376 1 P 0 ;0,1=528,2=0.000000
L 5.25113337 3.82078376 5.25304961 3.8243997 1 P 0 ;0,1=528,2=0.000000
L 5.25304961 3.8243997 5.25573307 3.82698337 1 P 0 ;0,1=528,2=0.000000
L 5.25573307 3.82698337 5.25841654 3.8275 1 P 0 ;0,1=528,2=0.000000
L 5.25841654 3.8275 5.2611 3.82646683 1 P 0 ;0,1=528,2=0.000000
L 5.2611 3.82646683 5.26301703 3.82388307 1 P 0 ;0,1=528,2=0.000000
L 1.743 4.114 1.743 4.188 1 P 0 
L 1.619 4.114 1.743 4.114 1 P 0 
L 1.743 4.188 1.619 4.188 1 P 0 
L 1.619 4.188 1.619 4.114 1 P 0 
L 1.80243327 4.21341624 1.80013307 4.21496683 1 P 0 ;0,1=529,2=0.000000
L 1.80013307 4.21496683 1.7974503 4.216 1 P 0 ;0,1=529,2=0.000000
L 1.7974503 4.216 1.79438356 4.216 1 P 0 ;0,1=529,2=0.000000
L 1.79438356 4.216 1.79093287 4.21444931 1 P 0 ;0,1=529,2=0.000000
L 1.79093287 4.21444931 1.7882501 4.21186654 1 P 0 ;0,1=529,2=0.000000
L 1.7882501 4.21186654 1.78633317 4.20876624 1 P 0 ;0,1=529,2=0.000000
L 1.78633317 4.20876624 1.78479951 4.2035998 1 P 0 ;0,1=529,2=0.000000
L 1.78479951 4.2035998 1.78441624 4.1989498 1 P 0 ;0,1=529,2=0.000000
L 1.78441624 4.1989498 1.78518337 4.1942999 1 P 0 ;0,1=529,2=0.000000
L 1.78518337 4.1942999 1.78633317 4.19119961 1 P 0 ;0,1=529,2=0.000000
L 1.78633317 4.19119961 1.78863337 4.18809931 1 P 0 ;0,1=529,2=0.000000
L 1.78863337 4.18809931 1.79131683 4.18603307 1 P 0 ;0,1=529,2=0.000000
L 1.79131683 4.18603307 1.79399961 4.185 1 P 0 ;0,1=529,2=0.000000
L 1.79399961 4.185 1.79668307 4.185 1 P 0 ;0,1=529,2=0.000000
L 1.79668307 4.185 1.79936654 4.18603307 1 P 0 ;0,1=529,2=0.000000
L 1.79936654 4.18603307 1.80166673 4.18758278 1 P 0 ;0,1=529,2=0.000000
L 1.80166673 4.18758278 1.80358366 4.18964892 1 P 0 ;0,1=529,2=0.000000
L 1.81656663 4.19119961 1.81886614 4.18758278 1 P 0 ;0,1=529,2=0.000000
L 1.81886614 4.18758278 1.82193287 4.18551654 1 P 0 ;0,1=529,2=0.000000
L 1.82193287 4.18551654 1.82538356 4.185 1 P 0 ;0,1=529,2=0.000000
L 1.82538356 4.185 1.8284503 4.18551654 1 P 0 ;0,1=529,2=0.000000
L 1.8284503 4.18551654 1.83151703 4.18809931 1 P 0 ;0,1=529,2=0.000000
L 1.83151703 4.18809931 1.83343327 4.19119961 1 P 0 ;0,1=529,2=0.000000
L 1.83343327 4.19119961 1.83381654 4.1942999 1 P 0 ;0,1=529,2=0.000000
L 1.83381654 4.1942999 1.83305 4.19791575 1 P 0 ;0,1=529,2=0.000000
L 1.83305 4.19791575 1.83036654 4.20049951 1 P 0 ;0,1=529,2=0.000000
L 1.83036654 4.20049951 1.82768307 4.20153356 1 P 0 ;0,1=529,2=0.000000
L 1.82768307 4.20153356 1.82423307 4.20153356 1 P 0 ;0,1=529,2=0.000000
L 1.82768307 4.20153356 1.82998327 4.20308317 1 P 0 ;0,1=529,2=0.000000
L 1.82998327 4.20308317 1.8319002 4.20566594 1 P 0 ;0,1=529,2=0.000000
L 1.8319002 4.20566594 1.83266673 4.20876624 1 P 0 ;0,1=529,2=0.000000
L 1.83266673 4.20876624 1.8319002 4.21186654 1 P 0 ;0,1=529,2=0.000000
L 1.8319002 4.21186654 1.82998327 4.21444931 1 P 0 ;0,1=529,2=0.000000
L 1.82998327 4.21444931 1.82653327 4.216 1 P 0 ;0,1=529,2=0.000000
L 1.82653327 4.216 1.82308337 4.21548337 1 P 0 ;0,1=529,2=0.000000
L 1.82308337 4.21548337 1.81963337 4.21341624 1 P 0 ;0,1=529,2=0.000000
L 1.85599961 4.216 1.85293287 4.21496683 1 P 0 ;0,1=529,2=0.000000
L 1.85293287 4.21496683 1.85063337 4.21238307 1 P 0 ;0,1=529,2=0.000000
L 1.85063337 4.21238307 1.8490997 4.20928376 1 P 0 ;0,1=529,2=0.000000
L 1.8490997 4.20928376 1.8479499 4.20514941 1 P 0 ;0,1=529,2=0.000000
L 1.8479499 4.20514941 1.84756663 4.20049951 1 P 0 ;0,1=529,2=0.000000
L 1.84756663 4.20049951 1.8479499 4.19584951 1 P 0 ;0,1=529,2=0.000000
L 1.8479499 4.19584951 1.8490997 4.19171614 1 P 0 ;0,1=529,2=0.000000
L 1.8490997 4.19171614 1.85063337 4.18861585 1 P 0 ;0,1=529,2=0.000000
L 1.85063337 4.18861585 1.85293287 4.18603307 1 P 0 ;0,1=529,2=0.000000
L 1.85293287 4.18603307 1.85599961 4.185 1 P 0 ;0,1=529,2=0.000000
L 1.85599961 4.185 1.85906634 4.18603307 1 P 0 ;0,1=529,2=0.000000
L 1.85906634 4.18603307 1.86136654 4.18861585 1 P 0 ;0,1=529,2=0.000000
L 1.86136654 4.18861585 1.8629002 4.19171614 1 P 0 ;0,1=529,2=0.000000
L 1.8629002 4.19171614 1.86405 4.19584951 1 P 0 ;0,1=529,2=0.000000
L 1.86405 4.19584951 1.86443327 4.20049951 1 P 0 ;0,1=529,2=0.000000
L 1.86443327 4.20049951 1.86405 4.20514941 1 P 0 ;0,1=529,2=0.000000
L 1.86405 4.20514941 1.8629002 4.20928376 1 P 0 ;0,1=529,2=0.000000
L 1.8629002 4.20928376 1.86136654 4.21238307 1 P 0 ;0,1=529,2=0.000000
L 1.86136654 4.21238307 1.85906634 4.21496683 1 P 0 ;0,1=529,2=0.000000
L 1.85906634 4.21496683 1.85599961 4.216 1 P 0 ;0,1=529,2=0.000000
L 1.773 3.739 1.773 3.813 1 P 0 
L 1.649 3.739 1.773 3.739 1 P 0 
L 1.773 3.813 1.649 3.813 1 P 0 
L 1.649 3.813 1.649 3.739 1 P 0 
L 1.69343327 3.63091624 1.69113307 3.63246683 1 P 0 ;0,1=530,2=0.000000
L 1.69113307 3.63246683 1.6884503 3.6335 1 P 0 ;0,1=530,2=0.000000
L 1.6884503 3.6335 1.68538356 3.6335 1 P 0 ;0,1=530,2=0.000000
L 1.68538356 3.6335 1.68193287 3.63194931 1 P 0 ;0,1=530,2=0.000000
L 1.68193287 3.63194931 1.6792501 3.62936654 1 P 0 ;0,1=530,2=0.000000
L 1.6792501 3.62936654 1.67733317 3.62626624 1 P 0 ;0,1=530,2=0.000000
L 1.67733317 3.62626624 1.67579951 3.6210998 1 P 0 ;0,1=530,2=0.000000
L 1.67579951 3.6210998 1.67541624 3.6164498 1 P 0 ;0,1=530,2=0.000000
L 1.67541624 3.6164498 1.67618337 3.6117999 1 P 0 ;0,1=530,2=0.000000
L 1.67618337 3.6117999 1.67733317 3.60869961 1 P 0 ;0,1=530,2=0.000000
L 1.67733317 3.60869961 1.67963337 3.60559931 1 P 0 ;0,1=530,2=0.000000
L 1.67963337 3.60559931 1.68231683 3.60353307 1 P 0 ;0,1=530,2=0.000000
L 1.68231683 3.60353307 1.68499961 3.6025 1 P 0 ;0,1=530,2=0.000000
L 1.68499961 3.6025 1.68768307 3.6025 1 P 0 ;0,1=530,2=0.000000
L 1.68768307 3.6025 1.69036654 3.60353307 1 P 0 ;0,1=530,2=0.000000
L 1.69036654 3.60353307 1.69266673 3.60508278 1 P 0 ;0,1=530,2=0.000000
L 1.69266673 3.60508278 1.69458366 3.60714892 1 P 0 ;0,1=530,2=0.000000
L 1.70756663 3.60869961 1.70986614 3.60508278 1 P 0 ;0,1=530,2=0.000000
L 1.70986614 3.60508278 1.71293287 3.60301654 1 P 0 ;0,1=530,2=0.000000
L 1.71293287 3.60301654 1.71638356 3.6025 1 P 0 ;0,1=530,2=0.000000
L 1.71638356 3.6025 1.7194503 3.60301654 1 P 0 ;0,1=530,2=0.000000
L 1.7194503 3.60301654 1.72251703 3.60559931 1 P 0 ;0,1=530,2=0.000000
L 1.72251703 3.60559931 1.72443327 3.60869961 1 P 0 ;0,1=530,2=0.000000
L 1.72443327 3.60869961 1.72481654 3.6117999 1 P 0 ;0,1=530,2=0.000000
L 1.72481654 3.6117999 1.72405 3.61541575 1 P 0 ;0,1=530,2=0.000000
L 1.72405 3.61541575 1.72136654 3.61799951 1 P 0 ;0,1=530,2=0.000000
L 1.72136654 3.61799951 1.71868307 3.61903356 1 P 0 ;0,1=530,2=0.000000
L 1.71868307 3.61903356 1.71523307 3.61903356 1 P 0 ;0,1=530,2=0.000000
L 1.71868307 3.61903356 1.72098327 3.62058317 1 P 0 ;0,1=530,2=0.000000
L 1.72098327 3.62058317 1.7229002 3.62316594 1 P 0 ;0,1=530,2=0.000000
L 1.7229002 3.62316594 1.72366673 3.62626624 1 P 0 ;0,1=530,2=0.000000
L 1.72366673 3.62626624 1.7229002 3.62936654 1 P 0 ;0,1=530,2=0.000000
L 1.7229002 3.62936654 1.72098327 3.63194931 1 P 0 ;0,1=530,2=0.000000
L 1.72098327 3.63194931 1.71753327 3.6335 1 P 0 ;0,1=530,2=0.000000
L 1.71753327 3.6335 1.71408337 3.63298337 1 P 0 ;0,1=530,2=0.000000
L 1.71408337 3.63298337 1.71063337 3.63091624 1 P 0 ;0,1=530,2=0.000000
L 1.73971644 3.62833346 1.74201663 3.63143278 1 P 0 ;0,1=530,2=0.000000
L 1.74201663 3.63143278 1.7447001 3.63298337 1 P 0 ;0,1=530,2=0.000000
L 1.7447001 3.63298337 1.74776683 3.6335 1 P 0 ;0,1=530,2=0.000000
L 1.74776683 3.6335 1.7516 3.63246683 1 P 0 ;0,1=530,2=0.000000
L 1.7516 3.63246683 1.75428346 3.62988307 1 P 0 ;0,1=530,2=0.000000
L 1.75428346 3.62988307 1.75505 3.62678376 1 P 0 ;0,1=530,2=0.000000
L 1.75505 3.62678376 1.75466673 3.62368258 1 P 0 ;0,1=530,2=0.000000
L 1.75466673 3.62368258 1.75313307 3.6210998 1 P 0 ;0,1=530,2=0.000000
L 1.75313307 3.6210998 1.74546663 3.61593327 1 P 0 ;0,1=530,2=0.000000
L 1.74546663 3.61593327 1.74201663 3.61231644 1 P 0 ;0,1=530,2=0.000000
L 1.74201663 3.61231644 1.73971644 3.60714892 1 P 0 ;0,1=530,2=0.000000
L 1.73971644 3.60714892 1.7389499 3.6025 1 P 0 ;0,1=530,2=0.000000
L 1.7389499 3.6025 1.75505 3.6025 1 P 0 ;0,1=530,2=0.000000
L 2.223 4.133 2.149 4.133 1 P 0 
L 2.223 4.009 2.223 4.133 1 P 0 
L 2.149 4.133 2.149 4.009 1 P 0 
L 2.149 4.009 2.223 4.009 1 P 0 
L 2.32308376 4.04843327 2.32153317 4.04613307 1 P 0 ;0,1=531,2=270.000000
L 2.32153317 4.04613307 2.3205 4.0434503 1 P 0 ;0,1=531,2=270.000000
L 2.3205 4.0434503 2.3205 4.04038356 1 P 0 ;0,1=531,2=270.000000
L 2.3205 4.04038356 2.32205069 4.03693287 1 P 0 ;0,1=531,2=270.000000
L 2.32205069 4.03693287 2.32463346 4.0342501 1 P 0 ;0,1=531,2=270.000000
L 2.32463346 4.0342501 2.32773376 4.03233317 1 P 0 ;0,1=531,2=270.000000
L 2.32773376 4.03233317 2.3329002 4.03079951 1 P 0 ;0,1=531,2=270.000000
L 2.3329002 4.03079951 2.3375502 4.03041624 1 P 0 ;0,1=531,2=270.000000
L 2.3375502 4.03041624 2.3422001 4.03118337 1 P 0 ;0,1=531,2=270.000000
L 2.3422001 4.03118337 2.34530039 4.03233317 1 P 0 ;0,1=531,2=270.000000
L 2.34530039 4.03233317 2.34840069 4.03463337 1 P 0 ;0,1=531,2=270.000000
L 2.34840069 4.03463337 2.35046693 4.03731683 1 P 0 ;0,1=531,2=270.000000
L 2.35046693 4.03731683 2.3515 4.03999961 1 P 0 ;0,1=531,2=270.000000
L 2.3515 4.03999961 2.3515 4.04268307 1 P 0 ;0,1=531,2=270.000000
L 2.3515 4.04268307 2.35046693 4.04536654 1 P 0 ;0,1=531,2=270.000000
L 2.35046693 4.04536654 2.34891722 4.04766673 1 P 0 ;0,1=531,2=270.000000
L 2.34891722 4.04766673 2.34685108 4.04958366 1 P 0 ;0,1=531,2=270.000000
L 2.3515 4.07099961 2.3205 4.07099961 1 P 0 ;0,1=531,2=270.000000
L 2.3205 4.07099961 2.3266997 4.0663999 1 P 0 ;0,1=531,2=270.000000
L 2.3515 4.0663999 2.3515 4.07559931 1 P 0 ;0,1=531,2=270.000000
L 2.3515 4.1066 2.3205 4.1066 1 P 0 ;0,1=531,2=270.000000
L 2.3205 4.1066 2.34271673 4.09241624 1 P 0 ;0,1=531,2=270.000000
L 2.34271673 4.09241624 2.34271673 4.11158366 1 P 0 ;0,1=531,2=270.000000
L 2.298 4.009 2.298 4.133 1 P 0 
L 2.298 4.133 2.224 4.133 1 P 0 
L 2.224 4.133 2.224 4.009 1 P 0 
L 2.224 4.009 2.298 4.009 1 P 0 
L 2.37208376 4.04743327 2.37053317 4.04513307 1 P 0 ;0,1=532,2=270.000000
L 2.37053317 4.04513307 2.3695 4.0424503 1 P 0 ;0,1=532,2=270.000000
L 2.3695 4.0424503 2.3695 4.03938356 1 P 0 ;0,1=532,2=270.000000
L 2.3695 4.03938356 2.37105069 4.03593287 1 P 0 ;0,1=532,2=270.000000
L 2.37105069 4.03593287 2.37363346 4.0332501 1 P 0 ;0,1=532,2=270.000000
L 2.37363346 4.0332501 2.37673376 4.03133317 1 P 0 ;0,1=532,2=270.000000
L 2.37673376 4.03133317 2.3819002 4.02979951 1 P 0 ;0,1=532,2=270.000000
L 2.3819002 4.02979951 2.3865502 4.02941624 1 P 0 ;0,1=532,2=270.000000
L 2.3865502 4.02941624 2.3912001 4.03018337 1 P 0 ;0,1=532,2=270.000000
L 2.3912001 4.03018337 2.39430039 4.03133317 1 P 0 ;0,1=532,2=270.000000
L 2.39430039 4.03133317 2.39740069 4.03363337 1 P 0 ;0,1=532,2=270.000000
L 2.39740069 4.03363337 2.39946693 4.03631683 1 P 0 ;0,1=532,2=270.000000
L 2.39946693 4.03631683 2.4005 4.03899961 1 P 0 ;0,1=532,2=270.000000
L 2.4005 4.03899961 2.4005 4.04168307 1 P 0 ;0,1=532,2=270.000000
L 2.4005 4.04168307 2.39946693 4.04436654 1 P 0 ;0,1=532,2=270.000000
L 2.39946693 4.04436654 2.39791722 4.04666673 1 P 0 ;0,1=532,2=270.000000
L 2.39791722 4.04666673 2.39585108 4.04858366 1 P 0 ;0,1=532,2=270.000000
L 2.4005 4.06999961 2.3695 4.06999961 1 P 0 ;0,1=532,2=270.000000
L 2.3695 4.06999961 2.3756997 4.0653999 1 P 0 ;0,1=532,2=270.000000
L 2.4005 4.0653999 2.4005 4.07459931 1 P 0 ;0,1=532,2=270.000000
L 2.39585108 4.09256663 2.39843386 4.09486614 1 P 0 ;0,1=532,2=270.000000
L 2.39843386 4.09486614 2.39998346 4.09754961 1 P 0 ;0,1=532,2=270.000000
L 2.39998346 4.09754961 2.4005 4.10099961 1 P 0 ;0,1=532,2=270.000000
L 2.4005 4.10099961 2.39946693 4.1044503 1 P 0 ;0,1=532,2=270.000000
L 2.39946693 4.1044503 2.39740069 4.10713307 1 P 0 ;0,1=532,2=270.000000
L 2.39740069 4.10713307 2.39378386 4.10905 1 P 0 ;0,1=532,2=270.000000
L 2.39378386 4.10905 2.38965049 4.10943327 1 P 0 ;0,1=532,2=270.000000
L 2.38965049 4.10943327 2.38551713 4.10866673 1 P 0 ;0,1=532,2=270.000000
L 2.38551713 4.10866673 2.38293337 4.1067498 1 P 0 ;0,1=532,2=270.000000
L 2.38293337 4.1067498 2.38086713 4.10406634 1 P 0 ;0,1=532,2=270.000000
L 2.38086713 4.10406634 2.38035059 4.10138356 1 P 0 ;0,1=532,2=270.000000
L 2.38035059 4.10138356 2.38086713 4.0987001 1 P 0 ;0,1=532,2=270.000000
L 2.38086713 4.0987001 2.38293337 4.0952501 1 P 0 ;0,1=532,2=270.000000
L 2.38293337 4.0952501 2.3695 4.0963999 1 P 0 ;0,1=532,2=270.000000
L 2.3695 4.0963999 2.3695 4.1067498 1 P 0 ;0,1=532,2=270.000000
L 2.273 3.799 2.273 3.923 1 P 0 
L 2.273 3.923 2.199 3.923 1 P 0 
L 2.199 3.923 2.199 3.799 1 P 0 
L 2.199 3.799 2.273 3.799 1 P 0 
L 2.36308376 3.84343327 2.36153317 3.84113307 1 P 0 ;0,1=533,2=270.000000
L 2.36153317 3.84113307 2.3605 3.8384503 1 P 0 ;0,1=533,2=270.000000
L 2.3605 3.8384503 2.3605 3.83538356 1 P 0 ;0,1=533,2=270.000000
L 2.3605 3.83538356 2.36205069 3.83193287 1 P 0 ;0,1=533,2=270.000000
L 2.36205069 3.83193287 2.36463346 3.8292501 1 P 0 ;0,1=533,2=270.000000
L 2.36463346 3.8292501 2.36773376 3.82733317 1 P 0 ;0,1=533,2=270.000000
L 2.36773376 3.82733317 2.3729002 3.82579951 1 P 0 ;0,1=533,2=270.000000
L 2.3729002 3.82579951 2.3775502 3.82541624 1 P 0 ;0,1=533,2=270.000000
L 2.3775502 3.82541624 2.3822001 3.82618337 1 P 0 ;0,1=533,2=270.000000
L 2.3822001 3.82618337 2.38530039 3.82733317 1 P 0 ;0,1=533,2=270.000000
L 2.38530039 3.82733317 2.38840069 3.82963337 1 P 0 ;0,1=533,2=270.000000
L 2.38840069 3.82963337 2.39046693 3.83231683 1 P 0 ;0,1=533,2=270.000000
L 2.39046693 3.83231683 2.3915 3.83499961 1 P 0 ;0,1=533,2=270.000000
L 2.3915 3.83499961 2.3915 3.83768307 1 P 0 ;0,1=533,2=270.000000
L 2.3915 3.83768307 2.39046693 3.84036654 1 P 0 ;0,1=533,2=270.000000
L 2.39046693 3.84036654 2.38891722 3.84266673 1 P 0 ;0,1=533,2=270.000000
L 2.38891722 3.84266673 2.38685108 3.84458366 1 P 0 ;0,1=533,2=270.000000
L 2.3915 3.86599961 2.3605 3.86599961 1 P 0 ;0,1=533,2=270.000000
L 2.3605 3.86599961 2.3666997 3.8613999 1 P 0 ;0,1=533,2=270.000000
L 2.3915 3.8613999 2.3915 3.87059931 1 P 0 ;0,1=533,2=270.000000
L 2.38530039 3.88856663 2.38891722 3.89086614 1 P 0 ;0,1=533,2=270.000000
L 2.38891722 3.89086614 2.39098346 3.89393287 1 P 0 ;0,1=533,2=270.000000
L 2.39098346 3.89393287 2.3915 3.89738356 1 P 0 ;0,1=533,2=270.000000
L 2.3915 3.89738356 2.39098346 3.9004503 1 P 0 ;0,1=533,2=270.000000
L 2.39098346 3.9004503 2.38840069 3.90351703 1 P 0 ;0,1=533,2=270.000000
L 2.38840069 3.90351703 2.38530039 3.90543327 1 P 0 ;0,1=533,2=270.000000
L 2.38530039 3.90543327 2.3822001 3.90581654 1 P 0 ;0,1=533,2=270.000000
L 2.3822001 3.90581654 2.37858425 3.90505 1 P 0 ;0,1=533,2=270.000000
L 2.37858425 3.90505 2.37600049 3.90236654 1 P 0 ;0,1=533,2=270.000000
L 2.37600049 3.90236654 2.37496644 3.89968307 1 P 0 ;0,1=533,2=270.000000
L 2.37496644 3.89968307 2.37496644 3.89623307 1 P 0 ;0,1=533,2=270.000000
L 2.37496644 3.89968307 2.37341683 3.90198327 1 P 0 ;0,1=533,2=270.000000
L 2.37341683 3.90198327 2.37083406 3.9039002 1 P 0 ;0,1=533,2=270.000000
L 2.37083406 3.9039002 2.36773376 3.90466673 1 P 0 ;0,1=533,2=270.000000
L 2.36773376 3.90466673 2.36463346 3.9039002 1 P 0 ;0,1=533,2=270.000000
L 2.36463346 3.9039002 2.36205069 3.90198327 1 P 0 ;0,1=533,2=270.000000
L 2.36205069 3.90198327 2.3605 3.89853327 1 P 0 ;0,1=533,2=270.000000
L 2.3605 3.89853327 2.36101663 3.89508337 1 P 0 ;0,1=533,2=270.000000
L 2.36101663 3.89508337 2.36308376 3.89163337 1 P 0 ;0,1=533,2=270.000000
L 5.302 1.203 5.302 1.277 1 P 0 
L 5.302 1.277 5.178 1.277 1 P 0 
L 5.178 1.203 5.302 1.203 1 P 0 
L 5.178 1.277 5.178 1.203 1 P 0 
L 5.38193327 1.24291624 5.37963307 1.24446683 1 P 0 ;0,1=534,2=0.000000
L 5.37963307 1.24446683 5.3769503 1.2455 1 P 0 ;0,1=534,2=0.000000
L 5.3769503 1.2455 5.37388356 1.2455 1 P 0 ;0,1=534,2=0.000000
L 5.37388356 1.2455 5.37043287 1.24394931 1 P 0 ;0,1=534,2=0.000000
L 5.37043287 1.24394931 5.3677501 1.24136654 1 P 0 ;0,1=534,2=0.000000
L 5.3677501 1.24136654 5.36583317 1.23826624 1 P 0 ;0,1=534,2=0.000000
L 5.36583317 1.23826624 5.36429951 1.2330998 1 P 0 ;0,1=534,2=0.000000
L 5.36429951 1.2330998 5.36391624 1.2284498 1 P 0 ;0,1=534,2=0.000000
L 5.36391624 1.2284498 5.36468337 1.2237999 1 P 0 ;0,1=534,2=0.000000
L 5.36468337 1.2237999 5.36583317 1.22069961 1 P 0 ;0,1=534,2=0.000000
L 5.36583317 1.22069961 5.36813337 1.21759931 1 P 0 ;0,1=534,2=0.000000
L 5.36813337 1.21759931 5.37081683 1.21553307 1 P 0 ;0,1=534,2=0.000000
L 5.37081683 1.21553307 5.37349961 1.2145 1 P 0 ;0,1=534,2=0.000000
L 5.37349961 1.2145 5.37618307 1.2145 1 P 0 ;0,1=534,2=0.000000
L 5.37618307 1.2145 5.37886654 1.21553307 1 P 0 ;0,1=534,2=0.000000
L 5.37886654 1.21553307 5.38116673 1.21708278 1 P 0 ;0,1=534,2=0.000000
L 5.38116673 1.21708278 5.38308366 1.21914892 1 P 0 ;0,1=534,2=0.000000
L 5.40449961 1.2145 5.40449961 1.2455 1 P 0 ;0,1=534,2=0.000000
L 5.40449961 1.2455 5.3998999 1.2393003 1 P 0 ;0,1=534,2=0.000000
L 5.3998999 1.2145 5.40909931 1.2145 1 P 0 ;0,1=534,2=0.000000
L 5.43473307 1.2145 5.43549961 1.22121614 1 P 0 ;0,1=534,2=0.000000
L 5.43549961 1.22121614 5.4366501 1.22689921 1 P 0 ;0,1=534,2=0.000000
L 5.4366501 1.22689921 5.43818307 1.23206663 1 P 0 ;0,1=534,2=0.000000
L 5.43818307 1.23206663 5.4401 1.2377497 1 P 0 ;0,1=534,2=0.000000
L 5.4401 1.2377497 5.44316673 1.2455 1 P 0 ;0,1=534,2=0.000000
L 5.44316673 1.2455 5.42783317 1.2455 1 P 0 ;0,1=534,2=0.000000
L 5.45806663 1.22069961 5.46036614 1.21708278 1 P 0 ;0,1=534,2=0.000000
L 5.46036614 1.21708278 5.46343287 1.21501654 1 P 0 ;0,1=534,2=0.000000
L 5.46343287 1.21501654 5.46688356 1.2145 1 P 0 ;0,1=534,2=0.000000
L 5.46688356 1.2145 5.4699503 1.21501654 1 P 0 ;0,1=534,2=0.000000
L 5.4699503 1.21501654 5.47301703 1.21759931 1 P 0 ;0,1=534,2=0.000000
L 5.47301703 1.21759931 5.47493327 1.22069961 1 P 0 ;0,1=534,2=0.000000
L 5.47493327 1.22069961 5.47531654 1.2237999 1 P 0 ;0,1=534,2=0.000000
L 5.47531654 1.2237999 5.47455 1.22741575 1 P 0 ;0,1=534,2=0.000000
L 5.47455 1.22741575 5.47186654 1.22999951 1 P 0 ;0,1=534,2=0.000000
L 5.47186654 1.22999951 5.46918307 1.23103356 1 P 0 ;0,1=534,2=0.000000
L 5.46918307 1.23103356 5.46573307 1.23103356 1 P 0 ;0,1=534,2=0.000000
L 5.46918307 1.23103356 5.47148327 1.23258317 1 P 0 ;0,1=534,2=0.000000
L 5.47148327 1.23258317 5.4734002 1.23516594 1 P 0 ;0,1=534,2=0.000000
L 5.4734002 1.23516594 5.47416673 1.23826624 1 P 0 ;0,1=534,2=0.000000
L 5.47416673 1.23826624 5.4734002 1.24136654 1 P 0 ;0,1=534,2=0.000000
L 5.4734002 1.24136654 5.47148327 1.24394931 1 P 0 ;0,1=534,2=0.000000
L 5.47148327 1.24394931 5.46803327 1.2455 1 P 0 ;0,1=534,2=0.000000
L 5.46803327 1.2455 5.46458337 1.24498337 1 P 0 ;0,1=534,2=0.000000
L 5.46458337 1.24498337 5.46113337 1.24291624 1 P 0 ;0,1=534,2=0.000000
L 5.752 1.647 5.628 1.647 1 P 0 
L 5.628 1.573 5.752 1.573 1 P 0 
L 5.752 1.573 5.752 1.647 1 P 0 
L 5.628 1.647 5.628 1.573 1 P 0 
L 5.65693327 1.56291624 5.65463307 1.56446683 1 P 0 ;0,1=535,2=0.000000
L 5.65463307 1.56446683 5.6519503 1.5655 1 P 0 ;0,1=535,2=0.000000
L 5.6519503 1.5655 5.64888356 1.5655 1 P 0 ;0,1=535,2=0.000000
L 5.64888356 1.5655 5.64543287 1.56394931 1 P 0 ;0,1=535,2=0.000000
L 5.64543287 1.56394931 5.6427501 1.56136654 1 P 0 ;0,1=535,2=0.000000
L 5.6427501 1.56136654 5.64083317 1.55826624 1 P 0 ;0,1=535,2=0.000000
L 5.64083317 1.55826624 5.63929951 1.5530998 1 P 0 ;0,1=535,2=0.000000
L 5.63929951 1.5530998 5.63891624 1.5484498 1 P 0 ;0,1=535,2=0.000000
L 5.63891624 1.5484498 5.63968337 1.5437999 1 P 0 ;0,1=535,2=0.000000
L 5.63968337 1.5437999 5.64083317 1.54069961 1 P 0 ;0,1=535,2=0.000000
L 5.64083317 1.54069961 5.64313337 1.53759931 1 P 0 ;0,1=535,2=0.000000
L 5.64313337 1.53759931 5.64581683 1.53553307 1 P 0 ;0,1=535,2=0.000000
L 5.64581683 1.53553307 5.64849961 1.5345 1 P 0 ;0,1=535,2=0.000000
L 5.64849961 1.5345 5.65118307 1.5345 1 P 0 ;0,1=535,2=0.000000
L 5.65118307 1.5345 5.65386654 1.53553307 1 P 0 ;0,1=535,2=0.000000
L 5.65386654 1.53553307 5.65616673 1.53708278 1 P 0 ;0,1=535,2=0.000000
L 5.65616673 1.53708278 5.65808366 1.53914892 1 P 0 ;0,1=535,2=0.000000
L 5.67221644 1.56033346 5.67451663 1.56343278 1 P 0 ;0,1=535,2=0.000000
L 5.67451663 1.56343278 5.6772001 1.56498337 1 P 0 ;0,1=535,2=0.000000
L 5.6772001 1.56498337 5.68026683 1.5655 1 P 0 ;0,1=535,2=0.000000
L 5.68026683 1.5655 5.6841 1.56446683 1 P 0 ;0,1=535,2=0.000000
L 5.6841 1.56446683 5.68678346 1.56188307 1 P 0 ;0,1=535,2=0.000000
L 5.68678346 1.56188307 5.68755 1.55878376 1 P 0 ;0,1=535,2=0.000000
L 5.68755 1.55878376 5.68716673 1.55568258 1 P 0 ;0,1=535,2=0.000000
L 5.68716673 1.55568258 5.68563307 1.5530998 1 P 0 ;0,1=535,2=0.000000
L 5.68563307 1.5530998 5.67796663 1.54793327 1 P 0 ;0,1=535,2=0.000000
L 5.67796663 1.54793327 5.67451663 1.54431644 1 P 0 ;0,1=535,2=0.000000
L 5.67451663 1.54431644 5.67221644 1.53914892 1 P 0 ;0,1=535,2=0.000000
L 5.67221644 1.53914892 5.6714499 1.5345 1 P 0 ;0,1=535,2=0.000000
L 5.6714499 1.5345 5.68755 1.5345 1 P 0 ;0,1=535,2=0.000000
L 5.70321644 1.54741575 5.7058999 1.55103356 1 P 0 ;0,1=535,2=0.000000
L 5.7058999 1.55103356 5.7082001 1.5530998 1 P 0 ;0,1=535,2=0.000000
L 5.7082001 1.5530998 5.71126683 1.55413287 1 P 0 ;0,1=535,2=0.000000
L 5.71126683 1.55413287 5.7139503 1.5530998 1 P 0 ;0,1=535,2=0.000000
L 5.7139503 1.5530998 5.71586654 1.55103356 1 P 0 ;0,1=535,2=0.000000
L 5.71586654 1.55103356 5.7174002 1.54793327 1 P 0 ;0,1=535,2=0.000000
L 5.7174002 1.54793327 5.71778346 1.54431644 1 P 0 ;0,1=535,2=0.000000
L 5.71778346 1.54431644 5.7174002 1.54121614 1 P 0 ;0,1=535,2=0.000000
L 5.7174002 1.54121614 5.71586654 1.53811585 1 P 0 ;0,1=535,2=0.000000
L 5.71586654 1.53811585 5.71356634 1.53553307 1 P 0 ;0,1=535,2=0.000000
L 5.71356634 1.53553307 5.71088356 1.5345 1 P 0 ;0,1=535,2=0.000000
L 5.71088356 1.5345 5.70781683 1.53553307 1 P 0 ;0,1=535,2=0.000000
L 5.70781683 1.53553307 5.70513337 1.53863238 1 P 0 ;0,1=535,2=0.000000
L 5.70513337 1.53863238 5.7035997 1.54328327 1 P 0 ;0,1=535,2=0.000000
L 5.7035997 1.54328327 5.70321644 1.5484498 1 P 0 ;0,1=535,2=0.000000
L 5.70321644 1.5484498 5.70398287 1.55516594 1 P 0 ;0,1=535,2=0.000000
L 5.70398287 1.55516594 5.70513337 1.55878376 1 P 0 ;0,1=535,2=0.000000
L 5.70513337 1.55878376 5.70704961 1.5623997 1 P 0 ;0,1=535,2=0.000000
L 5.70704961 1.5623997 5.70973307 1.56498337 1 P 0 ;0,1=535,2=0.000000
L 5.70973307 1.56498337 5.71241654 1.5655 1 P 0 ;0,1=535,2=0.000000
L 5.71241654 1.5655 5.7151 1.56446683 1 P 0 ;0,1=535,2=0.000000
L 5.7151 1.56446683 5.71701703 1.56188307 1 P 0 ;0,1=535,2=0.000000
L 5.73498287 1.53811585 5.73766634 1.53553307 1 P 0 ;0,1=535,2=0.000000
L 5.73766634 1.53553307 5.74073307 1.5345 1 P 0 ;0,1=535,2=0.000000
L 5.74073307 1.5345 5.7437998 1.53553307 1 P 0 ;0,1=535,2=0.000000
L 5.7437998 1.53553307 5.74648327 1.53863238 1 P 0 ;0,1=535,2=0.000000
L 5.74648327 1.53863238 5.7484002 1.54328327 1 P 0 ;0,1=535,2=0.000000
L 5.7484002 1.54328327 5.74916673 1.54793327 1 P 0 ;0,1=535,2=0.000000
L 5.74916673 1.54793327 5.74916673 1.55361634 1 P 0 ;0,1=535,2=0.000000
L 5.74916673 1.55361634 5.7484002 1.55826624 1 P 0 ;0,1=535,2=0.000000
L 5.7484002 1.55826624 5.74648327 1.5623997 1 P 0 ;0,1=535,2=0.000000
L 5.74648327 1.5623997 5.74418307 1.56446683 1 P 0 ;0,1=535,2=0.000000
L 5.74418307 1.56446683 5.74149961 1.5655 1 P 0 ;0,1=535,2=0.000000
L 5.74149961 1.5655 5.73843287 1.56446683 1 P 0 ;0,1=535,2=0.000000
L 5.73843287 1.56446683 5.73613337 1.5623997 1 P 0 ;0,1=535,2=0.000000
L 5.73613337 1.5623997 5.7345997 1.5593003 1 P 0 ;0,1=535,2=0.000000
L 5.7345997 1.5593003 5.73383317 1.55516594 1 P 0 ;0,1=535,2=0.000000
L 5.73383317 1.55516594 5.7345997 1.5515501 1 P 0 ;0,1=535,2=0.000000
L 5.7345997 1.5515501 5.73651663 1.54793327 1 P 0 ;0,1=535,2=0.000000
L 5.73651663 1.54793327 5.73881683 1.54586604 1 P 0 ;0,1=535,2=0.000000
L 5.73881683 1.54586604 5.74149961 1.54534951 1 P 0 ;0,1=535,2=0.000000
L 5.74149961 1.54534951 5.74456634 1.54638268 1 P 0 ;0,1=535,2=0.000000
L 5.74456634 1.54638268 5.74686654 1.54896634 1 P 0 ;0,1=535,2=0.000000
L 5.74686654 1.54896634 5.74916673 1.55361634 1 P 0 ;0,1=535,2=0.000000
L 5.422 2.028 5.422 2.152 1 P 0 
L 5.422 2.152 5.348 2.152 1 P 0 
L 5.348 2.152 5.348 2.028 1 P 0 
L 5.348 2.028 5.422 2.028 1 P 0 
L 5.26208376 2.05193327 5.26053317 2.04963307 1 P 0 ;0,1=536,2=270.000000
L 5.26053317 2.04963307 5.2595 2.0469503 1 P 0 ;0,1=536,2=270.000000
L 5.2595 2.0469503 5.2595 2.04388356 1 P 0 ;0,1=536,2=270.000000
L 5.2595 2.04388356 5.26105069 2.04043287 1 P 0 ;0,1=536,2=270.000000
L 5.26105069 2.04043287 5.26363346 2.0377501 1 P 0 ;0,1=536,2=270.000000
L 5.26363346 2.0377501 5.26673376 2.03583317 1 P 0 ;0,1=536,2=270.000000
L 5.26673376 2.03583317 5.2719002 2.03429951 1 P 0 ;0,1=536,2=270.000000
L 5.2719002 2.03429951 5.2765502 2.03391624 1 P 0 ;0,1=536,2=270.000000
L 5.2765502 2.03391624 5.2812001 2.03468337 1 P 0 ;0,1=536,2=270.000000
L 5.2812001 2.03468337 5.28430039 2.03583317 1 P 0 ;0,1=536,2=270.000000
L 5.28430039 2.03583317 5.28740069 2.03813337 1 P 0 ;0,1=536,2=270.000000
L 5.28740069 2.03813337 5.28946693 2.04081683 1 P 0 ;0,1=536,2=270.000000
L 5.28946693 2.04081683 5.2905 2.04349961 1 P 0 ;0,1=536,2=270.000000
L 5.2905 2.04349961 5.2905 2.04618307 1 P 0 ;0,1=536,2=270.000000
L 5.2905 2.04618307 5.28946693 2.04886654 1 P 0 ;0,1=536,2=270.000000
L 5.28946693 2.04886654 5.28791722 2.05116673 1 P 0 ;0,1=536,2=270.000000
L 5.28791722 2.05116673 5.28585108 2.05308366 1 P 0 ;0,1=536,2=270.000000
L 5.26466654 2.06721644 5.26156722 2.06951663 1 P 0 ;0,1=536,2=270.000000
L 5.26156722 2.06951663 5.26001663 2.0722001 1 P 0 ;0,1=536,2=270.000000
L 5.26001663 2.0722001 5.2595 2.07526683 1 P 0 ;0,1=536,2=270.000000
L 5.2595 2.07526683 5.26053317 2.0791 1 P 0 ;0,1=536,2=270.000000
L 5.26053317 2.0791 5.26311693 2.08178346 1 P 0 ;0,1=536,2=270.000000
L 5.26311693 2.08178346 5.26621624 2.08255 1 P 0 ;0,1=536,2=270.000000
L 5.26621624 2.08255 5.26931742 2.08216673 1 P 0 ;0,1=536,2=270.000000
L 5.26931742 2.08216673 5.2719002 2.08063307 1 P 0 ;0,1=536,2=270.000000
L 5.2719002 2.08063307 5.27706673 2.07296663 1 P 0 ;0,1=536,2=270.000000
L 5.27706673 2.07296663 5.28068356 2.06951663 1 P 0 ;0,1=536,2=270.000000
L 5.28068356 2.06951663 5.28585108 2.06721644 1 P 0 ;0,1=536,2=270.000000
L 5.28585108 2.06721644 5.2905 2.0664499 1 P 0 ;0,1=536,2=270.000000
L 5.2905 2.0664499 5.2905 2.08255 1 P 0 ;0,1=536,2=270.000000
L 5.27758425 2.09821644 5.27396644 2.1008999 1 P 0 ;0,1=536,2=270.000000
L 5.27396644 2.1008999 5.2719002 2.1032001 1 P 0 ;0,1=536,2=270.000000
L 5.2719002 2.1032001 5.27086713 2.10626683 1 P 0 ;0,1=536,2=270.000000
L 5.27086713 2.10626683 5.2719002 2.1089503 1 P 0 ;0,1=536,2=270.000000
L 5.2719002 2.1089503 5.27396644 2.11086654 1 P 0 ;0,1=536,2=270.000000
L 5.27396644 2.11086654 5.27706673 2.1124002 1 P 0 ;0,1=536,2=270.000000
L 5.27706673 2.1124002 5.28068356 2.11278346 1 P 0 ;0,1=536,2=270.000000
L 5.28068356 2.11278346 5.28378386 2.1124002 1 P 0 ;0,1=536,2=270.000000
L 5.28378386 2.1124002 5.28688415 2.11086654 1 P 0 ;0,1=536,2=270.000000
L 5.28688415 2.11086654 5.28946693 2.10856634 1 P 0 ;0,1=536,2=270.000000
L 5.28946693 2.10856634 5.2905 2.10588356 1 P 0 ;0,1=536,2=270.000000
L 5.2905 2.10588356 5.28946693 2.10281683 1 P 0 ;0,1=536,2=270.000000
L 5.28946693 2.10281683 5.28636762 2.10013337 1 P 0 ;0,1=536,2=270.000000
L 5.28636762 2.10013337 5.28171673 2.0985997 1 P 0 ;0,1=536,2=270.000000
L 5.28171673 2.0985997 5.2765502 2.09821644 1 P 0 ;0,1=536,2=270.000000
L 5.2765502 2.09821644 5.26983406 2.09898287 1 P 0 ;0,1=536,2=270.000000
L 5.26983406 2.09898287 5.26621624 2.10013337 1 P 0 ;0,1=536,2=270.000000
L 5.26621624 2.10013337 5.2626003 2.10204961 1 P 0 ;0,1=536,2=270.000000
L 5.2626003 2.10204961 5.26001663 2.10473307 1 P 0 ;0,1=536,2=270.000000
L 5.26001663 2.10473307 5.2595 2.10741654 1 P 0 ;0,1=536,2=270.000000
L 5.2595 2.10741654 5.26053317 2.1101 1 P 0 ;0,1=536,2=270.000000
L 5.26053317 2.1101 5.26311693 2.11201703 1 P 0 ;0,1=536,2=270.000000
L 5.2595 2.13649961 5.26053317 2.13343287 1 P 0 ;0,1=536,2=270.000000
L 5.26053317 2.13343287 5.26311693 2.13113337 1 P 0 ;0,1=536,2=270.000000
L 5.26311693 2.13113337 5.26621624 2.1295997 1 P 0 ;0,1=536,2=270.000000
L 5.26621624 2.1295997 5.27035059 2.1284499 1 P 0 ;0,1=536,2=270.000000
L 5.27035059 2.1284499 5.27500049 2.12806663 1 P 0 ;0,1=536,2=270.000000
L 5.27500049 2.12806663 5.27965049 2.1284499 1 P 0 ;0,1=536,2=270.000000
L 5.27965049 2.1284499 5.28378386 2.1295997 1 P 0 ;0,1=536,2=270.000000
L 5.28378386 2.1295997 5.28688415 2.13113337 1 P 0 ;0,1=536,2=270.000000
L 5.28688415 2.13113337 5.28946693 2.13343287 1 P 0 ;0,1=536,2=270.000000
L 5.28946693 2.13343287 5.2905 2.13649961 1 P 0 ;0,1=536,2=270.000000
L 5.2905 2.13649961 5.28946693 2.13956634 1 P 0 ;0,1=536,2=270.000000
L 5.28946693 2.13956634 5.28688415 2.14186654 1 P 0 ;0,1=536,2=270.000000
L 5.28688415 2.14186654 5.28378386 2.1434002 1 P 0 ;0,1=536,2=270.000000
L 5.28378386 2.1434002 5.27965049 2.14455 1 P 0 ;0,1=536,2=270.000000
L 5.27965049 2.14455 5.27500049 2.14493327 1 P 0 ;0,1=536,2=270.000000
L 5.27500049 2.14493327 5.27035059 2.14455 1 P 0 ;0,1=536,2=270.000000
L 5.27035059 2.14455 5.26621624 2.1434002 1 P 0 ;0,1=536,2=270.000000
L 5.26621624 2.1434002 5.26311693 2.14186654 1 P 0 ;0,1=536,2=270.000000
L 5.26311693 2.14186654 5.26053317 2.13956634 1 P 0 ;0,1=536,2=270.000000
L 5.26053317 2.13956634 5.2595 2.13649961 1 P 0 ;0,1=536,2=270.000000
L 5.427 1.568 5.427 1.692 1 P 0 
L 5.427 1.692 5.353 1.692 1 P 0 
L 5.353 1.692 5.353 1.568 1 P 0 
L 5.353 1.568 5.427 1.568 1 P 0 
L 5.37708376 1.46193327 5.37553317 1.45963307 1 P 0 ;0,1=537,2=270.000000
L 5.37553317 1.45963307 5.3745 1.4569503 1 P 0 ;0,1=537,2=270.000000
L 5.3745 1.4569503 5.3745 1.45388356 1 P 0 ;0,1=537,2=270.000000
L 5.3745 1.45388356 5.37605069 1.45043287 1 P 0 ;0,1=537,2=270.000000
L 5.37605069 1.45043287 5.37863346 1.4477501 1 P 0 ;0,1=537,2=270.000000
L 5.37863346 1.4477501 5.38173376 1.44583317 1 P 0 ;0,1=537,2=270.000000
L 5.38173376 1.44583317 5.3869002 1.44429951 1 P 0 ;0,1=537,2=270.000000
L 5.3869002 1.44429951 5.3915502 1.44391624 1 P 0 ;0,1=537,2=270.000000
L 5.3915502 1.44391624 5.3962001 1.44468337 1 P 0 ;0,1=537,2=270.000000
L 5.3962001 1.44468337 5.39930039 1.44583317 1 P 0 ;0,1=537,2=270.000000
L 5.39930039 1.44583317 5.40240069 1.44813337 1 P 0 ;0,1=537,2=270.000000
L 5.40240069 1.44813337 5.40446693 1.45081683 1 P 0 ;0,1=537,2=270.000000
L 5.40446693 1.45081683 5.4055 1.45349961 1 P 0 ;0,1=537,2=270.000000
L 5.4055 1.45349961 5.4055 1.45618307 1 P 0 ;0,1=537,2=270.000000
L 5.4055 1.45618307 5.40446693 1.45886654 1 P 0 ;0,1=537,2=270.000000
L 5.40446693 1.45886654 5.40291722 1.46116673 1 P 0 ;0,1=537,2=270.000000
L 5.40291722 1.46116673 5.40085108 1.46308366 1 P 0 ;0,1=537,2=270.000000
L 5.37966654 1.47721644 5.37656722 1.47951663 1 P 0 ;0,1=537,2=270.000000
L 5.37656722 1.47951663 5.37501663 1.4822001 1 P 0 ;0,1=537,2=270.000000
L 5.37501663 1.4822001 5.3745 1.48526683 1 P 0 ;0,1=537,2=270.000000
L 5.3745 1.48526683 5.37553317 1.4891 1 P 0 ;0,1=537,2=270.000000
L 5.37553317 1.4891 5.37811693 1.49178346 1 P 0 ;0,1=537,2=270.000000
L 5.37811693 1.49178346 5.38121624 1.49255 1 P 0 ;0,1=537,2=270.000000
L 5.38121624 1.49255 5.38431742 1.49216673 1 P 0 ;0,1=537,2=270.000000
L 5.38431742 1.49216673 5.3869002 1.49063307 1 P 0 ;0,1=537,2=270.000000
L 5.3869002 1.49063307 5.39206673 1.48296663 1 P 0 ;0,1=537,2=270.000000
L 5.39206673 1.48296663 5.39568356 1.47951663 1 P 0 ;0,1=537,2=270.000000
L 5.39568356 1.47951663 5.40085108 1.47721644 1 P 0 ;0,1=537,2=270.000000
L 5.40085108 1.47721644 5.4055 1.4764499 1 P 0 ;0,1=537,2=270.000000
L 5.4055 1.4764499 5.4055 1.49255 1 P 0 ;0,1=537,2=270.000000
L 5.4055 1.51473307 5.39878386 1.51549961 1 P 0 ;0,1=537,2=270.000000
L 5.39878386 1.51549961 5.39310079 1.5166501 1 P 0 ;0,1=537,2=270.000000
L 5.39310079 1.5166501 5.38793337 1.51818307 1 P 0 ;0,1=537,2=270.000000
L 5.38793337 1.51818307 5.3822503 1.5201 1 P 0 ;0,1=537,2=270.000000
L 5.3822503 1.5201 5.3745 1.52316673 1 P 0 ;0,1=537,2=270.000000
L 5.3745 1.52316673 5.3745 1.50783317 1 P 0 ;0,1=537,2=270.000000
L 5.4055 1.54649961 5.3745 1.54649961 1 P 0 ;0,1=537,2=270.000000
L 5.3745 1.54649961 5.3806997 1.5418999 1 P 0 ;0,1=537,2=270.000000
L 5.4055 1.5418999 5.4055 1.55109931 1 P 0 ;0,1=537,2=270.000000
L 5.387 1.882 5.313 1.882 1 P 0 
L 5.387 1.758 5.387 1.882 1 P 0 
L 5.313 1.882 5.313 1.758 1 P 0 
L 5.313 1.758 5.387 1.758 1 P 0 
L 5.32158376 1.91193327 5.32003317 1.90963307 1 P 0 ;0,1=538,2=270.000000
L 5.32003317 1.90963307 5.319 1.9069503 1 P 0 ;0,1=538,2=270.000000
L 5.319 1.9069503 5.319 1.90388356 1 P 0 ;0,1=538,2=270.000000
L 5.319 1.90388356 5.32055069 1.90043287 1 P 0 ;0,1=538,2=270.000000
L 5.32055069 1.90043287 5.32313346 1.8977501 1 P 0 ;0,1=538,2=270.000000
L 5.32313346 1.8977501 5.32623376 1.89583317 1 P 0 ;0,1=538,2=270.000000
L 5.32623376 1.89583317 5.3314002 1.89429951 1 P 0 ;0,1=538,2=270.000000
L 5.3314002 1.89429951 5.3360502 1.89391624 1 P 0 ;0,1=538,2=270.000000
L 5.3360502 1.89391624 5.3407001 1.89468337 1 P 0 ;0,1=538,2=270.000000
L 5.3407001 1.89468337 5.34380039 1.89583317 1 P 0 ;0,1=538,2=270.000000
L 5.34380039 1.89583317 5.34690069 1.89813337 1 P 0 ;0,1=538,2=270.000000
L 5.34690069 1.89813337 5.34896693 1.90081683 1 P 0 ;0,1=538,2=270.000000
L 5.34896693 1.90081683 5.35 1.90349961 1 P 0 ;0,1=538,2=270.000000
L 5.35 1.90349961 5.35 1.90618307 1 P 0 ;0,1=538,2=270.000000
L 5.35 1.90618307 5.34896693 1.90886654 1 P 0 ;0,1=538,2=270.000000
L 5.34896693 1.90886654 5.34741722 1.91116673 1 P 0 ;0,1=538,2=270.000000
L 5.34741722 1.91116673 5.34535108 1.91308366 1 P 0 ;0,1=538,2=270.000000
L 5.32416654 1.92721644 5.32106722 1.92951663 1 P 0 ;0,1=538,2=270.000000
L 5.32106722 1.92951663 5.31951663 1.9322001 1 P 0 ;0,1=538,2=270.000000
L 5.31951663 1.9322001 5.319 1.93526683 1 P 0 ;0,1=538,2=270.000000
L 5.319 1.93526683 5.32003317 1.9391 1 P 0 ;0,1=538,2=270.000000
L 5.32003317 1.9391 5.32261693 1.94178346 1 P 0 ;0,1=538,2=270.000000
L 5.32261693 1.94178346 5.32571624 1.94255 1 P 0 ;0,1=538,2=270.000000
L 5.32571624 1.94255 5.32881742 1.94216673 1 P 0 ;0,1=538,2=270.000000
L 5.32881742 1.94216673 5.3314002 1.94063307 1 P 0 ;0,1=538,2=270.000000
L 5.3314002 1.94063307 5.33656673 1.93296663 1 P 0 ;0,1=538,2=270.000000
L 5.33656673 1.93296663 5.34018356 1.92951663 1 P 0 ;0,1=538,2=270.000000
L 5.34018356 1.92951663 5.34535108 1.92721644 1 P 0 ;0,1=538,2=270.000000
L 5.34535108 1.92721644 5.35 1.9264499 1 P 0 ;0,1=538,2=270.000000
L 5.35 1.9264499 5.35 1.94255 1 P 0 ;0,1=538,2=270.000000
L 5.35 1.96473307 5.34328386 1.96549961 1 P 0 ;0,1=538,2=270.000000
L 5.34328386 1.96549961 5.33760079 1.9666501 1 P 0 ;0,1=538,2=270.000000
L 5.33760079 1.9666501 5.33243337 1.96818307 1 P 0 ;0,1=538,2=270.000000
L 5.33243337 1.96818307 5.3267503 1.9701 1 P 0 ;0,1=538,2=270.000000
L 5.3267503 1.9701 5.319 1.97316673 1 P 0 ;0,1=538,2=270.000000
L 5.319 1.97316673 5.319 1.95783317 1 P 0 ;0,1=538,2=270.000000
L 5.319 1.99649961 5.32003317 1.99343287 1 P 0 ;0,1=538,2=270.000000
L 5.32003317 1.99343287 5.32261693 1.99113337 1 P 0 ;0,1=538,2=270.000000
L 5.32261693 1.99113337 5.32571624 1.9895997 1 P 0 ;0,1=538,2=270.000000
L 5.32571624 1.9895997 5.32985059 1.9884499 1 P 0 ;0,1=538,2=270.000000
L 5.32985059 1.9884499 5.33450049 1.98806663 1 P 0 ;0,1=538,2=270.000000
L 5.33450049 1.98806663 5.33915049 1.9884499 1 P 0 ;0,1=538,2=270.000000
L 5.33915049 1.9884499 5.34328386 1.9895997 1 P 0 ;0,1=538,2=270.000000
L 5.34328386 1.9895997 5.34638415 1.99113337 1 P 0 ;0,1=538,2=270.000000
L 5.34638415 1.99113337 5.34896693 1.99343287 1 P 0 ;0,1=538,2=270.000000
L 5.34896693 1.99343287 5.35 1.99649961 1 P 0 ;0,1=538,2=270.000000
L 5.35 1.99649961 5.34896693 1.99956634 1 P 0 ;0,1=538,2=270.000000
L 5.34896693 1.99956634 5.34638415 2.00186654 1 P 0 ;0,1=538,2=270.000000
L 5.34638415 2.00186654 5.34328386 2.0034002 1 P 0 ;0,1=538,2=270.000000
L 5.34328386 2.0034002 5.33915049 2.00455 1 P 0 ;0,1=538,2=270.000000
L 5.33915049 2.00455 5.33450049 2.00493327 1 P 0 ;0,1=538,2=270.000000
L 5.33450049 2.00493327 5.32985059 2.00455 1 P 0 ;0,1=538,2=270.000000
L 5.32985059 2.00455 5.32571624 2.0034002 1 P 0 ;0,1=538,2=270.000000
L 5.32571624 2.0034002 5.32261693 2.00186654 1 P 0 ;0,1=538,2=270.000000
L 5.32261693 2.00186654 5.32003317 1.99956634 1 P 0 ;0,1=538,2=270.000000
L 5.32003317 1.99956634 5.319 1.99649961 1 P 0 ;0,1=538,2=270.000000
L 5.028 1.301 4.904 1.301 1 P 0 
L 4.904 1.301 4.904 1.227 1 P 0 
L 4.904 1.227 5.028 1.227 1 P 0 
L 5.028 1.227 5.028 1.301 1 P 0 
L 4.92793327 1.20091624 4.92563307 1.20246683 1 P 0 ;0,1=539,2=0.000000
L 4.92563307 1.20246683 4.9229503 1.2035 1 P 0 ;0,1=539,2=0.000000
L 4.9229503 1.2035 4.91988356 1.2035 1 P 0 ;0,1=539,2=0.000000
L 4.91988356 1.2035 4.91643287 1.20194931 1 P 0 ;0,1=539,2=0.000000
L 4.91643287 1.20194931 4.9137501 1.19936654 1 P 0 ;0,1=539,2=0.000000
L 4.9137501 1.19936654 4.91183317 1.19626624 1 P 0 ;0,1=539,2=0.000000
L 4.91183317 1.19626624 4.91029951 1.1910998 1 P 0 ;0,1=539,2=0.000000
L 4.91029951 1.1910998 4.90991624 1.1864498 1 P 0 ;0,1=539,2=0.000000
L 4.90991624 1.1864498 4.91068337 1.1817999 1 P 0 ;0,1=539,2=0.000000
L 4.91068337 1.1817999 4.91183317 1.17869961 1 P 0 ;0,1=539,2=0.000000
L 4.91183317 1.17869961 4.91413337 1.17559931 1 P 0 ;0,1=539,2=0.000000
L 4.91413337 1.17559931 4.91681683 1.17353307 1 P 0 ;0,1=539,2=0.000000
L 4.91681683 1.17353307 4.91949961 1.1725 1 P 0 ;0,1=539,2=0.000000
L 4.91949961 1.1725 4.92218307 1.1725 1 P 0 ;0,1=539,2=0.000000
L 4.92218307 1.1725 4.92486654 1.17353307 1 P 0 ;0,1=539,2=0.000000
L 4.92486654 1.17353307 4.92716673 1.17508278 1 P 0 ;0,1=539,2=0.000000
L 4.92716673 1.17508278 4.92908366 1.17714892 1 P 0 ;0,1=539,2=0.000000
L 4.94321644 1.19833346 4.94551663 1.20143278 1 P 0 ;0,1=539,2=0.000000
L 4.94551663 1.20143278 4.9482001 1.20298337 1 P 0 ;0,1=539,2=0.000000
L 4.9482001 1.20298337 4.95126683 1.2035 1 P 0 ;0,1=539,2=0.000000
L 4.95126683 1.2035 4.9551 1.20246683 1 P 0 ;0,1=539,2=0.000000
L 4.9551 1.20246683 4.95778346 1.19988307 1 P 0 ;0,1=539,2=0.000000
L 4.95778346 1.19988307 4.95855 1.19678376 1 P 0 ;0,1=539,2=0.000000
L 4.95855 1.19678376 4.95816673 1.19368258 1 P 0 ;0,1=539,2=0.000000
L 4.95816673 1.19368258 4.95663307 1.1910998 1 P 0 ;0,1=539,2=0.000000
L 4.95663307 1.1910998 4.94896663 1.18593327 1 P 0 ;0,1=539,2=0.000000
L 4.94896663 1.18593327 4.94551663 1.18231644 1 P 0 ;0,1=539,2=0.000000
L 4.94551663 1.18231644 4.94321644 1.17714892 1 P 0 ;0,1=539,2=0.000000
L 4.94321644 1.17714892 4.9424499 1.1725 1 P 0 ;0,1=539,2=0.000000
L 4.9424499 1.1725 4.95855 1.1725 1 P 0 ;0,1=539,2=0.000000
L 4.97498287 1.17611585 4.97766634 1.17353307 1 P 0 ;0,1=539,2=0.000000
L 4.97766634 1.17353307 4.98073307 1.1725 1 P 0 ;0,1=539,2=0.000000
L 4.98073307 1.1725 4.9837998 1.17353307 1 P 0 ;0,1=539,2=0.000000
L 4.9837998 1.17353307 4.98648327 1.17663238 1 P 0 ;0,1=539,2=0.000000
L 4.98648327 1.17663238 4.9884002 1.18128327 1 P 0 ;0,1=539,2=0.000000
L 4.9884002 1.18128327 4.98916673 1.18593327 1 P 0 ;0,1=539,2=0.000000
L 4.98916673 1.18593327 4.98916673 1.19161634 1 P 0 ;0,1=539,2=0.000000
L 4.98916673 1.19161634 4.9884002 1.19626624 1 P 0 ;0,1=539,2=0.000000
L 4.9884002 1.19626624 4.98648327 1.2003997 1 P 0 ;0,1=539,2=0.000000
L 4.98648327 1.2003997 4.98418307 1.20246683 1 P 0 ;0,1=539,2=0.000000
L 4.98418307 1.20246683 4.98149961 1.2035 1 P 0 ;0,1=539,2=0.000000
L 4.98149961 1.2035 4.97843287 1.20246683 1 P 0 ;0,1=539,2=0.000000
L 4.97843287 1.20246683 4.97613337 1.2003997 1 P 0 ;0,1=539,2=0.000000
L 4.97613337 1.2003997 4.9745997 1.1973003 1 P 0 ;0,1=539,2=0.000000
L 4.9745997 1.1973003 4.97383317 1.19316594 1 P 0 ;0,1=539,2=0.000000
L 4.97383317 1.19316594 4.9745997 1.1895501 1 P 0 ;0,1=539,2=0.000000
L 4.9745997 1.1895501 4.97651663 1.18593327 1 P 0 ;0,1=539,2=0.000000
L 4.97651663 1.18593327 4.97881683 1.18386604 1 P 0 ;0,1=539,2=0.000000
L 4.97881683 1.18386604 4.98149961 1.18334951 1 P 0 ;0,1=539,2=0.000000
L 4.98149961 1.18334951 4.98456634 1.18438268 1 P 0 ;0,1=539,2=0.000000
L 4.98456634 1.18438268 4.98686654 1.18696634 1 P 0 ;0,1=539,2=0.000000
L 4.98686654 1.18696634 4.98916673 1.19161634 1 P 0 ;0,1=539,2=0.000000
L 5.00521644 1.19833346 5.00751663 1.20143278 1 P 0 ;0,1=539,2=0.000000
L 5.00751663 1.20143278 5.0102001 1.20298337 1 P 0 ;0,1=539,2=0.000000
L 5.0102001 1.20298337 5.01326683 1.2035 1 P 0 ;0,1=539,2=0.000000
L 5.01326683 1.2035 5.0171 1.20246683 1 P 0 ;0,1=539,2=0.000000
L 5.0171 1.20246683 5.01978346 1.19988307 1 P 0 ;0,1=539,2=0.000000
L 5.01978346 1.19988307 5.02055 1.19678376 1 P 0 ;0,1=539,2=0.000000
L 5.02055 1.19678376 5.02016673 1.19368258 1 P 0 ;0,1=539,2=0.000000
L 5.02016673 1.19368258 5.01863307 1.1910998 1 P 0 ;0,1=539,2=0.000000
L 5.01863307 1.1910998 5.01096663 1.18593327 1 P 0 ;0,1=539,2=0.000000
L 5.01096663 1.18593327 5.00751663 1.18231644 1 P 0 ;0,1=539,2=0.000000
L 5.00751663 1.18231644 5.00521644 1.17714892 1 P 0 ;0,1=539,2=0.000000
L 5.00521644 1.17714892 5.0044499 1.1725 1 P 0 ;0,1=539,2=0.000000
L 5.0044499 1.1725 5.02055 1.1725 1 P 0 ;0,1=539,2=0.000000
L 5.455 0.826 5.579 0.826 1 P 0 
L 5.579 0.826 5.579 0.9 1 P 0 
L 5.579 0.9 5.455 0.9 1 P 0 
L 5.455 0.9 5.455 0.826 1 P 0 
L 5.35193327 0.91791624 5.34963307 0.91946683 1 P 0 ;0,1=540,2=0.000000
L 5.34963307 0.91946683 5.3469503 0.9205 1 P 0 ;0,1=540,2=0.000000
L 5.3469503 0.9205 5.34388356 0.9205 1 P 0 ;0,1=540,2=0.000000
L 5.34388356 0.9205 5.34043287 0.91894931 1 P 0 ;0,1=540,2=0.000000
L 5.34043287 0.91894931 5.3377501 0.91636654 1 P 0 ;0,1=540,2=0.000000
L 5.3377501 0.91636654 5.33583317 0.91326624 1 P 0 ;0,1=540,2=0.000000
L 5.33583317 0.91326624 5.33429951 0.9080998 1 P 0 ;0,1=540,2=0.000000
L 5.33429951 0.9080998 5.33391624 0.9034498 1 P 0 ;0,1=540,2=0.000000
L 5.33391624 0.9034498 5.33468337 0.8987999 1 P 0 ;0,1=540,2=0.000000
L 5.33468337 0.8987999 5.33583317 0.89569961 1 P 0 ;0,1=540,2=0.000000
L 5.33583317 0.89569961 5.33813337 0.89259931 1 P 0 ;0,1=540,2=0.000000
L 5.33813337 0.89259931 5.34081683 0.89053307 1 P 0 ;0,1=540,2=0.000000
L 5.34081683 0.89053307 5.34349961 0.8895 1 P 0 ;0,1=540,2=0.000000
L 5.34349961 0.8895 5.34618307 0.8895 1 P 0 ;0,1=540,2=0.000000
L 5.34618307 0.8895 5.34886654 0.89053307 1 P 0 ;0,1=540,2=0.000000
L 5.34886654 0.89053307 5.35116673 0.89208278 1 P 0 ;0,1=540,2=0.000000
L 5.35116673 0.89208278 5.35308366 0.89414892 1 P 0 ;0,1=540,2=0.000000
L 5.36721644 0.91533346 5.36951663 0.91843278 1 P 0 ;0,1=540,2=0.000000
L 5.36951663 0.91843278 5.3722001 0.91998337 1 P 0 ;0,1=540,2=0.000000
L 5.3722001 0.91998337 5.37526683 0.9205 1 P 0 ;0,1=540,2=0.000000
L 5.37526683 0.9205 5.3791 0.91946683 1 P 0 ;0,1=540,2=0.000000
L 5.3791 0.91946683 5.38178346 0.91688307 1 P 0 ;0,1=540,2=0.000000
L 5.38178346 0.91688307 5.38255 0.91378376 1 P 0 ;0,1=540,2=0.000000
L 5.38255 0.91378376 5.38216673 0.91068258 1 P 0 ;0,1=540,2=0.000000
L 5.38216673 0.91068258 5.38063307 0.9080998 1 P 0 ;0,1=540,2=0.000000
L 5.38063307 0.9080998 5.37296663 0.90293327 1 P 0 ;0,1=540,2=0.000000
L 5.37296663 0.90293327 5.36951663 0.89931644 1 P 0 ;0,1=540,2=0.000000
L 5.36951663 0.89931644 5.36721644 0.89414892 1 P 0 ;0,1=540,2=0.000000
L 5.36721644 0.89414892 5.3664499 0.8895 1 P 0 ;0,1=540,2=0.000000
L 5.3664499 0.8895 5.38255 0.8895 1 P 0 ;0,1=540,2=0.000000
L 5.39706663 0.89569961 5.39936614 0.89208278 1 P 0 ;0,1=540,2=0.000000
L 5.39936614 0.89208278 5.40243287 0.89001654 1 P 0 ;0,1=540,2=0.000000
L 5.40243287 0.89001654 5.40588356 0.8895 1 P 0 ;0,1=540,2=0.000000
L 5.40588356 0.8895 5.4089503 0.89001654 1 P 0 ;0,1=540,2=0.000000
L 5.4089503 0.89001654 5.41201703 0.89259931 1 P 0 ;0,1=540,2=0.000000
L 5.41201703 0.89259931 5.41393327 0.89569961 1 P 0 ;0,1=540,2=0.000000
L 5.41393327 0.89569961 5.41431654 0.8987999 1 P 0 ;0,1=540,2=0.000000
L 5.41431654 0.8987999 5.41355 0.90241575 1 P 0 ;0,1=540,2=0.000000
L 5.41355 0.90241575 5.41086654 0.90499951 1 P 0 ;0,1=540,2=0.000000
L 5.41086654 0.90499951 5.40818307 0.90603356 1 P 0 ;0,1=540,2=0.000000
L 5.40818307 0.90603356 5.40473307 0.90603356 1 P 0 ;0,1=540,2=0.000000
L 5.40818307 0.90603356 5.41048327 0.90758317 1 P 0 ;0,1=540,2=0.000000
L 5.41048327 0.90758317 5.4124002 0.91016594 1 P 0 ;0,1=540,2=0.000000
L 5.4124002 0.91016594 5.41316673 0.91326624 1 P 0 ;0,1=540,2=0.000000
L 5.41316673 0.91326624 5.4124002 0.91636654 1 P 0 ;0,1=540,2=0.000000
L 5.4124002 0.91636654 5.41048327 0.91894931 1 P 0 ;0,1=540,2=0.000000
L 5.41048327 0.91894931 5.40703327 0.9205 1 P 0 ;0,1=540,2=0.000000
L 5.40703327 0.9205 5.40358337 0.91998337 1 P 0 ;0,1=540,2=0.000000
L 5.40358337 0.91998337 5.40013337 0.91791624 1 P 0 ;0,1=540,2=0.000000
L 5.42998287 0.89311585 5.43266634 0.89053307 1 P 0 ;0,1=540,2=0.000000
L 5.43266634 0.89053307 5.43573307 0.8895 1 P 0 ;0,1=540,2=0.000000
L 5.43573307 0.8895 5.4387998 0.89053307 1 P 0 ;0,1=540,2=0.000000
L 5.4387998 0.89053307 5.44148327 0.89363238 1 P 0 ;0,1=540,2=0.000000
L 5.44148327 0.89363238 5.4434002 0.89828327 1 P 0 ;0,1=540,2=0.000000
L 5.4434002 0.89828327 5.44416673 0.90293327 1 P 0 ;0,1=540,2=0.000000
L 5.44416673 0.90293327 5.44416673 0.90861634 1 P 0 ;0,1=540,2=0.000000
L 5.44416673 0.90861634 5.4434002 0.91326624 1 P 0 ;0,1=540,2=0.000000
L 5.4434002 0.91326624 5.44148327 0.9173997 1 P 0 ;0,1=540,2=0.000000
L 5.44148327 0.9173997 5.43918307 0.91946683 1 P 0 ;0,1=540,2=0.000000
L 5.43918307 0.91946683 5.43649961 0.9205 1 P 0 ;0,1=540,2=0.000000
L 5.43649961 0.9205 5.43343287 0.91946683 1 P 0 ;0,1=540,2=0.000000
L 5.43343287 0.91946683 5.43113337 0.9173997 1 P 0 ;0,1=540,2=0.000000
L 5.43113337 0.9173997 5.4295997 0.9143003 1 P 0 ;0,1=540,2=0.000000
L 5.4295997 0.9143003 5.42883317 0.91016594 1 P 0 ;0,1=540,2=0.000000
L 5.42883317 0.91016594 5.4295997 0.9065501 1 P 0 ;0,1=540,2=0.000000
L 5.4295997 0.9065501 5.43151663 0.90293327 1 P 0 ;0,1=540,2=0.000000
L 5.43151663 0.90293327 5.43381683 0.90086604 1 P 0 ;0,1=540,2=0.000000
L 5.43381683 0.90086604 5.43649961 0.90034951 1 P 0 ;0,1=540,2=0.000000
L 5.43649961 0.90034951 5.43956634 0.90138268 1 P 0 ;0,1=540,2=0.000000
L 5.43956634 0.90138268 5.44186654 0.90396634 1 P 0 ;0,1=540,2=0.000000
L 5.44186654 0.90396634 5.44416673 0.90861634 1 P 0 ;0,1=540,2=0.000000
L 5.727 0.896 5.603 0.896 1 P 0 
L 5.603 0.896 5.603 0.822 1 P 0 
L 5.603 0.822 5.727 0.822 1 P 0 
L 5.727 0.822 5.727 0.896 1 P 0 
L 5.75193327 0.90291624 5.74963307 0.90446683 1 P 0 ;0,1=541,2=0.000000
L 5.74963307 0.90446683 5.7469503 0.9055 1 P 0 ;0,1=541,2=0.000000
L 5.7469503 0.9055 5.74388356 0.9055 1 P 0 ;0,1=541,2=0.000000
L 5.74388356 0.9055 5.74043287 0.90394931 1 P 0 ;0,1=541,2=0.000000
L 5.74043287 0.90394931 5.7377501 0.90136654 1 P 0 ;0,1=541,2=0.000000
L 5.7377501 0.90136654 5.73583317 0.89826624 1 P 0 ;0,1=541,2=0.000000
L 5.73583317 0.89826624 5.73429951 0.8930998 1 P 0 ;0,1=541,2=0.000000
L 5.73429951 0.8930998 5.73391624 0.8884498 1 P 0 ;0,1=541,2=0.000000
L 5.73391624 0.8884498 5.73468337 0.8837999 1 P 0 ;0,1=541,2=0.000000
L 5.73468337 0.8837999 5.73583317 0.88069961 1 P 0 ;0,1=541,2=0.000000
L 5.73583317 0.88069961 5.73813337 0.87759931 1 P 0 ;0,1=541,2=0.000000
L 5.73813337 0.87759931 5.74081683 0.87553307 1 P 0 ;0,1=541,2=0.000000
L 5.74081683 0.87553307 5.74349961 0.8745 1 P 0 ;0,1=541,2=0.000000
L 5.74349961 0.8745 5.74618307 0.8745 1 P 0 ;0,1=541,2=0.000000
L 5.74618307 0.8745 5.74886654 0.87553307 1 P 0 ;0,1=541,2=0.000000
L 5.74886654 0.87553307 5.75116673 0.87708278 1 P 0 ;0,1=541,2=0.000000
L 5.75116673 0.87708278 5.75308366 0.87914892 1 P 0 ;0,1=541,2=0.000000
L 5.76721644 0.90033346 5.76951663 0.90343278 1 P 0 ;0,1=541,2=0.000000
L 5.76951663 0.90343278 5.7722001 0.90498337 1 P 0 ;0,1=541,2=0.000000
L 5.7722001 0.90498337 5.77526683 0.9055 1 P 0 ;0,1=541,2=0.000000
L 5.77526683 0.9055 5.7791 0.90446683 1 P 0 ;0,1=541,2=0.000000
L 5.7791 0.90446683 5.78178346 0.90188307 1 P 0 ;0,1=541,2=0.000000
L 5.78178346 0.90188307 5.78255 0.89878376 1 P 0 ;0,1=541,2=0.000000
L 5.78255 0.89878376 5.78216673 0.89568258 1 P 0 ;0,1=541,2=0.000000
L 5.78216673 0.89568258 5.78063307 0.8930998 1 P 0 ;0,1=541,2=0.000000
L 5.78063307 0.8930998 5.77296663 0.88793327 1 P 0 ;0,1=541,2=0.000000
L 5.77296663 0.88793327 5.76951663 0.88431644 1 P 0 ;0,1=541,2=0.000000
L 5.76951663 0.88431644 5.76721644 0.87914892 1 P 0 ;0,1=541,2=0.000000
L 5.76721644 0.87914892 5.7664499 0.8745 1 P 0 ;0,1=541,2=0.000000
L 5.7664499 0.8745 5.78255 0.8745 1 P 0 ;0,1=541,2=0.000000
L 5.79821644 0.90033346 5.80051663 0.90343278 1 P 0 ;0,1=541,2=0.000000
L 5.80051663 0.90343278 5.8032001 0.90498337 1 P 0 ;0,1=541,2=0.000000
L 5.8032001 0.90498337 5.80626683 0.9055 1 P 0 ;0,1=541,2=0.000000
L 5.80626683 0.9055 5.8101 0.90446683 1 P 0 ;0,1=541,2=0.000000
L 5.8101 0.90446683 5.81278346 0.90188307 1 P 0 ;0,1=541,2=0.000000
L 5.81278346 0.90188307 5.81355 0.89878376 1 P 0 ;0,1=541,2=0.000000
L 5.81355 0.89878376 5.81316673 0.89568258 1 P 0 ;0,1=541,2=0.000000
L 5.81316673 0.89568258 5.81163307 0.8930998 1 P 0 ;0,1=541,2=0.000000
L 5.81163307 0.8930998 5.80396663 0.88793327 1 P 0 ;0,1=541,2=0.000000
L 5.80396663 0.88793327 5.80051663 0.88431644 1 P 0 ;0,1=541,2=0.000000
L 5.80051663 0.88431644 5.79821644 0.87914892 1 P 0 ;0,1=541,2=0.000000
L 5.79821644 0.87914892 5.7974499 0.8745 1 P 0 ;0,1=541,2=0.000000
L 5.7974499 0.8745 5.81355 0.8745 1 P 0 ;0,1=541,2=0.000000
L 5.83649961 0.8745 5.83918307 0.87501654 1 P 0 ;0,1=541,2=0.000000
L 5.83918307 0.87501654 5.8422498 0.87656614 1 P 0 ;0,1=541,2=0.000000
L 5.8422498 0.87656614 5.84416673 0.87914892 1 P 0 ;0,1=541,2=0.000000
L 5.84416673 0.87914892 5.84493327 0.88276673 1 P 0 ;0,1=541,2=0.000000
L 5.84493327 0.88276673 5.84416673 0.88638268 1 P 0 ;0,1=541,2=0.000000
L 5.84416673 0.88638268 5.84186654 0.88948287 1 P 0 ;0,1=541,2=0.000000
L 5.84186654 0.88948287 5.83841654 0.89103356 1 P 0 ;0,1=541,2=0.000000
L 5.83841654 0.89103356 5.83458337 0.89103356 1 P 0 ;0,1=541,2=0.000000
L 5.83458337 0.89103356 5.83228317 0.89206663 1 P 0 ;0,1=541,2=0.000000
L 5.83228317 0.89206663 5.83036614 0.89464941 1 P 0 ;0,1=541,2=0.000000
L 5.83036614 0.89464941 5.8295997 0.89826624 1 P 0 ;0,1=541,2=0.000000
L 5.8295997 0.89826624 5.8307501 0.90188307 1 P 0 ;0,1=541,2=0.000000
L 5.8307501 0.90188307 5.83343287 0.90446683 1 P 0 ;0,1=541,2=0.000000
L 5.83343287 0.90446683 5.83649961 0.9055 1 P 0 ;0,1=541,2=0.000000
L 5.83649961 0.9055 5.83956634 0.90446683 1 P 0 ;0,1=541,2=0.000000
L 5.83956634 0.90446683 5.8422498 0.90188307 1 P 0 ;0,1=541,2=0.000000
L 5.8422498 0.90188307 5.8434002 0.89826624 1 P 0 ;0,1=541,2=0.000000
L 5.8434002 0.89826624 5.84263307 0.89464941 1 P 0 ;0,1=541,2=0.000000
L 5.84263307 0.89464941 5.84071673 0.89206663 1 P 0 ;0,1=541,2=0.000000
L 5.84071673 0.89206663 5.83841654 0.89103356 1 P 0 ;0,1=541,2=0.000000
L 5.83841654 0.89103356 5.83458337 0.89103356 1 P 0 ;0,1=541,2=0.000000
L 5.83458337 0.89103356 5.83113337 0.88948287 1 P 0 ;0,1=541,2=0.000000
L 5.83113337 0.88948287 5.82883317 0.88638268 1 P 0 ;0,1=541,2=0.000000
L 5.82883317 0.88638268 5.82806663 0.88276673 1 P 0 ;0,1=541,2=0.000000
L 5.82806663 0.88276673 5.82883317 0.87914892 1 P 0 ;0,1=541,2=0.000000
L 5.82883317 0.87914892 5.8307501 0.87656614 1 P 0 ;0,1=541,2=0.000000
L 5.8307501 0.87656614 5.83381683 0.87501654 1 P 0 ;0,1=541,2=0.000000
L 5.83381683 0.87501654 5.83649961 0.8745 1 P 0 ;0,1=541,2=0.000000
L 5.612 0.903 5.612 1.027 1 P 0 
L 5.612 1.027 5.538 1.027 1 P 0 
L 5.538 1.027 5.538 0.903 1 P 0 
L 5.538 0.903 5.612 0.903 1 P 0 
L 5.56708376 1.06693327 5.56553317 1.06463307 1 P 0 ;0,1=542,2=270.000000
L 5.56553317 1.06463307 5.5645 1.0619503 1 P 0 ;0,1=542,2=270.000000
L 5.5645 1.0619503 5.5645 1.05888356 1 P 0 ;0,1=542,2=270.000000
L 5.5645 1.05888356 5.56605069 1.05543287 1 P 0 ;0,1=542,2=270.000000
L 5.56605069 1.05543287 5.56863346 1.0527501 1 P 0 ;0,1=542,2=270.000000
L 5.56863346 1.0527501 5.57173376 1.05083317 1 P 0 ;0,1=542,2=270.000000
L 5.57173376 1.05083317 5.5769002 1.04929951 1 P 0 ;0,1=542,2=270.000000
L 5.5769002 1.04929951 5.5815502 1.04891624 1 P 0 ;0,1=542,2=270.000000
L 5.5815502 1.04891624 5.5862001 1.04968337 1 P 0 ;0,1=542,2=270.000000
L 5.5862001 1.04968337 5.58930039 1.05083317 1 P 0 ;0,1=542,2=270.000000
L 5.58930039 1.05083317 5.59240069 1.05313337 1 P 0 ;0,1=542,2=270.000000
L 5.59240069 1.05313337 5.59446693 1.05581683 1 P 0 ;0,1=542,2=270.000000
L 5.59446693 1.05581683 5.5955 1.05849961 1 P 0 ;0,1=542,2=270.000000
L 5.5955 1.05849961 5.5955 1.06118307 1 P 0 ;0,1=542,2=270.000000
L 5.5955 1.06118307 5.59446693 1.06386654 1 P 0 ;0,1=542,2=270.000000
L 5.59446693 1.06386654 5.59291722 1.06616673 1 P 0 ;0,1=542,2=270.000000
L 5.59291722 1.06616673 5.59085108 1.06808366 1 P 0 ;0,1=542,2=270.000000
L 5.56966654 1.08221644 5.56656722 1.08451663 1 P 0 ;0,1=542,2=270.000000
L 5.56656722 1.08451663 5.56501663 1.0872001 1 P 0 ;0,1=542,2=270.000000
L 5.56501663 1.0872001 5.5645 1.09026683 1 P 0 ;0,1=542,2=270.000000
L 5.5645 1.09026683 5.56553317 1.0941 1 P 0 ;0,1=542,2=270.000000
L 5.56553317 1.0941 5.56811693 1.09678346 1 P 0 ;0,1=542,2=270.000000
L 5.56811693 1.09678346 5.57121624 1.09755 1 P 0 ;0,1=542,2=270.000000
L 5.57121624 1.09755 5.57431742 1.09716673 1 P 0 ;0,1=542,2=270.000000
L 5.57431742 1.09716673 5.5769002 1.09563307 1 P 0 ;0,1=542,2=270.000000
L 5.5769002 1.09563307 5.58206673 1.08796663 1 P 0 ;0,1=542,2=270.000000
L 5.58206673 1.08796663 5.58568356 1.08451663 1 P 0 ;0,1=542,2=270.000000
L 5.58568356 1.08451663 5.59085108 1.08221644 1 P 0 ;0,1=542,2=270.000000
L 5.59085108 1.08221644 5.5955 1.0814499 1 P 0 ;0,1=542,2=270.000000
L 5.5955 1.0814499 5.5955 1.09755 1 P 0 ;0,1=542,2=270.000000
L 5.56966654 1.11321644 5.56656722 1.11551663 1 P 0 ;0,1=542,2=270.000000
L 5.56656722 1.11551663 5.56501663 1.1182001 1 P 0 ;0,1=542,2=270.000000
L 5.56501663 1.1182001 5.5645 1.12126683 1 P 0 ;0,1=542,2=270.000000
L 5.5645 1.12126683 5.56553317 1.1251 1 P 0 ;0,1=542,2=270.000000
L 5.56553317 1.1251 5.56811693 1.12778346 1 P 0 ;0,1=542,2=270.000000
L 5.56811693 1.12778346 5.57121624 1.12855 1 P 0 ;0,1=542,2=270.000000
L 5.57121624 1.12855 5.57431742 1.12816673 1 P 0 ;0,1=542,2=270.000000
L 5.57431742 1.12816673 5.5769002 1.12663307 1 P 0 ;0,1=542,2=270.000000
L 5.5769002 1.12663307 5.58206673 1.11896663 1 P 0 ;0,1=542,2=270.000000
L 5.58206673 1.11896663 5.58568356 1.11551663 1 P 0 ;0,1=542,2=270.000000
L 5.58568356 1.11551663 5.59085108 1.11321644 1 P 0 ;0,1=542,2=270.000000
L 5.59085108 1.11321644 5.5955 1.1124499 1 P 0 ;0,1=542,2=270.000000
L 5.5955 1.1124499 5.5955 1.12855 1 P 0 ;0,1=542,2=270.000000
L 5.5955 1.1561 5.5645 1.1561 1 P 0 ;0,1=542,2=270.000000
L 5.5645 1.1561 5.58671673 1.14191624 1 P 0 ;0,1=542,2=270.000000
L 5.58671673 1.14191624 5.58671673 1.16108366 1 P 0 ;0,1=542,2=270.000000
L 3.38 3.79 3.38 3.864 1 P 0 
L 3.38 3.864 3.256 3.864 1 P 0 
L 3.256 3.864 3.256 3.79 1 P 0 
L 3.256 3.79 3.38 3.79 1 P 0 
L 3.12243327 3.61791624 3.12013307 3.61946683 1 P 0 ;0,1=543,2=0.000000
L 3.12013307 3.61946683 3.1174503 3.6205 1 P 0 ;0,1=543,2=0.000000
L 3.1174503 3.6205 3.11438356 3.6205 1 P 0 ;0,1=543,2=0.000000
L 3.11438356 3.6205 3.11093287 3.61894931 1 P 0 ;0,1=543,2=0.000000
L 3.11093287 3.61894931 3.1082501 3.61636654 1 P 0 ;0,1=543,2=0.000000
L 3.1082501 3.61636654 3.10633317 3.61326624 1 P 0 ;0,1=543,2=0.000000
L 3.10633317 3.61326624 3.10479951 3.6080998 1 P 0 ;0,1=543,2=0.000000
L 3.10479951 3.6080998 3.10441624 3.6034498 1 P 0 ;0,1=543,2=0.000000
L 3.10441624 3.6034498 3.10518337 3.5987999 1 P 0 ;0,1=543,2=0.000000
L 3.10518337 3.5987999 3.10633317 3.59569961 1 P 0 ;0,1=543,2=0.000000
L 3.10633317 3.59569961 3.10863337 3.59259931 1 P 0 ;0,1=543,2=0.000000
L 3.10863337 3.59259931 3.11131683 3.59053307 1 P 0 ;0,1=543,2=0.000000
L 3.11131683 3.59053307 3.11399961 3.5895 1 P 0 ;0,1=543,2=0.000000
L 3.11399961 3.5895 3.11668307 3.5895 1 P 0 ;0,1=543,2=0.000000
L 3.11668307 3.5895 3.11936654 3.59053307 1 P 0 ;0,1=543,2=0.000000
L 3.11936654 3.59053307 3.12166673 3.59208278 1 P 0 ;0,1=543,2=0.000000
L 3.12166673 3.59208278 3.12358366 3.59414892 1 P 0 ;0,1=543,2=0.000000
L 3.1496 3.5895 3.1496 3.6205 1 P 0 ;0,1=543,2=0.000000
L 3.1496 3.6205 3.13541624 3.59828327 1 P 0 ;0,1=543,2=0.000000
L 3.13541624 3.59828327 3.15458366 3.59828327 1 P 0 ;0,1=543,2=0.000000
L 3.17599961 3.5895 3.17868307 3.59001654 1 P 0 ;0,1=543,2=0.000000
L 3.17868307 3.59001654 3.1817498 3.59156614 1 P 0 ;0,1=543,2=0.000000
L 3.1817498 3.59156614 3.18366673 3.59414892 1 P 0 ;0,1=543,2=0.000000
L 3.18366673 3.59414892 3.18443327 3.59776673 1 P 0 ;0,1=543,2=0.000000
L 3.18443327 3.59776673 3.18366673 3.60138268 1 P 0 ;0,1=543,2=0.000000
L 3.18366673 3.60138268 3.18136654 3.60448287 1 P 0 ;0,1=543,2=0.000000
L 3.18136654 3.60448287 3.17791654 3.60603356 1 P 0 ;0,1=543,2=0.000000
L 3.17791654 3.60603356 3.17408337 3.60603356 1 P 0 ;0,1=543,2=0.000000
L 3.17408337 3.60603356 3.17178317 3.60706663 1 P 0 ;0,1=543,2=0.000000
L 3.17178317 3.60706663 3.16986614 3.60964941 1 P 0 ;0,1=543,2=0.000000
L 3.16986614 3.60964941 3.1690997 3.61326624 1 P 0 ;0,1=543,2=0.000000
L 3.1690997 3.61326624 3.1702501 3.61688307 1 P 0 ;0,1=543,2=0.000000
L 3.1702501 3.61688307 3.17293287 3.61946683 1 P 0 ;0,1=543,2=0.000000
L 3.17293287 3.61946683 3.17599961 3.6205 1 P 0 ;0,1=543,2=0.000000
L 3.17599961 3.6205 3.17906634 3.61946683 1 P 0 ;0,1=543,2=0.000000
L 3.17906634 3.61946683 3.1817498 3.61688307 1 P 0 ;0,1=543,2=0.000000
L 3.1817498 3.61688307 3.1829002 3.61326624 1 P 0 ;0,1=543,2=0.000000
L 3.1829002 3.61326624 3.18213307 3.60964941 1 P 0 ;0,1=543,2=0.000000
L 3.18213307 3.60964941 3.18021673 3.60706663 1 P 0 ;0,1=543,2=0.000000
L 3.18021673 3.60706663 3.17791654 3.60603356 1 P 0 ;0,1=543,2=0.000000
L 3.17791654 3.60603356 3.17408337 3.60603356 1 P 0 ;0,1=543,2=0.000000
L 3.17408337 3.60603356 3.17063337 3.60448287 1 P 0 ;0,1=543,2=0.000000
L 3.17063337 3.60448287 3.16833317 3.60138268 1 P 0 ;0,1=543,2=0.000000
L 3.16833317 3.60138268 3.16756663 3.59776673 1 P 0 ;0,1=543,2=0.000000
L 3.16756663 3.59776673 3.16833317 3.59414892 1 P 0 ;0,1=543,2=0.000000
L 3.16833317 3.59414892 3.1702501 3.59156614 1 P 0 ;0,1=543,2=0.000000
L 3.1702501 3.59156614 3.17331683 3.59001654 1 P 0 ;0,1=543,2=0.000000
L 3.17331683 3.59001654 3.17599961 3.5895 1 P 0 ;0,1=543,2=0.000000
L 3.357 3.623 3.357 3.747 1 P 0 
L 3.357 3.747 3.283 3.747 1 P 0 
L 3.283 3.747 3.283 3.623 1 P 0 
L 3.283 3.623 3.357 3.623 1 P 0 
L 3.15208376 3.51243327 3.15053317 3.51013307 1 P 0 ;0,1=544,2=270.000000
L 3.15053317 3.51013307 3.1495 3.5074503 1 P 0 ;0,1=544,2=270.000000
L 3.1495 3.5074503 3.1495 3.50438356 1 P 0 ;0,1=544,2=270.000000
L 3.1495 3.50438356 3.15105069 3.50093287 1 P 0 ;0,1=544,2=270.000000
L 3.15105069 3.50093287 3.15363346 3.4982501 1 P 0 ;0,1=544,2=270.000000
L 3.15363346 3.4982501 3.15673376 3.49633317 1 P 0 ;0,1=544,2=270.000000
L 3.15673376 3.49633317 3.1619002 3.49479951 1 P 0 ;0,1=544,2=270.000000
L 3.1619002 3.49479951 3.1665502 3.49441624 1 P 0 ;0,1=544,2=270.000000
L 3.1665502 3.49441624 3.1712001 3.49518337 1 P 0 ;0,1=544,2=270.000000
L 3.1712001 3.49518337 3.17430039 3.49633317 1 P 0 ;0,1=544,2=270.000000
L 3.17430039 3.49633317 3.17740069 3.49863337 1 P 0 ;0,1=544,2=270.000000
L 3.17740069 3.49863337 3.17946693 3.50131683 1 P 0 ;0,1=544,2=270.000000
L 3.17946693 3.50131683 3.1805 3.50399961 1 P 0 ;0,1=544,2=270.000000
L 3.1805 3.50399961 3.1805 3.50668307 1 P 0 ;0,1=544,2=270.000000
L 3.1805 3.50668307 3.17946693 3.50936654 1 P 0 ;0,1=544,2=270.000000
L 3.17946693 3.50936654 3.17791722 3.51166673 1 P 0 ;0,1=544,2=270.000000
L 3.17791722 3.51166673 3.17585108 3.51358366 1 P 0 ;0,1=544,2=270.000000
L 3.15466654 3.52771644 3.15156722 3.53001663 1 P 0 ;0,1=544,2=270.000000
L 3.15156722 3.53001663 3.15001663 3.5327001 1 P 0 ;0,1=544,2=270.000000
L 3.15001663 3.5327001 3.1495 3.53576683 1 P 0 ;0,1=544,2=270.000000
L 3.1495 3.53576683 3.15053317 3.5396 1 P 0 ;0,1=544,2=270.000000
L 3.15053317 3.5396 3.15311693 3.54228346 1 P 0 ;0,1=544,2=270.000000
L 3.15311693 3.54228346 3.15621624 3.54305 1 P 0 ;0,1=544,2=270.000000
L 3.15621624 3.54305 3.15931742 3.54266673 1 P 0 ;0,1=544,2=270.000000
L 3.15931742 3.54266673 3.1619002 3.54113307 1 P 0 ;0,1=544,2=270.000000
L 3.1619002 3.54113307 3.16706673 3.53346663 1 P 0 ;0,1=544,2=270.000000
L 3.16706673 3.53346663 3.17068356 3.53001663 1 P 0 ;0,1=544,2=270.000000
L 3.17068356 3.53001663 3.17585108 3.52771644 1 P 0 ;0,1=544,2=270.000000
L 3.17585108 3.52771644 3.1805 3.5269499 1 P 0 ;0,1=544,2=270.000000
L 3.1805 3.5269499 3.1805 3.54305 1 P 0 ;0,1=544,2=270.000000
L 3.1805 3.56599961 3.1495 3.56599961 1 P 0 ;0,1=544,2=270.000000
L 3.1495 3.56599961 3.1556997 3.5613999 1 P 0 ;0,1=544,2=270.000000
L 3.1805 3.5613999 3.1805 3.57059931 1 P 0 ;0,1=544,2=270.000000
L 3.517 3.623 3.517 3.747 1 P 0 
L 3.517 3.747 3.443 3.747 1 P 0 
L 3.443 3.747 3.443 3.623 1 P 0 
L 3.443 3.623 3.517 3.623 1 P 0 
L 3.23708376 3.51243327 3.23553317 3.51013307 1 P 0 ;0,1=545,2=270.000000
L 3.23553317 3.51013307 3.2345 3.5074503 1 P 0 ;0,1=545,2=270.000000
L 3.2345 3.5074503 3.2345 3.50438356 1 P 0 ;0,1=545,2=270.000000
L 3.2345 3.50438356 3.23605069 3.50093287 1 P 0 ;0,1=545,2=270.000000
L 3.23605069 3.50093287 3.23863346 3.4982501 1 P 0 ;0,1=545,2=270.000000
L 3.23863346 3.4982501 3.24173376 3.49633317 1 P 0 ;0,1=545,2=270.000000
L 3.24173376 3.49633317 3.2469002 3.49479951 1 P 0 ;0,1=545,2=270.000000
L 3.2469002 3.49479951 3.2515502 3.49441624 1 P 0 ;0,1=545,2=270.000000
L 3.2515502 3.49441624 3.2562001 3.49518337 1 P 0 ;0,1=545,2=270.000000
L 3.2562001 3.49518337 3.25930039 3.49633317 1 P 0 ;0,1=545,2=270.000000
L 3.25930039 3.49633317 3.26240069 3.49863337 1 P 0 ;0,1=545,2=270.000000
L 3.26240069 3.49863337 3.26446693 3.50131683 1 P 0 ;0,1=545,2=270.000000
L 3.26446693 3.50131683 3.2655 3.50399961 1 P 0 ;0,1=545,2=270.000000
L 3.2655 3.50399961 3.2655 3.50668307 1 P 0 ;0,1=545,2=270.000000
L 3.2655 3.50668307 3.26446693 3.50936654 1 P 0 ;0,1=545,2=270.000000
L 3.26446693 3.50936654 3.26291722 3.51166673 1 P 0 ;0,1=545,2=270.000000
L 3.26291722 3.51166673 3.26085108 3.51358366 1 P 0 ;0,1=545,2=270.000000
L 3.23966654 3.52771644 3.23656722 3.53001663 1 P 0 ;0,1=545,2=270.000000
L 3.23656722 3.53001663 3.23501663 3.5327001 1 P 0 ;0,1=545,2=270.000000
L 3.23501663 3.5327001 3.2345 3.53576683 1 P 0 ;0,1=545,2=270.000000
L 3.2345 3.53576683 3.23553317 3.5396 1 P 0 ;0,1=545,2=270.000000
L 3.23553317 3.5396 3.23811693 3.54228346 1 P 0 ;0,1=545,2=270.000000
L 3.23811693 3.54228346 3.24121624 3.54305 1 P 0 ;0,1=545,2=270.000000
L 3.24121624 3.54305 3.24431742 3.54266673 1 P 0 ;0,1=545,2=270.000000
L 3.24431742 3.54266673 3.2469002 3.54113307 1 P 0 ;0,1=545,2=270.000000
L 3.2469002 3.54113307 3.25206673 3.53346663 1 P 0 ;0,1=545,2=270.000000
L 3.25206673 3.53346663 3.25568356 3.53001663 1 P 0 ;0,1=545,2=270.000000
L 3.25568356 3.53001663 3.26085108 3.52771644 1 P 0 ;0,1=545,2=270.000000
L 3.26085108 3.52771644 3.2655 3.5269499 1 P 0 ;0,1=545,2=270.000000
L 3.2655 3.5269499 3.2655 3.54305 1 P 0 ;0,1=545,2=270.000000
L 3.2345 3.56599961 3.23553317 3.56293287 1 P 0 ;0,1=545,2=270.000000
L 3.23553317 3.56293287 3.23811693 3.56063337 1 P 0 ;0,1=545,2=270.000000
L 3.23811693 3.56063337 3.24121624 3.5590997 1 P 0 ;0,1=545,2=270.000000
L 3.24121624 3.5590997 3.24535059 3.5579499 1 P 0 ;0,1=545,2=270.000000
L 3.24535059 3.5579499 3.25000049 3.55756663 1 P 0 ;0,1=545,2=270.000000
L 3.25000049 3.55756663 3.25465049 3.5579499 1 P 0 ;0,1=545,2=270.000000
L 3.25465049 3.5579499 3.25878386 3.5590997 1 P 0 ;0,1=545,2=270.000000
L 3.25878386 3.5590997 3.26188415 3.56063337 1 P 0 ;0,1=545,2=270.000000
L 3.26188415 3.56063337 3.26446693 3.56293287 1 P 0 ;0,1=545,2=270.000000
L 3.26446693 3.56293287 3.2655 3.56599961 1 P 0 ;0,1=545,2=270.000000
L 3.2655 3.56599961 3.26446693 3.56906634 1 P 0 ;0,1=545,2=270.000000
L 3.26446693 3.56906634 3.26188415 3.57136654 1 P 0 ;0,1=545,2=270.000000
L 3.26188415 3.57136654 3.25878386 3.5729002 1 P 0 ;0,1=545,2=270.000000
L 3.25878386 3.5729002 3.25465049 3.57405 1 P 0 ;0,1=545,2=270.000000
L 3.25465049 3.57405 3.25000049 3.57443327 1 P 0 ;0,1=545,2=270.000000
L 3.25000049 3.57443327 3.24535059 3.57405 1 P 0 ;0,1=545,2=270.000000
L 3.24535059 3.57405 3.24121624 3.5729002 1 P 0 ;0,1=545,2=270.000000
L 3.24121624 3.5729002 3.23811693 3.57136654 1 P 0 ;0,1=545,2=270.000000
L 3.23811693 3.57136654 3.23553317 3.56906634 1 P 0 ;0,1=545,2=270.000000
L 3.23553317 3.56906634 3.2345 3.56599961 1 P 0 ;0,1=545,2=270.000000
L 4.492 2.767 4.418 2.767 1 P 0 
L 4.418 2.767 4.418 2.643 1 P 0 
L 4.418 2.643 4.492 2.643 1 P 0 
L 4.492 2.643 4.492 2.767 1 P 0 
L 4.55708376 2.68193327 4.55553317 2.67963307 1 P 0 ;0,1=546,2=270.000000
L 4.55553317 2.67963307 4.5545 2.6769503 1 P 0 ;0,1=546,2=270.000000
L 4.5545 2.6769503 4.5545 2.67388356 1 P 0 ;0,1=546,2=270.000000
L 4.5545 2.67388356 4.55605069 2.67043287 1 P 0 ;0,1=546,2=270.000000
L 4.55605069 2.67043287 4.55863346 2.6677501 1 P 0 ;0,1=546,2=270.000000
L 4.55863346 2.6677501 4.56173376 2.66583317 1 P 0 ;0,1=546,2=270.000000
L 4.56173376 2.66583317 4.5669002 2.66429951 1 P 0 ;0,1=546,2=270.000000
L 4.5669002 2.66429951 4.5715502 2.66391624 1 P 0 ;0,1=546,2=270.000000
L 4.5715502 2.66391624 4.5762001 2.66468337 1 P 0 ;0,1=546,2=270.000000
L 4.5762001 2.66468337 4.57930039 2.66583317 1 P 0 ;0,1=546,2=270.000000
L 4.57930039 2.66583317 4.58240069 2.66813337 1 P 0 ;0,1=546,2=270.000000
L 4.58240069 2.66813337 4.58446693 2.67081683 1 P 0 ;0,1=546,2=270.000000
L 4.58446693 2.67081683 4.5855 2.67349961 1 P 0 ;0,1=546,2=270.000000
L 4.5855 2.67349961 4.5855 2.67618307 1 P 0 ;0,1=546,2=270.000000
L 4.5855 2.67618307 4.58446693 2.67886654 1 P 0 ;0,1=546,2=270.000000
L 4.58446693 2.67886654 4.58291722 2.68116673 1 P 0 ;0,1=546,2=270.000000
L 4.58291722 2.68116673 4.58085108 2.68308366 1 P 0 ;0,1=546,2=270.000000
L 4.55966654 2.69721644 4.55656722 2.69951663 1 P 0 ;0,1=546,2=270.000000
L 4.55656722 2.69951663 4.55501663 2.7022001 1 P 0 ;0,1=546,2=270.000000
L 4.55501663 2.7022001 4.5545 2.70526683 1 P 0 ;0,1=546,2=270.000000
L 4.5545 2.70526683 4.55553317 2.7091 1 P 0 ;0,1=546,2=270.000000
L 4.55553317 2.7091 4.55811693 2.71178346 1 P 0 ;0,1=546,2=270.000000
L 4.55811693 2.71178346 4.56121624 2.71255 1 P 0 ;0,1=546,2=270.000000
L 4.56121624 2.71255 4.56431742 2.71216673 1 P 0 ;0,1=546,2=270.000000
L 4.56431742 2.71216673 4.5669002 2.71063307 1 P 0 ;0,1=546,2=270.000000
L 4.5669002 2.71063307 4.57206673 2.70296663 1 P 0 ;0,1=546,2=270.000000
L 4.57206673 2.70296663 4.57568356 2.69951663 1 P 0 ;0,1=546,2=270.000000
L 4.57568356 2.69951663 4.58085108 2.69721644 1 P 0 ;0,1=546,2=270.000000
L 4.58085108 2.69721644 4.5855 2.6964499 1 P 0 ;0,1=546,2=270.000000
L 4.5855 2.6964499 4.5855 2.71255 1 P 0 ;0,1=546,2=270.000000
L 4.57930039 2.72706663 4.58291722 2.72936614 1 P 0 ;0,1=546,2=270.000000
L 4.58291722 2.72936614 4.58498346 2.73243287 1 P 0 ;0,1=546,2=270.000000
L 4.58498346 2.73243287 4.5855 2.73588356 1 P 0 ;0,1=546,2=270.000000
L 4.5855 2.73588356 4.58498346 2.7389503 1 P 0 ;0,1=546,2=270.000000
L 4.58498346 2.7389503 4.58240069 2.74201703 1 P 0 ;0,1=546,2=270.000000
L 4.58240069 2.74201703 4.57930039 2.74393327 1 P 0 ;0,1=546,2=270.000000
L 4.57930039 2.74393327 4.5762001 2.74431654 1 P 0 ;0,1=546,2=270.000000
L 4.5762001 2.74431654 4.57258425 2.74355 1 P 0 ;0,1=546,2=270.000000
L 4.57258425 2.74355 4.57000049 2.74086654 1 P 0 ;0,1=546,2=270.000000
L 4.57000049 2.74086654 4.56896644 2.73818307 1 P 0 ;0,1=546,2=270.000000
L 4.56896644 2.73818307 4.56896644 2.73473307 1 P 0 ;0,1=546,2=270.000000
L 4.56896644 2.73818307 4.56741683 2.74048327 1 P 0 ;0,1=546,2=270.000000
L 4.56741683 2.74048327 4.56483406 2.7424002 1 P 0 ;0,1=546,2=270.000000
L 4.56483406 2.7424002 4.56173376 2.74316673 1 P 0 ;0,1=546,2=270.000000
L 4.56173376 2.74316673 4.55863346 2.7424002 1 P 0 ;0,1=546,2=270.000000
L 4.55863346 2.7424002 4.55605069 2.74048327 1 P 0 ;0,1=546,2=270.000000
L 4.55605069 2.74048327 4.5545 2.73703327 1 P 0 ;0,1=546,2=270.000000
L 4.5545 2.73703327 4.55501663 2.73358337 1 P 0 ;0,1=546,2=270.000000
L 4.55501663 2.73358337 4.55708376 2.73013337 1 P 0 ;0,1=546,2=270.000000
L 4.55966654 2.75921644 4.55656722 2.76151663 1 P 0 ;0,1=546,2=270.000000
L 4.55656722 2.76151663 4.55501663 2.7642001 1 P 0 ;0,1=546,2=270.000000
L 4.55501663 2.7642001 4.5545 2.76726683 1 P 0 ;0,1=546,2=270.000000
L 4.5545 2.76726683 4.55553317 2.7711 1 P 0 ;0,1=546,2=270.000000
L 4.55553317 2.7711 4.55811693 2.77378346 1 P 0 ;0,1=546,2=270.000000
L 4.55811693 2.77378346 4.56121624 2.77455 1 P 0 ;0,1=546,2=270.000000
L 4.56121624 2.77455 4.56431742 2.77416673 1 P 0 ;0,1=546,2=270.000000
L 4.56431742 2.77416673 4.5669002 2.77263307 1 P 0 ;0,1=546,2=270.000000
L 4.5669002 2.77263307 4.57206673 2.76496663 1 P 0 ;0,1=546,2=270.000000
L 4.57206673 2.76496663 4.57568356 2.76151663 1 P 0 ;0,1=546,2=270.000000
L 4.57568356 2.76151663 4.58085108 2.75921644 1 P 0 ;0,1=546,2=270.000000
L 4.58085108 2.75921644 4.5855 2.7584499 1 P 0 ;0,1=546,2=270.000000
L 4.5855 2.7584499 4.5855 2.77455 1 P 0 ;0,1=546,2=270.000000
L 4.229 2.899 4.229 2.973 1 P 0 
L 4.229 2.973 4.105 2.973 1 P 0 
L 4.105 2.973 4.105 2.899 1 P 0 
L 4.105 2.899 4.229 2.899 1 P 0 
L 4.14193327 2.75341624 4.13963307 2.75496683 1 P 0 ;0,1=547,2=0.000000
L 4.13963307 2.75496683 4.1369503 2.756 1 P 0 ;0,1=547,2=0.000000
L 4.1369503 2.756 4.13388356 2.756 1 P 0 ;0,1=547,2=0.000000
L 4.13388356 2.756 4.13043287 2.75444931 1 P 0 ;0,1=547,2=0.000000
L 4.13043287 2.75444931 4.1277501 2.75186654 1 P 0 ;0,1=547,2=0.000000
L 4.1277501 2.75186654 4.12583317 2.74876624 1 P 0 ;0,1=547,2=0.000000
L 4.12583317 2.74876624 4.12429951 2.7435998 1 P 0 ;0,1=547,2=0.000000
L 4.12429951 2.7435998 4.12391624 2.7389498 1 P 0 ;0,1=547,2=0.000000
L 4.12391624 2.7389498 4.12468337 2.7342999 1 P 0 ;0,1=547,2=0.000000
L 4.12468337 2.7342999 4.12583317 2.73119961 1 P 0 ;0,1=547,2=0.000000
L 4.12583317 2.73119961 4.12813337 2.72809931 1 P 0 ;0,1=547,2=0.000000
L 4.12813337 2.72809931 4.13081683 2.72603307 1 P 0 ;0,1=547,2=0.000000
L 4.13081683 2.72603307 4.13349961 2.725 1 P 0 ;0,1=547,2=0.000000
L 4.13349961 2.725 4.13618307 2.725 1 P 0 ;0,1=547,2=0.000000
L 4.13618307 2.725 4.13886654 2.72603307 1 P 0 ;0,1=547,2=0.000000
L 4.13886654 2.72603307 4.14116673 2.72758278 1 P 0 ;0,1=547,2=0.000000
L 4.14116673 2.72758278 4.14308366 2.72964892 1 P 0 ;0,1=547,2=0.000000
L 4.15721644 2.75083346 4.15951663 2.75393278 1 P 0 ;0,1=547,2=0.000000
L 4.15951663 2.75393278 4.1622001 2.75548337 1 P 0 ;0,1=547,2=0.000000
L 4.1622001 2.75548337 4.16526683 2.756 1 P 0 ;0,1=547,2=0.000000
L 4.16526683 2.756 4.1691 2.75496683 1 P 0 ;0,1=547,2=0.000000
L 4.1691 2.75496683 4.17178346 2.75238307 1 P 0 ;0,1=547,2=0.000000
L 4.17178346 2.75238307 4.17255 2.74928376 1 P 0 ;0,1=547,2=0.000000
L 4.17255 2.74928376 4.17216673 2.74618258 1 P 0 ;0,1=547,2=0.000000
L 4.17216673 2.74618258 4.17063307 2.7435998 1 P 0 ;0,1=547,2=0.000000
L 4.17063307 2.7435998 4.16296663 2.73843327 1 P 0 ;0,1=547,2=0.000000
L 4.16296663 2.73843327 4.15951663 2.73481644 1 P 0 ;0,1=547,2=0.000000
L 4.15951663 2.73481644 4.15721644 2.72964892 1 P 0 ;0,1=547,2=0.000000
L 4.15721644 2.72964892 4.1564499 2.725 1 P 0 ;0,1=547,2=0.000000
L 4.1564499 2.725 4.17255 2.725 1 P 0 ;0,1=547,2=0.000000
L 4.18706663 2.73119961 4.18936614 2.72758278 1 P 0 ;0,1=547,2=0.000000
L 4.18936614 2.72758278 4.19243287 2.72551654 1 P 0 ;0,1=547,2=0.000000
L 4.19243287 2.72551654 4.19588356 2.725 1 P 0 ;0,1=547,2=0.000000
L 4.19588356 2.725 4.1989503 2.72551654 1 P 0 ;0,1=547,2=0.000000
L 4.1989503 2.72551654 4.20201703 2.72809931 1 P 0 ;0,1=547,2=0.000000
L 4.20201703 2.72809931 4.20393327 2.73119961 1 P 0 ;0,1=547,2=0.000000
L 4.20393327 2.73119961 4.20431654 2.7342999 1 P 0 ;0,1=547,2=0.000000
L 4.20431654 2.7342999 4.20355 2.73791575 1 P 0 ;0,1=547,2=0.000000
L 4.20355 2.73791575 4.20086654 2.74049951 1 P 0 ;0,1=547,2=0.000000
L 4.20086654 2.74049951 4.19818307 2.74153356 1 P 0 ;0,1=547,2=0.000000
L 4.19818307 2.74153356 4.19473307 2.74153356 1 P 0 ;0,1=547,2=0.000000
L 4.19818307 2.74153356 4.20048327 2.74308317 1 P 0 ;0,1=547,2=0.000000
L 4.20048327 2.74308317 4.2024002 2.74566594 1 P 0 ;0,1=547,2=0.000000
L 4.2024002 2.74566594 4.20316673 2.74876624 1 P 0 ;0,1=547,2=0.000000
L 4.20316673 2.74876624 4.2024002 2.75186654 1 P 0 ;0,1=547,2=0.000000
L 4.2024002 2.75186654 4.20048327 2.75444931 1 P 0 ;0,1=547,2=0.000000
L 4.20048327 2.75444931 4.19703327 2.756 1 P 0 ;0,1=547,2=0.000000
L 4.19703327 2.756 4.19358337 2.75548337 1 P 0 ;0,1=547,2=0.000000
L 4.19358337 2.75548337 4.19013337 2.75341624 1 P 0 ;0,1=547,2=0.000000
L 4.22649961 2.725 4.22918307 2.72551654 1 P 0 ;0,1=547,2=0.000000
L 4.22918307 2.72551654 4.2322498 2.72706614 1 P 0 ;0,1=547,2=0.000000
L 4.2322498 2.72706614 4.23416673 2.72964892 1 P 0 ;0,1=547,2=0.000000
L 4.23416673 2.72964892 4.23493327 2.73326673 1 P 0 ;0,1=547,2=0.000000
L 4.23493327 2.73326673 4.23416673 2.73688268 1 P 0 ;0,1=547,2=0.000000
L 4.23416673 2.73688268 4.23186654 2.73998287 1 P 0 ;0,1=547,2=0.000000
L 4.23186654 2.73998287 4.22841654 2.74153356 1 P 0 ;0,1=547,2=0.000000
L 4.22841654 2.74153356 4.22458337 2.74153356 1 P 0 ;0,1=547,2=0.000000
L 4.22458337 2.74153356 4.22228317 2.74256663 1 P 0 ;0,1=547,2=0.000000
L 4.22228317 2.74256663 4.22036614 2.74514941 1 P 0 ;0,1=547,2=0.000000
L 4.22036614 2.74514941 4.2195997 2.74876624 1 P 0 ;0,1=547,2=0.000000
L 4.2195997 2.74876624 4.2207501 2.75238307 1 P 0 ;0,1=547,2=0.000000
L 4.2207501 2.75238307 4.22343287 2.75496683 1 P 0 ;0,1=547,2=0.000000
L 4.22343287 2.75496683 4.22649961 2.756 1 P 0 ;0,1=547,2=0.000000
L 4.22649961 2.756 4.22956634 2.75496683 1 P 0 ;0,1=547,2=0.000000
L 4.22956634 2.75496683 4.2322498 2.75238307 1 P 0 ;0,1=547,2=0.000000
L 4.2322498 2.75238307 4.2334002 2.74876624 1 P 0 ;0,1=547,2=0.000000
L 4.2334002 2.74876624 4.23263307 2.74514941 1 P 0 ;0,1=547,2=0.000000
L 4.23263307 2.74514941 4.23071673 2.74256663 1 P 0 ;0,1=547,2=0.000000
L 4.23071673 2.74256663 4.22841654 2.74153356 1 P 0 ;0,1=547,2=0.000000
L 4.22841654 2.74153356 4.22458337 2.74153356 1 P 0 ;0,1=547,2=0.000000
L 4.22458337 2.74153356 4.22113337 2.73998287 1 P 0 ;0,1=547,2=0.000000
L 4.22113337 2.73998287 4.21883317 2.73688268 1 P 0 ;0,1=547,2=0.000000
L 4.21883317 2.73688268 4.21806663 2.73326673 1 P 0 ;0,1=547,2=0.000000
L 4.21806663 2.73326673 4.21883317 2.72964892 1 P 0 ;0,1=547,2=0.000000
L 4.21883317 2.72964892 4.2207501 2.72706614 1 P 0 ;0,1=547,2=0.000000
L 4.2207501 2.72706614 4.22381683 2.72551654 1 P 0 ;0,1=547,2=0.000000
L 4.22381683 2.72551654 4.22649961 2.725 1 P 0 ;0,1=547,2=0.000000
L 3.437 3.747 3.363 3.747 1 P 0 
L 3.437 3.623 3.437 3.747 1 P 0 
L 3.363 3.747 3.363 3.623 1 P 0 
L 3.363 3.623 3.437 3.623 1 P 0 
L 3.19708376 3.51243327 3.19553317 3.51013307 1 P 0 ;0,1=548,2=270.000000
L 3.19553317 3.51013307 3.1945 3.5074503 1 P 0 ;0,1=548,2=270.000000
L 3.1945 3.5074503 3.1945 3.50438356 1 P 0 ;0,1=548,2=270.000000
L 3.1945 3.50438356 3.19605069 3.50093287 1 P 0 ;0,1=548,2=270.000000
L 3.19605069 3.50093287 3.19863346 3.4982501 1 P 0 ;0,1=548,2=270.000000
L 3.19863346 3.4982501 3.20173376 3.49633317 1 P 0 ;0,1=548,2=270.000000
L 3.20173376 3.49633317 3.2069002 3.49479951 1 P 0 ;0,1=548,2=270.000000
L 3.2069002 3.49479951 3.2115502 3.49441624 1 P 0 ;0,1=548,2=270.000000
L 3.2115502 3.49441624 3.2162001 3.49518337 1 P 0 ;0,1=548,2=270.000000
L 3.2162001 3.49518337 3.21930039 3.49633317 1 P 0 ;0,1=548,2=270.000000
L 3.21930039 3.49633317 3.22240069 3.49863337 1 P 0 ;0,1=548,2=270.000000
L 3.22240069 3.49863337 3.22446693 3.50131683 1 P 0 ;0,1=548,2=270.000000
L 3.22446693 3.50131683 3.2255 3.50399961 1 P 0 ;0,1=548,2=270.000000
L 3.2255 3.50399961 3.2255 3.50668307 1 P 0 ;0,1=548,2=270.000000
L 3.2255 3.50668307 3.22446693 3.50936654 1 P 0 ;0,1=548,2=270.000000
L 3.22446693 3.50936654 3.22291722 3.51166673 1 P 0 ;0,1=548,2=270.000000
L 3.22291722 3.51166673 3.22085108 3.51358366 1 P 0 ;0,1=548,2=270.000000
L 3.19966654 3.52771644 3.19656722 3.53001663 1 P 0 ;0,1=548,2=270.000000
L 3.19656722 3.53001663 3.19501663 3.5327001 1 P 0 ;0,1=548,2=270.000000
L 3.19501663 3.5327001 3.1945 3.53576683 1 P 0 ;0,1=548,2=270.000000
L 3.1945 3.53576683 3.19553317 3.5396 1 P 0 ;0,1=548,2=270.000000
L 3.19553317 3.5396 3.19811693 3.54228346 1 P 0 ;0,1=548,2=270.000000
L 3.19811693 3.54228346 3.20121624 3.54305 1 P 0 ;0,1=548,2=270.000000
L 3.20121624 3.54305 3.20431742 3.54266673 1 P 0 ;0,1=548,2=270.000000
L 3.20431742 3.54266673 3.2069002 3.54113307 1 P 0 ;0,1=548,2=270.000000
L 3.2069002 3.54113307 3.21206673 3.53346663 1 P 0 ;0,1=548,2=270.000000
L 3.21206673 3.53346663 3.21568356 3.53001663 1 P 0 ;0,1=548,2=270.000000
L 3.21568356 3.53001663 3.22085108 3.52771644 1 P 0 ;0,1=548,2=270.000000
L 3.22085108 3.52771644 3.2255 3.5269499 1 P 0 ;0,1=548,2=270.000000
L 3.2255 3.5269499 3.2255 3.54305 1 P 0 ;0,1=548,2=270.000000
L 3.19966654 3.55871644 3.19656722 3.56101663 1 P 0 ;0,1=548,2=270.000000
L 3.19656722 3.56101663 3.19501663 3.5637001 1 P 0 ;0,1=548,2=270.000000
L 3.19501663 3.5637001 3.1945 3.56676683 1 P 0 ;0,1=548,2=270.000000
L 3.1945 3.56676683 3.19553317 3.5706 1 P 0 ;0,1=548,2=270.000000
L 3.19553317 3.5706 3.19811693 3.57328346 1 P 0 ;0,1=548,2=270.000000
L 3.19811693 3.57328346 3.20121624 3.57405 1 P 0 ;0,1=548,2=270.000000
L 3.20121624 3.57405 3.20431742 3.57366673 1 P 0 ;0,1=548,2=270.000000
L 3.20431742 3.57366673 3.2069002 3.57213307 1 P 0 ;0,1=548,2=270.000000
L 3.2069002 3.57213307 3.21206673 3.56446663 1 P 0 ;0,1=548,2=270.000000
L 3.21206673 3.56446663 3.21568356 3.56101663 1 P 0 ;0,1=548,2=270.000000
L 3.21568356 3.56101663 3.22085108 3.55871644 1 P 0 ;0,1=548,2=270.000000
L 3.22085108 3.55871644 3.2255 3.5579499 1 P 0 ;0,1=548,2=270.000000
L 3.2255 3.5579499 3.2255 3.57405 1 P 0 ;0,1=548,2=270.000000
L 4.229 2.818 4.229 2.892 1 P 0 
L 4.229 2.892 4.105 2.892 1 P 0 
L 4.105 2.892 4.105 2.818 1 P 0 
L 4.105 2.818 4.229 2.818 1 P 0 
L 4.14193327 2.70841624 4.13963307 2.70996683 1 P 0 ;0,1=549,2=0.000000
L 4.13963307 2.70996683 4.1369503 2.711 1 P 0 ;0,1=549,2=0.000000
L 4.1369503 2.711 4.13388356 2.711 1 P 0 ;0,1=549,2=0.000000
L 4.13388356 2.711 4.13043287 2.70944931 1 P 0 ;0,1=549,2=0.000000
L 4.13043287 2.70944931 4.1277501 2.70686654 1 P 0 ;0,1=549,2=0.000000
L 4.1277501 2.70686654 4.12583317 2.70376624 1 P 0 ;0,1=549,2=0.000000
L 4.12583317 2.70376624 4.12429951 2.6985998 1 P 0 ;0,1=549,2=0.000000
L 4.12429951 2.6985998 4.12391624 2.6939498 1 P 0 ;0,1=549,2=0.000000
L 4.12391624 2.6939498 4.12468337 2.6892999 1 P 0 ;0,1=549,2=0.000000
L 4.12468337 2.6892999 4.12583317 2.68619961 1 P 0 ;0,1=549,2=0.000000
L 4.12583317 2.68619961 4.12813337 2.68309931 1 P 0 ;0,1=549,2=0.000000
L 4.12813337 2.68309931 4.13081683 2.68103307 1 P 0 ;0,1=549,2=0.000000
L 4.13081683 2.68103307 4.13349961 2.68 1 P 0 ;0,1=549,2=0.000000
L 4.13349961 2.68 4.13618307 2.68 1 P 0 ;0,1=549,2=0.000000
L 4.13618307 2.68 4.13886654 2.68103307 1 P 0 ;0,1=549,2=0.000000
L 4.13886654 2.68103307 4.14116673 2.68258278 1 P 0 ;0,1=549,2=0.000000
L 4.14116673 2.68258278 4.14308366 2.68464892 1 P 0 ;0,1=549,2=0.000000
L 4.15721644 2.70583346 4.15951663 2.70893278 1 P 0 ;0,1=549,2=0.000000
L 4.15951663 2.70893278 4.1622001 2.71048337 1 P 0 ;0,1=549,2=0.000000
L 4.1622001 2.71048337 4.16526683 2.711 1 P 0 ;0,1=549,2=0.000000
L 4.16526683 2.711 4.1691 2.70996683 1 P 0 ;0,1=549,2=0.000000
L 4.1691 2.70996683 4.17178346 2.70738307 1 P 0 ;0,1=549,2=0.000000
L 4.17178346 2.70738307 4.17255 2.70428376 1 P 0 ;0,1=549,2=0.000000
L 4.17255 2.70428376 4.17216673 2.70118258 1 P 0 ;0,1=549,2=0.000000
L 4.17216673 2.70118258 4.17063307 2.6985998 1 P 0 ;0,1=549,2=0.000000
L 4.17063307 2.6985998 4.16296663 2.69343327 1 P 0 ;0,1=549,2=0.000000
L 4.16296663 2.69343327 4.15951663 2.68981644 1 P 0 ;0,1=549,2=0.000000
L 4.15951663 2.68981644 4.15721644 2.68464892 1 P 0 ;0,1=549,2=0.000000
L 4.15721644 2.68464892 4.1564499 2.68 1 P 0 ;0,1=549,2=0.000000
L 4.1564499 2.68 4.17255 2.68 1 P 0 ;0,1=549,2=0.000000
L 4.2001 2.68 4.2001 2.711 1 P 0 ;0,1=549,2=0.000000
L 4.2001 2.711 4.18591624 2.68878327 1 P 0 ;0,1=549,2=0.000000
L 4.18591624 2.68878327 4.20508366 2.68878327 1 P 0 ;0,1=549,2=0.000000
L 4.22649961 2.711 4.22343287 2.70996683 1 P 0 ;0,1=549,2=0.000000
L 4.22343287 2.70996683 4.22113337 2.70738307 1 P 0 ;0,1=549,2=0.000000
L 4.22113337 2.70738307 4.2195997 2.70428376 1 P 0 ;0,1=549,2=0.000000
L 4.2195997 2.70428376 4.2184499 2.70014941 1 P 0 ;0,1=549,2=0.000000
L 4.2184499 2.70014941 4.21806663 2.69549951 1 P 0 ;0,1=549,2=0.000000
L 4.21806663 2.69549951 4.2184499 2.69084951 1 P 0 ;0,1=549,2=0.000000
L 4.2184499 2.69084951 4.2195997 2.68671614 1 P 0 ;0,1=549,2=0.000000
L 4.2195997 2.68671614 4.22113337 2.68361585 1 P 0 ;0,1=549,2=0.000000
L 4.22113337 2.68361585 4.22343287 2.68103307 1 P 0 ;0,1=549,2=0.000000
L 4.22343287 2.68103307 4.22649961 2.68 1 P 0 ;0,1=549,2=0.000000
L 4.22649961 2.68 4.22956634 2.68103307 1 P 0 ;0,1=549,2=0.000000
L 4.22956634 2.68103307 4.23186654 2.68361585 1 P 0 ;0,1=549,2=0.000000
L 4.23186654 2.68361585 4.2334002 2.68671614 1 P 0 ;0,1=549,2=0.000000
L 4.2334002 2.68671614 4.23455 2.69084951 1 P 0 ;0,1=549,2=0.000000
L 4.23455 2.69084951 4.23493327 2.69549951 1 P 0 ;0,1=549,2=0.000000
L 4.23493327 2.69549951 4.23455 2.70014941 1 P 0 ;0,1=549,2=0.000000
L 4.23455 2.70014941 4.2334002 2.70428376 1 P 0 ;0,1=549,2=0.000000
L 4.2334002 2.70428376 4.23186654 2.70738307 1 P 0 ;0,1=549,2=0.000000
L 4.23186654 2.70738307 4.22956634 2.70996683 1 P 0 ;0,1=549,2=0.000000
L 4.22956634 2.70996683 4.22649961 2.711 1 P 0 ;0,1=549,2=0.000000
L 3.766 2.899 3.692 2.899 1 P 0 
L 3.766 2.775 3.766 2.899 1 P 0 
L 3.692 2.899 3.692 2.775 1 P 0 
L 3.692 2.775 3.766 2.775 1 P 0 
L 2.63208376 3.58193327 2.63053317 3.57963307 1 P 0 ;0,1=550,2=270.000000
L 2.63053317 3.57963307 2.6295 3.5769503 1 P 0 ;0,1=550,2=270.000000
L 2.6295 3.5769503 2.6295 3.57388356 1 P 0 ;0,1=550,2=270.000000
L 2.6295 3.57388356 2.63105069 3.57043287 1 P 0 ;0,1=550,2=270.000000
L 2.63105069 3.57043287 2.63363346 3.5677501 1 P 0 ;0,1=550,2=270.000000
L 2.63363346 3.5677501 2.63673376 3.56583317 1 P 0 ;0,1=550,2=270.000000
L 2.63673376 3.56583317 2.6419002 3.56429951 1 P 0 ;0,1=550,2=270.000000
L 2.6419002 3.56429951 2.6465502 3.56391624 1 P 0 ;0,1=550,2=270.000000
L 2.6465502 3.56391624 2.6512001 3.56468337 1 P 0 ;0,1=550,2=270.000000
L 2.6512001 3.56468337 2.65430039 3.56583317 1 P 0 ;0,1=550,2=270.000000
L 2.65430039 3.56583317 2.65740069 3.56813337 1 P 0 ;0,1=550,2=270.000000
L 2.65740069 3.56813337 2.65946693 3.57081683 1 P 0 ;0,1=550,2=270.000000
L 2.65946693 3.57081683 2.6605 3.57349961 1 P 0 ;0,1=550,2=270.000000
L 2.6605 3.57349961 2.6605 3.57618307 1 P 0 ;0,1=550,2=270.000000
L 2.6605 3.57618307 2.65946693 3.57886654 1 P 0 ;0,1=550,2=270.000000
L 2.65946693 3.57886654 2.65791722 3.58116673 1 P 0 ;0,1=550,2=270.000000
L 2.65791722 3.58116673 2.65585108 3.58308366 1 P 0 ;0,1=550,2=270.000000
L 2.6605 3.60449961 2.6295 3.60449961 1 P 0 ;0,1=550,2=270.000000
L 2.6295 3.60449961 2.6356997 3.5998999 1 P 0 ;0,1=550,2=270.000000
L 2.6605 3.5998999 2.6605 3.60909931 1 P 0 ;0,1=550,2=270.000000
L 2.65688415 3.62898287 2.65946693 3.63166634 1 P 0 ;0,1=550,2=270.000000
L 2.65946693 3.63166634 2.6605 3.63473307 1 P 0 ;0,1=550,2=270.000000
L 2.6605 3.63473307 2.65946693 3.6377998 1 P 0 ;0,1=550,2=270.000000
L 2.65946693 3.6377998 2.65636762 3.64048327 1 P 0 ;0,1=550,2=270.000000
L 2.65636762 3.64048327 2.65171673 3.6424002 1 P 0 ;0,1=550,2=270.000000
L 2.65171673 3.6424002 2.64706673 3.64316673 1 P 0 ;0,1=550,2=270.000000
L 2.64706673 3.64316673 2.64138366 3.64316673 1 P 0 ;0,1=550,2=270.000000
L 2.64138366 3.64316673 2.63673376 3.6424002 1 P 0 ;0,1=550,2=270.000000
L 2.63673376 3.6424002 2.6326003 3.64048327 1 P 0 ;0,1=550,2=270.000000
L 2.6326003 3.64048327 2.63053317 3.63818307 1 P 0 ;0,1=550,2=270.000000
L 2.63053317 3.63818307 2.6295 3.63549961 1 P 0 ;0,1=550,2=270.000000
L 2.6295 3.63549961 2.63053317 3.63243287 1 P 0 ;0,1=550,2=270.000000
L 2.63053317 3.63243287 2.6326003 3.63013337 1 P 0 ;0,1=550,2=270.000000
L 2.6326003 3.63013337 2.6356997 3.6285997 1 P 0 ;0,1=550,2=270.000000
L 2.6356997 3.6285997 2.63983406 3.62783317 1 P 0 ;0,1=550,2=270.000000
L 2.63983406 3.62783317 2.6434499 3.6285997 1 P 0 ;0,1=550,2=270.000000
L 2.6434499 3.6285997 2.64706673 3.63051663 1 P 0 ;0,1=550,2=270.000000
L 2.64706673 3.63051663 2.64913396 3.63281683 1 P 0 ;0,1=550,2=270.000000
L 2.64913396 3.63281683 2.64965049 3.63549961 1 P 0 ;0,1=550,2=270.000000
L 2.64965049 3.63549961 2.64861732 3.63856634 1 P 0 ;0,1=550,2=270.000000
L 2.64861732 3.63856634 2.64603366 3.64086654 1 P 0 ;0,1=550,2=270.000000
L 2.64603366 3.64086654 2.64138366 3.64316673 1 P 0 ;0,1=550,2=270.000000
L 2.6605 3.6711 2.6295 3.6711 1 P 0 ;0,1=550,2=270.000000
L 2.6295 3.6711 2.65171673 3.65691624 1 P 0 ;0,1=550,2=270.000000
L 2.65171673 3.65691624 2.65171673 3.67608366 1 P 0 ;0,1=550,2=270.000000
L 5.087 3.808 5.087 3.932 1 P 0 
L 5.087 3.932 5.013 3.932 1 P 0 
L 5.013 3.932 5.013 3.808 1 P 0 
L 5.013 3.808 5.087 3.808 1 P 0 
L 5.09208376 3.96243327 5.09053317 3.96013307 1 P 0 ;0,1=551,2=270.000000
L 5.09053317 3.96013307 5.0895 3.9574503 1 P 0 ;0,1=551,2=270.000000
L 5.0895 3.9574503 5.0895 3.95438356 1 P 0 ;0,1=551,2=270.000000
L 5.0895 3.95438356 5.09105069 3.95093287 1 P 0 ;0,1=551,2=270.000000
L 5.09105069 3.95093287 5.09363346 3.9482501 1 P 0 ;0,1=551,2=270.000000
L 5.09363346 3.9482501 5.09673376 3.94633317 1 P 0 ;0,1=551,2=270.000000
L 5.09673376 3.94633317 5.1019002 3.94479951 1 P 0 ;0,1=551,2=270.000000
L 5.1019002 3.94479951 5.1065502 3.94441624 1 P 0 ;0,1=551,2=270.000000
L 5.1065502 3.94441624 5.1112001 3.94518337 1 P 0 ;0,1=551,2=270.000000
L 5.1112001 3.94518337 5.11430039 3.94633317 1 P 0 ;0,1=551,2=270.000000
L 5.11430039 3.94633317 5.11740069 3.94863337 1 P 0 ;0,1=551,2=270.000000
L 5.11740069 3.94863337 5.11946693 3.95131683 1 P 0 ;0,1=551,2=270.000000
L 5.11946693 3.95131683 5.1205 3.95399961 1 P 0 ;0,1=551,2=270.000000
L 5.1205 3.95399961 5.1205 3.95668307 1 P 0 ;0,1=551,2=270.000000
L 5.1205 3.95668307 5.11946693 3.95936654 1 P 0 ;0,1=551,2=270.000000
L 5.11946693 3.95936654 5.11791722 3.96166673 1 P 0 ;0,1=551,2=270.000000
L 5.11791722 3.96166673 5.11585108 3.96358366 1 P 0 ;0,1=551,2=270.000000
L 5.1205 3.98423307 5.11378386 3.98499961 1 P 0 ;0,1=551,2=270.000000
L 5.11378386 3.98499961 5.10810079 3.9861501 1 P 0 ;0,1=551,2=270.000000
L 5.10810079 3.9861501 5.10293337 3.98768307 1 P 0 ;0,1=551,2=270.000000
L 5.10293337 3.98768307 5.0972503 3.9896 1 P 0 ;0,1=551,2=270.000000
L 5.0972503 3.9896 5.0895 3.99266673 1 P 0 ;0,1=551,2=270.000000
L 5.0895 3.99266673 5.0895 3.97733317 1 P 0 ;0,1=551,2=270.000000
L 5.09466654 4.00871644 5.09156722 4.01101663 1 P 0 ;0,1=551,2=270.000000
L 5.09156722 4.01101663 5.09001663 4.0137001 1 P 0 ;0,1=551,2=270.000000
L 5.09001663 4.0137001 5.0895 4.01676683 1 P 0 ;0,1=551,2=270.000000
L 5.0895 4.01676683 5.09053317 4.0206 1 P 0 ;0,1=551,2=270.000000
L 5.09053317 4.0206 5.09311693 4.02328346 1 P 0 ;0,1=551,2=270.000000
L 5.09311693 4.02328346 5.09621624 4.02405 1 P 0 ;0,1=551,2=270.000000
L 5.09621624 4.02405 5.09931742 4.02366673 1 P 0 ;0,1=551,2=270.000000
L 5.09931742 4.02366673 5.1019002 4.02213307 1 P 0 ;0,1=551,2=270.000000
L 5.1019002 4.02213307 5.10706673 4.01446663 1 P 0 ;0,1=551,2=270.000000
L 5.10706673 4.01446663 5.11068356 4.01101663 1 P 0 ;0,1=551,2=270.000000
L 5.11068356 4.01101663 5.11585108 4.00871644 1 P 0 ;0,1=551,2=270.000000
L 5.11585108 4.00871644 5.1205 4.0079499 1 P 0 ;0,1=551,2=270.000000
L 5.1205 4.0079499 5.1205 4.02405 1 P 0 ;0,1=551,2=270.000000
L 3.769 3.047 3.695 3.047 1 P 0 
L 3.695 3.047 3.695 2.923 1 P 0 
L 3.695 2.923 3.769 2.923 1 P 0 
L 3.769 2.923 3.769 3.047 1 P 0 
L 2.63208376 3.70693327 2.63053317 3.70463307 1 P 0 ;0,1=552,2=270.000000
L 2.63053317 3.70463307 2.6295 3.7019503 1 P 0 ;0,1=552,2=270.000000
L 2.6295 3.7019503 2.6295 3.69888356 1 P 0 ;0,1=552,2=270.000000
L 2.6295 3.69888356 2.63105069 3.69543287 1 P 0 ;0,1=552,2=270.000000
L 2.63105069 3.69543287 2.63363346 3.6927501 1 P 0 ;0,1=552,2=270.000000
L 2.63363346 3.6927501 2.63673376 3.69083317 1 P 0 ;0,1=552,2=270.000000
L 2.63673376 3.69083317 2.6419002 3.68929951 1 P 0 ;0,1=552,2=270.000000
L 2.6419002 3.68929951 2.6465502 3.68891624 1 P 0 ;0,1=552,2=270.000000
L 2.6465502 3.68891624 2.6512001 3.68968337 1 P 0 ;0,1=552,2=270.000000
L 2.6512001 3.68968337 2.65430039 3.69083317 1 P 0 ;0,1=552,2=270.000000
L 2.65430039 3.69083317 2.65740069 3.69313337 1 P 0 ;0,1=552,2=270.000000
L 2.65740069 3.69313337 2.65946693 3.69581683 1 P 0 ;0,1=552,2=270.000000
L 2.65946693 3.69581683 2.6605 3.69849961 1 P 0 ;0,1=552,2=270.000000
L 2.6605 3.69849961 2.6605 3.70118307 1 P 0 ;0,1=552,2=270.000000
L 2.6605 3.70118307 2.65946693 3.70386654 1 P 0 ;0,1=552,2=270.000000
L 2.65946693 3.70386654 2.65791722 3.70616673 1 P 0 ;0,1=552,2=270.000000
L 2.65791722 3.70616673 2.65585108 3.70808366 1 P 0 ;0,1=552,2=270.000000
L 2.6605 3.72949961 2.6295 3.72949961 1 P 0 ;0,1=552,2=270.000000
L 2.6295 3.72949961 2.6356997 3.7248999 1 P 0 ;0,1=552,2=270.000000
L 2.6605 3.7248999 2.6605 3.73409931 1 P 0 ;0,1=552,2=270.000000
L 2.6605 3.76049961 2.65998346 3.76318307 1 P 0 ;0,1=552,2=270.000000
L 2.65998346 3.76318307 2.65843386 3.7662498 1 P 0 ;0,1=552,2=270.000000
L 2.65843386 3.7662498 2.65585108 3.76816673 1 P 0 ;0,1=552,2=270.000000
L 2.65585108 3.76816673 2.65223327 3.76893327 1 P 0 ;0,1=552,2=270.000000
L 2.65223327 3.76893327 2.64861732 3.76816673 1 P 0 ;0,1=552,2=270.000000
L 2.64861732 3.76816673 2.64551713 3.76586654 1 P 0 ;0,1=552,2=270.000000
L 2.64551713 3.76586654 2.64396644 3.76241654 1 P 0 ;0,1=552,2=270.000000
L 2.64396644 3.76241654 2.64396644 3.75858337 1 P 0 ;0,1=552,2=270.000000
L 2.64396644 3.75858337 2.64293337 3.75628317 1 P 0 ;0,1=552,2=270.000000
L 2.64293337 3.75628317 2.64035059 3.75436614 1 P 0 ;0,1=552,2=270.000000
L 2.64035059 3.75436614 2.63673376 3.7535997 1 P 0 ;0,1=552,2=270.000000
L 2.63673376 3.7535997 2.63311693 3.7547501 1 P 0 ;0,1=552,2=270.000000
L 2.63311693 3.7547501 2.63053317 3.75743287 1 P 0 ;0,1=552,2=270.000000
L 2.63053317 3.75743287 2.6295 3.76049961 1 P 0 ;0,1=552,2=270.000000
L 2.6295 3.76049961 2.63053317 3.76356634 1 P 0 ;0,1=552,2=270.000000
L 2.63053317 3.76356634 2.63311693 3.7662498 1 P 0 ;0,1=552,2=270.000000
L 2.63311693 3.7662498 2.63673376 3.7674002 1 P 0 ;0,1=552,2=270.000000
L 2.63673376 3.7674002 2.64035059 3.76663307 1 P 0 ;0,1=552,2=270.000000
L 2.64035059 3.76663307 2.64293337 3.76471673 1 P 0 ;0,1=552,2=270.000000
L 2.64293337 3.76471673 2.64396644 3.76241654 1 P 0 ;0,1=552,2=270.000000
L 2.64396644 3.76241654 2.64396644 3.75858337 1 P 0 ;0,1=552,2=270.000000
L 2.64396644 3.75858337 2.64551713 3.75513337 1 P 0 ;0,1=552,2=270.000000
L 2.64551713 3.75513337 2.64861732 3.75283317 1 P 0 ;0,1=552,2=270.000000
L 2.64861732 3.75283317 2.65223327 3.75206663 1 P 0 ;0,1=552,2=270.000000
L 2.65223327 3.75206663 2.65585108 3.75283317 1 P 0 ;0,1=552,2=270.000000
L 2.65585108 3.75283317 2.65843386 3.7547501 1 P 0 ;0,1=552,2=270.000000
L 2.65843386 3.7547501 2.65998346 3.75781683 1 P 0 ;0,1=552,2=270.000000
L 2.65998346 3.75781683 2.6605 3.76049961 1 P 0 ;0,1=552,2=270.000000
L 2.65585108 3.78306663 2.65843386 3.78536614 1 P 0 ;0,1=552,2=270.000000
L 2.65843386 3.78536614 2.65998346 3.78804961 1 P 0 ;0,1=552,2=270.000000
L 2.65998346 3.78804961 2.6605 3.79149961 1 P 0 ;0,1=552,2=270.000000
L 2.6605 3.79149961 2.65946693 3.7949503 1 P 0 ;0,1=552,2=270.000000
L 2.65946693 3.7949503 2.65740069 3.79763307 1 P 0 ;0,1=552,2=270.000000
L 2.65740069 3.79763307 2.65378386 3.79955 1 P 0 ;0,1=552,2=270.000000
L 2.65378386 3.79955 2.64965049 3.79993327 1 P 0 ;0,1=552,2=270.000000
L 2.64965049 3.79993327 2.64551713 3.79916673 1 P 0 ;0,1=552,2=270.000000
L 2.64551713 3.79916673 2.64293337 3.7972498 1 P 0 ;0,1=552,2=270.000000
L 2.64293337 3.7972498 2.64086713 3.79456634 1 P 0 ;0,1=552,2=270.000000
L 2.64086713 3.79456634 2.64035059 3.79188356 1 P 0 ;0,1=552,2=270.000000
L 2.64035059 3.79188356 2.64086713 3.7892001 1 P 0 ;0,1=552,2=270.000000
L 2.64086713 3.7892001 2.64293337 3.7857501 1 P 0 ;0,1=552,2=270.000000
L 2.64293337 3.7857501 2.6295 3.7868999 1 P 0 ;0,1=552,2=270.000000
L 2.6295 3.7868999 2.6295 3.7972498 1 P 0 ;0,1=552,2=270.000000
L 3.35 4.165 3.35 4.239 1 P 0 
L 3.35 4.239 3.226 4.239 1 P 0 
L 3.226 4.239 3.226 4.165 1 P 0 
L 3.226 4.165 3.35 4.165 1 P 0 
L 3.27743327 4.28291624 3.27513307 4.28446683 1 P 0 ;0,1=553,2=0.000000
L 3.27513307 4.28446683 3.2724503 4.2855 1 P 0 ;0,1=553,2=0.000000
L 3.2724503 4.2855 3.26938356 4.2855 1 P 0 ;0,1=553,2=0.000000
L 3.26938356 4.2855 3.26593287 4.28394931 1 P 0 ;0,1=553,2=0.000000
L 3.26593287 4.28394931 3.2632501 4.28136654 1 P 0 ;0,1=553,2=0.000000
L 3.2632501 4.28136654 3.26133317 4.27826624 1 P 0 ;0,1=553,2=0.000000
L 3.26133317 4.27826624 3.25979951 4.2730998 1 P 0 ;0,1=553,2=0.000000
L 3.25979951 4.2730998 3.25941624 4.2684498 1 P 0 ;0,1=553,2=0.000000
L 3.25941624 4.2684498 3.26018337 4.2637999 1 P 0 ;0,1=553,2=0.000000
L 3.26018337 4.2637999 3.26133317 4.26069961 1 P 0 ;0,1=553,2=0.000000
L 3.26133317 4.26069961 3.26363337 4.25759931 1 P 0 ;0,1=553,2=0.000000
L 3.26363337 4.25759931 3.26631683 4.25553307 1 P 0 ;0,1=553,2=0.000000
L 3.26631683 4.25553307 3.26899961 4.2545 1 P 0 ;0,1=553,2=0.000000
L 3.26899961 4.2545 3.27168307 4.2545 1 P 0 ;0,1=553,2=0.000000
L 3.27168307 4.2545 3.27436654 4.25553307 1 P 0 ;0,1=553,2=0.000000
L 3.27436654 4.25553307 3.27666673 4.25708278 1 P 0 ;0,1=553,2=0.000000
L 3.27666673 4.25708278 3.27858366 4.25914892 1 P 0 ;0,1=553,2=0.000000
L 3.29156663 4.25914892 3.29386614 4.25656614 1 P 0 ;0,1=553,2=0.000000
L 3.29386614 4.25656614 3.29654961 4.25501654 1 P 0 ;0,1=553,2=0.000000
L 3.29654961 4.25501654 3.29999961 4.2545 1 P 0 ;0,1=553,2=0.000000
L 3.29999961 4.2545 3.3034503 4.25553307 1 P 0 ;0,1=553,2=0.000000
L 3.3034503 4.25553307 3.30613307 4.25759931 1 P 0 ;0,1=553,2=0.000000
L 3.30613307 4.25759931 3.30805 4.26121614 1 P 0 ;0,1=553,2=0.000000
L 3.30805 4.26121614 3.30843327 4.26534951 1 P 0 ;0,1=553,2=0.000000
L 3.30843327 4.26534951 3.30766673 4.26948287 1 P 0 ;0,1=553,2=0.000000
L 3.30766673 4.26948287 3.3057498 4.27206663 1 P 0 ;0,1=553,2=0.000000
L 3.3057498 4.27206663 3.30306634 4.27413287 1 P 0 ;0,1=553,2=0.000000
L 3.30306634 4.27413287 3.30038356 4.27464941 1 P 0 ;0,1=553,2=0.000000
L 3.30038356 4.27464941 3.2977001 4.27413287 1 P 0 ;0,1=553,2=0.000000
L 3.2977001 4.27413287 3.2942501 4.27206663 1 P 0 ;0,1=553,2=0.000000
L 3.2942501 4.27206663 3.2953999 4.2855 1 P 0 ;0,1=553,2=0.000000
L 3.2953999 4.2855 3.3057498 4.2855 1 P 0 ;0,1=553,2=0.000000
L 3.33099961 4.2855 3.32793287 4.28446683 1 P 0 ;0,1=553,2=0.000000
L 3.32793287 4.28446683 3.32563337 4.28188307 1 P 0 ;0,1=553,2=0.000000
L 3.32563337 4.28188307 3.3240997 4.27878376 1 P 0 ;0,1=553,2=0.000000
L 3.3240997 4.27878376 3.3229499 4.27464941 1 P 0 ;0,1=553,2=0.000000
L 3.3229499 4.27464941 3.32256663 4.26999951 1 P 0 ;0,1=553,2=0.000000
L 3.32256663 4.26999951 3.3229499 4.26534951 1 P 0 ;0,1=553,2=0.000000
L 3.3229499 4.26534951 3.3240997 4.26121614 1 P 0 ;0,1=553,2=0.000000
L 3.3240997 4.26121614 3.32563337 4.25811585 1 P 0 ;0,1=553,2=0.000000
L 3.32563337 4.25811585 3.32793287 4.25553307 1 P 0 ;0,1=553,2=0.000000
L 3.32793287 4.25553307 3.33099961 4.2545 1 P 0 ;0,1=553,2=0.000000
L 3.33099961 4.2545 3.33406634 4.25553307 1 P 0 ;0,1=553,2=0.000000
L 3.33406634 4.25553307 3.33636654 4.25811585 1 P 0 ;0,1=553,2=0.000000
L 3.33636654 4.25811585 3.3379002 4.26121614 1 P 0 ;0,1=553,2=0.000000
L 3.3379002 4.26121614 3.33905 4.26534951 1 P 0 ;0,1=553,2=0.000000
L 3.33905 4.26534951 3.33943327 4.26999951 1 P 0 ;0,1=553,2=0.000000
L 3.33943327 4.26999951 3.33905 4.27464941 1 P 0 ;0,1=553,2=0.000000
L 3.33905 4.27464941 3.3379002 4.27878376 1 P 0 ;0,1=553,2=0.000000
L 3.3379002 4.27878376 3.33636654 4.28188307 1 P 0 ;0,1=553,2=0.000000
L 3.33636654 4.28188307 3.33406634 4.28446683 1 P 0 ;0,1=553,2=0.000000
L 3.33406634 4.28446683 3.33099961 4.2855 1 P 0 ;0,1=553,2=0.000000
L 4.683 3.964 4.559 3.964 1 P 0 
L 4.559 3.964 4.559 3.89 1 P 0 
L 4.559 3.89 4.683 3.89 1 P 0 
L 4.683 3.89 4.683 3.964 1 P 0 
L 4.60743327 4.00791624 4.60513307 4.00946683 1 P 0 ;0,1=554,2=0.000000
L 4.60513307 4.00946683 4.6024503 4.0105 1 P 0 ;0,1=554,2=0.000000
L 4.6024503 4.0105 4.59938356 4.0105 1 P 0 ;0,1=554,2=0.000000
L 4.59938356 4.0105 4.59593287 4.00894931 1 P 0 ;0,1=554,2=0.000000
L 4.59593287 4.00894931 4.5932501 4.00636654 1 P 0 ;0,1=554,2=0.000000
L 4.5932501 4.00636654 4.59133317 4.00326624 1 P 0 ;0,1=554,2=0.000000
L 4.59133317 4.00326624 4.58979951 3.9980998 1 P 0 ;0,1=554,2=0.000000
L 4.58979951 3.9980998 4.58941624 3.9934498 1 P 0 ;0,1=554,2=0.000000
L 4.58941624 3.9934498 4.59018337 3.9887999 1 P 0 ;0,1=554,2=0.000000
L 4.59018337 3.9887999 4.59133317 3.98569961 1 P 0 ;0,1=554,2=0.000000
L 4.59133317 3.98569961 4.59363337 3.98259931 1 P 0 ;0,1=554,2=0.000000
L 4.59363337 3.98259931 4.59631683 3.98053307 1 P 0 ;0,1=554,2=0.000000
L 4.59631683 3.98053307 4.59899961 3.9795 1 P 0 ;0,1=554,2=0.000000
L 4.59899961 3.9795 4.60168307 3.9795 1 P 0 ;0,1=554,2=0.000000
L 4.60168307 3.9795 4.60436654 3.98053307 1 P 0 ;0,1=554,2=0.000000
L 4.60436654 3.98053307 4.60666673 3.98208278 1 P 0 ;0,1=554,2=0.000000
L 4.60666673 3.98208278 4.60858366 3.98414892 1 P 0 ;0,1=554,2=0.000000
L 4.62923307 3.9795 4.62999961 3.98621614 1 P 0 ;0,1=554,2=0.000000
L 4.62999961 3.98621614 4.6311501 3.99189921 1 P 0 ;0,1=554,2=0.000000
L 4.6311501 3.99189921 4.63268307 3.99706663 1 P 0 ;0,1=554,2=0.000000
L 4.63268307 3.99706663 4.6346 4.0027497 1 P 0 ;0,1=554,2=0.000000
L 4.6346 4.0027497 4.63766673 4.0105 1 P 0 ;0,1=554,2=0.000000
L 4.63766673 4.0105 4.62233317 4.0105 1 P 0 ;0,1=554,2=0.000000
L 4.65448287 3.98311585 4.65716634 3.98053307 1 P 0 ;0,1=554,2=0.000000
L 4.65716634 3.98053307 4.66023307 3.9795 1 P 0 ;0,1=554,2=0.000000
L 4.66023307 3.9795 4.6632998 3.98053307 1 P 0 ;0,1=554,2=0.000000
L 4.6632998 3.98053307 4.66598327 3.98363238 1 P 0 ;0,1=554,2=0.000000
L 4.66598327 3.98363238 4.6679002 3.98828327 1 P 0 ;0,1=554,2=0.000000
L 4.6679002 3.98828327 4.66866673 3.99293327 1 P 0 ;0,1=554,2=0.000000
L 4.66866673 3.99293327 4.66866673 3.99861634 1 P 0 ;0,1=554,2=0.000000
L 4.66866673 3.99861634 4.6679002 4.00326624 1 P 0 ;0,1=554,2=0.000000
L 4.6679002 4.00326624 4.66598327 4.0073997 1 P 0 ;0,1=554,2=0.000000
L 4.66598327 4.0073997 4.66368307 4.00946683 1 P 0 ;0,1=554,2=0.000000
L 4.66368307 4.00946683 4.66099961 4.0105 1 P 0 ;0,1=554,2=0.000000
L 4.66099961 4.0105 4.65793287 4.00946683 1 P 0 ;0,1=554,2=0.000000
L 4.65793287 4.00946683 4.65563337 4.0073997 1 P 0 ;0,1=554,2=0.000000
L 4.65563337 4.0073997 4.6540997 4.0043003 1 P 0 ;0,1=554,2=0.000000
L 4.6540997 4.0043003 4.65333317 4.00016594 1 P 0 ;0,1=554,2=0.000000
L 4.65333317 4.00016594 4.6540997 3.9965501 1 P 0 ;0,1=554,2=0.000000
L 4.6540997 3.9965501 4.65601663 3.99293327 1 P 0 ;0,1=554,2=0.000000
L 4.65601663 3.99293327 4.65831683 3.99086604 1 P 0 ;0,1=554,2=0.000000
L 4.65831683 3.99086604 4.66099961 3.99034951 1 P 0 ;0,1=554,2=0.000000
L 4.66099961 3.99034951 4.66406634 3.99138268 1 P 0 ;0,1=554,2=0.000000
L 4.66406634 3.99138268 4.66636654 3.99396634 1 P 0 ;0,1=554,2=0.000000
L 4.66636654 3.99396634 4.66866673 3.99861634 1 P 0 ;0,1=554,2=0.000000
L 5.109 2.497 5.109 2.571 1 P 0 
L 5.109 2.571 4.985 2.571 1 P 0 
L 4.985 2.497 5.109 2.497 1 P 0 
L 4.985 2.571 4.985 2.497 1 P 0 
L 5.04393327 2.34191624 5.04163307 2.34346683 1 P 0 ;0,1=555,2=0.000000
L 5.04163307 2.34346683 5.0389503 2.3445 1 P 0 ;0,1=555,2=0.000000
L 5.0389503 2.3445 5.03588356 2.3445 1 P 0 ;0,1=555,2=0.000000
L 5.03588356 2.3445 5.03243287 2.34294931 1 P 0 ;0,1=555,2=0.000000
L 5.03243287 2.34294931 5.0297501 2.34036654 1 P 0 ;0,1=555,2=0.000000
L 5.0297501 2.34036654 5.02783317 2.33726624 1 P 0 ;0,1=555,2=0.000000
L 5.02783317 2.33726624 5.02629951 2.3320998 1 P 0 ;0,1=555,2=0.000000
L 5.02629951 2.3320998 5.02591624 2.3274498 1 P 0 ;0,1=555,2=0.000000
L 5.02591624 2.3274498 5.02668337 2.3227999 1 P 0 ;0,1=555,2=0.000000
L 5.02668337 2.3227999 5.02783317 2.31969961 1 P 0 ;0,1=555,2=0.000000
L 5.02783317 2.31969961 5.03013337 2.31659931 1 P 0 ;0,1=555,2=0.000000
L 5.03013337 2.31659931 5.03281683 2.31453307 1 P 0 ;0,1=555,2=0.000000
L 5.03281683 2.31453307 5.03549961 2.3135 1 P 0 ;0,1=555,2=0.000000
L 5.03549961 2.3135 5.03818307 2.3135 1 P 0 ;0,1=555,2=0.000000
L 5.03818307 2.3135 5.04086654 2.31453307 1 P 0 ;0,1=555,2=0.000000
L 5.04086654 2.31453307 5.04316673 2.31608278 1 P 0 ;0,1=555,2=0.000000
L 5.04316673 2.31608278 5.04508366 2.31814892 1 P 0 ;0,1=555,2=0.000000
L 5.06649961 2.3135 5.06649961 2.3445 1 P 0 ;0,1=555,2=0.000000
L 5.06649961 2.3445 5.0618999 2.3383003 1 P 0 ;0,1=555,2=0.000000
L 5.0618999 2.3135 5.07109931 2.3135 1 P 0 ;0,1=555,2=0.000000
L 5.09749961 2.3135 5.10018307 2.31401654 1 P 0 ;0,1=555,2=0.000000
L 5.10018307 2.31401654 5.1032498 2.31556614 1 P 0 ;0,1=555,2=0.000000
L 5.1032498 2.31556614 5.10516673 2.31814892 1 P 0 ;0,1=555,2=0.000000
L 5.10516673 2.31814892 5.10593327 2.32176673 1 P 0 ;0,1=555,2=0.000000
L 5.10593327 2.32176673 5.10516673 2.32538268 1 P 0 ;0,1=555,2=0.000000
L 5.10516673 2.32538268 5.10286654 2.32848287 1 P 0 ;0,1=555,2=0.000000
L 5.10286654 2.32848287 5.09941654 2.33003356 1 P 0 ;0,1=555,2=0.000000
L 5.09941654 2.33003356 5.09558337 2.33003356 1 P 0 ;0,1=555,2=0.000000
L 5.09558337 2.33003356 5.09328317 2.33106663 1 P 0 ;0,1=555,2=0.000000
L 5.09328317 2.33106663 5.09136614 2.33364941 1 P 0 ;0,1=555,2=0.000000
L 5.09136614 2.33364941 5.0905997 2.33726624 1 P 0 ;0,1=555,2=0.000000
L 5.0905997 2.33726624 5.0917501 2.34088307 1 P 0 ;0,1=555,2=0.000000
L 5.0917501 2.34088307 5.09443287 2.34346683 1 P 0 ;0,1=555,2=0.000000
L 5.09443287 2.34346683 5.09749961 2.3445 1 P 0 ;0,1=555,2=0.000000
L 5.09749961 2.3445 5.10056634 2.34346683 1 P 0 ;0,1=555,2=0.000000
L 5.10056634 2.34346683 5.1032498 2.34088307 1 P 0 ;0,1=555,2=0.000000
L 5.1032498 2.34088307 5.1044002 2.33726624 1 P 0 ;0,1=555,2=0.000000
L 5.1044002 2.33726624 5.10363307 2.33364941 1 P 0 ;0,1=555,2=0.000000
L 5.10363307 2.33364941 5.10171673 2.33106663 1 P 0 ;0,1=555,2=0.000000
L 5.10171673 2.33106663 5.09941654 2.33003356 1 P 0 ;0,1=555,2=0.000000
L 5.09941654 2.33003356 5.09558337 2.33003356 1 P 0 ;0,1=555,2=0.000000
L 5.09558337 2.33003356 5.09213337 2.32848287 1 P 0 ;0,1=555,2=0.000000
L 5.09213337 2.32848287 5.08983317 2.32538268 1 P 0 ;0,1=555,2=0.000000
L 5.08983317 2.32538268 5.08906663 2.32176673 1 P 0 ;0,1=555,2=0.000000
L 5.08906663 2.32176673 5.08983317 2.31814892 1 P 0 ;0,1=555,2=0.000000
L 5.08983317 2.31814892 5.0917501 2.31556614 1 P 0 ;0,1=555,2=0.000000
L 5.0917501 2.31556614 5.09481683 2.31401654 1 P 0 ;0,1=555,2=0.000000
L 5.09481683 2.31401654 5.09749961 2.3135 1 P 0 ;0,1=555,2=0.000000
L 5.12121644 2.32641575 5.1238999 2.33003356 1 P 0 ;0,1=555,2=0.000000
L 5.1238999 2.33003356 5.1262001 2.3320998 1 P 0 ;0,1=555,2=0.000000
L 5.1262001 2.3320998 5.12926683 2.33313287 1 P 0 ;0,1=555,2=0.000000
L 5.12926683 2.33313287 5.1319503 2.3320998 1 P 0 ;0,1=555,2=0.000000
L 5.1319503 2.3320998 5.13386654 2.33003356 1 P 0 ;0,1=555,2=0.000000
L 5.13386654 2.33003356 5.1354002 2.32693327 1 P 0 ;0,1=555,2=0.000000
L 5.1354002 2.32693327 5.13578346 2.32331644 1 P 0 ;0,1=555,2=0.000000
L 5.13578346 2.32331644 5.1354002 2.32021614 1 P 0 ;0,1=555,2=0.000000
L 5.1354002 2.32021614 5.13386654 2.31711585 1 P 0 ;0,1=555,2=0.000000
L 5.13386654 2.31711585 5.13156634 2.31453307 1 P 0 ;0,1=555,2=0.000000
L 5.13156634 2.31453307 5.12888356 2.3135 1 P 0 ;0,1=555,2=0.000000
L 5.12888356 2.3135 5.12581683 2.31453307 1 P 0 ;0,1=555,2=0.000000
L 5.12581683 2.31453307 5.12313337 2.31763238 1 P 0 ;0,1=555,2=0.000000
L 5.12313337 2.31763238 5.1215997 2.32228327 1 P 0 ;0,1=555,2=0.000000
L 5.1215997 2.32228327 5.12121644 2.3274498 1 P 0 ;0,1=555,2=0.000000
L 5.12121644 2.3274498 5.12198287 2.33416594 1 P 0 ;0,1=555,2=0.000000
L 5.12198287 2.33416594 5.12313337 2.33778376 1 P 0 ;0,1=555,2=0.000000
L 5.12313337 2.33778376 5.12504961 2.3413997 1 P 0 ;0,1=555,2=0.000000
L 5.12504961 2.3413997 5.12773307 2.34398337 1 P 0 ;0,1=555,2=0.000000
L 5.12773307 2.34398337 5.13041654 2.3445 1 P 0 ;0,1=555,2=0.000000
L 5.13041654 2.3445 5.1331 2.34346683 1 P 0 ;0,1=555,2=0.000000
L 5.1331 2.34346683 5.13501703 2.34088307 1 P 0 ;0,1=555,2=0.000000
L 1.917 3.068 1.917 3.142 1 P 0 
L 1.793 3.068 1.917 3.068 1 P 0 
L 1.917 3.142 1.793 3.142 1 P 0 
L 1.793 3.142 1.793 3.068 1 P 0 
L 1.94193327 3.11791624 1.93963307 3.11946683 1 P 0 ;0,1=556,2=0.000000
L 1.93963307 3.11946683 1.9369503 3.1205 1 P 0 ;0,1=556,2=0.000000
L 1.9369503 3.1205 1.93388356 3.1205 1 P 0 ;0,1=556,2=0.000000
L 1.93388356 3.1205 1.93043287 3.11894931 1 P 0 ;0,1=556,2=0.000000
L 1.93043287 3.11894931 1.9277501 3.11636654 1 P 0 ;0,1=556,2=0.000000
L 1.9277501 3.11636654 1.92583317 3.11326624 1 P 0 ;0,1=556,2=0.000000
L 1.92583317 3.11326624 1.92429951 3.1080998 1 P 0 ;0,1=556,2=0.000000
L 1.92429951 3.1080998 1.92391624 3.1034498 1 P 0 ;0,1=556,2=0.000000
L 1.92391624 3.1034498 1.92468337 3.0987999 1 P 0 ;0,1=556,2=0.000000
L 1.92468337 3.0987999 1.92583317 3.09569961 1 P 0 ;0,1=556,2=0.000000
L 1.92583317 3.09569961 1.92813337 3.09259931 1 P 0 ;0,1=556,2=0.000000
L 1.92813337 3.09259931 1.93081683 3.09053307 1 P 0 ;0,1=556,2=0.000000
L 1.93081683 3.09053307 1.93349961 3.0895 1 P 0 ;0,1=556,2=0.000000
L 1.93349961 3.0895 1.93618307 3.0895 1 P 0 ;0,1=556,2=0.000000
L 1.93618307 3.0895 1.93886654 3.09053307 1 P 0 ;0,1=556,2=0.000000
L 1.93886654 3.09053307 1.94116673 3.09208278 1 P 0 ;0,1=556,2=0.000000
L 1.94116673 3.09208278 1.94308366 3.09414892 1 P 0 ;0,1=556,2=0.000000
L 1.95606663 3.09569961 1.95836614 3.09208278 1 P 0 ;0,1=556,2=0.000000
L 1.95836614 3.09208278 1.96143287 3.09001654 1 P 0 ;0,1=556,2=0.000000
L 1.96143287 3.09001654 1.96488356 3.0895 1 P 0 ;0,1=556,2=0.000000
L 1.96488356 3.0895 1.9679503 3.09001654 1 P 0 ;0,1=556,2=0.000000
L 1.9679503 3.09001654 1.97101703 3.09259931 1 P 0 ;0,1=556,2=0.000000
L 1.97101703 3.09259931 1.97293327 3.09569961 1 P 0 ;0,1=556,2=0.000000
L 1.97293327 3.09569961 1.97331654 3.0987999 1 P 0 ;0,1=556,2=0.000000
L 1.97331654 3.0987999 1.97255 3.10241575 1 P 0 ;0,1=556,2=0.000000
L 1.97255 3.10241575 1.96986654 3.10499951 1 P 0 ;0,1=556,2=0.000000
L 1.96986654 3.10499951 1.96718307 3.10603356 1 P 0 ;0,1=556,2=0.000000
L 1.96718307 3.10603356 1.96373307 3.10603356 1 P 0 ;0,1=556,2=0.000000
L 1.96718307 3.10603356 1.96948327 3.10758317 1 P 0 ;0,1=556,2=0.000000
L 1.96948327 3.10758317 1.9714002 3.11016594 1 P 0 ;0,1=556,2=0.000000
L 1.9714002 3.11016594 1.97216673 3.11326624 1 P 0 ;0,1=556,2=0.000000
L 1.97216673 3.11326624 1.9714002 3.11636654 1 P 0 ;0,1=556,2=0.000000
L 1.9714002 3.11636654 1.96948327 3.11894931 1 P 0 ;0,1=556,2=0.000000
L 1.96948327 3.11894931 1.96603327 3.1205 1 P 0 ;0,1=556,2=0.000000
L 1.96603327 3.1205 1.96258337 3.11998337 1 P 0 ;0,1=556,2=0.000000
L 1.96258337 3.11998337 1.95913337 3.11791624 1 P 0 ;0,1=556,2=0.000000
L 1.99549961 3.1205 1.99243287 3.11946683 1 P 0 ;0,1=556,2=0.000000
L 1.99243287 3.11946683 1.99013337 3.11688307 1 P 0 ;0,1=556,2=0.000000
L 1.99013337 3.11688307 1.9885997 3.11378376 1 P 0 ;0,1=556,2=0.000000
L 1.9885997 3.11378376 1.9874499 3.10964941 1 P 0 ;0,1=556,2=0.000000
L 1.9874499 3.10964941 1.98706663 3.10499951 1 P 0 ;0,1=556,2=0.000000
L 1.98706663 3.10499951 1.9874499 3.10034951 1 P 0 ;0,1=556,2=0.000000
L 1.9874499 3.10034951 1.9885997 3.09621614 1 P 0 ;0,1=556,2=0.000000
L 1.9885997 3.09621614 1.99013337 3.09311585 1 P 0 ;0,1=556,2=0.000000
L 1.99013337 3.09311585 1.99243287 3.09053307 1 P 0 ;0,1=556,2=0.000000
L 1.99243287 3.09053307 1.99549961 3.0895 1 P 0 ;0,1=556,2=0.000000
L 1.99549961 3.0895 1.99856634 3.09053307 1 P 0 ;0,1=556,2=0.000000
L 1.99856634 3.09053307 2.00086654 3.09311585 1 P 0 ;0,1=556,2=0.000000
L 2.00086654 3.09311585 2.0024002 3.09621614 1 P 0 ;0,1=556,2=0.000000
L 2.0024002 3.09621614 2.00355 3.10034951 1 P 0 ;0,1=556,2=0.000000
L 2.00355 3.10034951 2.00393327 3.10499951 1 P 0 ;0,1=556,2=0.000000
L 2.00393327 3.10499951 2.00355 3.10964941 1 P 0 ;0,1=556,2=0.000000
L 2.00355 3.10964941 2.0024002 3.11378376 1 P 0 ;0,1=556,2=0.000000
L 2.0024002 3.11378376 2.00086654 3.11688307 1 P 0 ;0,1=556,2=0.000000
L 2.00086654 3.11688307 1.99856634 3.11946683 1 P 0 ;0,1=556,2=0.000000
L 1.99856634 3.11946683 1.99549961 3.1205 1 P 0 ;0,1=556,2=0.000000
L 2.02649961 3.1205 2.02343287 3.11946683 1 P 0 ;0,1=556,2=0.000000
L 2.02343287 3.11946683 2.02113337 3.11688307 1 P 0 ;0,1=556,2=0.000000
L 2.02113337 3.11688307 2.0195997 3.11378376 1 P 0 ;0,1=556,2=0.000000
L 2.0195997 3.11378376 2.0184499 3.10964941 1 P 0 ;0,1=556,2=0.000000
L 2.0184499 3.10964941 2.01806663 3.10499951 1 P 0 ;0,1=556,2=0.000000
L 2.01806663 3.10499951 2.0184499 3.10034951 1 P 0 ;0,1=556,2=0.000000
L 2.0184499 3.10034951 2.0195997 3.09621614 1 P 0 ;0,1=556,2=0.000000
L 2.0195997 3.09621614 2.02113337 3.09311585 1 P 0 ;0,1=556,2=0.000000
L 2.02113337 3.09311585 2.02343287 3.09053307 1 P 0 ;0,1=556,2=0.000000
L 2.02343287 3.09053307 2.02649961 3.0895 1 P 0 ;0,1=556,2=0.000000
L 2.02649961 3.0895 2.02956634 3.09053307 1 P 0 ;0,1=556,2=0.000000
L 2.02956634 3.09053307 2.03186654 3.09311585 1 P 0 ;0,1=556,2=0.000000
L 2.03186654 3.09311585 2.0334002 3.09621614 1 P 0 ;0,1=556,2=0.000000
L 2.0334002 3.09621614 2.03455 3.10034951 1 P 0 ;0,1=556,2=0.000000
L 2.03455 3.10034951 2.03493327 3.10499951 1 P 0 ;0,1=556,2=0.000000
L 2.03493327 3.10499951 2.03455 3.10964941 1 P 0 ;0,1=556,2=0.000000
L 2.03455 3.10964941 2.0334002 3.11378376 1 P 0 ;0,1=556,2=0.000000
L 2.0334002 3.11378376 2.03186654 3.11688307 1 P 0 ;0,1=556,2=0.000000
L 2.03186654 3.11688307 2.02956634 3.11946683 1 P 0 ;0,1=556,2=0.000000
L 2.02956634 3.11946683 2.02649961 3.1205 1 P 0 ;0,1=556,2=0.000000
L 5.257 2.484 5.257 2.558 1 P 0 
L 5.257 2.558 5.133 2.558 1 P 0 
L 5.133 2.558 5.133 2.484 1 P 0 
L 5.133 2.484 5.257 2.484 1 P 0 
L 5.17193327 2.40291624 5.16963307 2.40446683 1 P 0 ;0,1=557,2=0.000000
L 5.16963307 2.40446683 5.1669503 2.4055 1 P 0 ;0,1=557,2=0.000000
L 5.1669503 2.4055 5.16388356 2.4055 1 P 0 ;0,1=557,2=0.000000
L 5.16388356 2.4055 5.16043287 2.40394931 1 P 0 ;0,1=557,2=0.000000
L 5.16043287 2.40394931 5.1577501 2.40136654 1 P 0 ;0,1=557,2=0.000000
L 5.1577501 2.40136654 5.15583317 2.39826624 1 P 0 ;0,1=557,2=0.000000
L 5.15583317 2.39826624 5.15429951 2.3930998 1 P 0 ;0,1=557,2=0.000000
L 5.15429951 2.3930998 5.15391624 2.3884498 1 P 0 ;0,1=557,2=0.000000
L 5.15391624 2.3884498 5.15468337 2.3837999 1 P 0 ;0,1=557,2=0.000000
L 5.15468337 2.3837999 5.15583317 2.38069961 1 P 0 ;0,1=557,2=0.000000
L 5.15583317 2.38069961 5.15813337 2.37759931 1 P 0 ;0,1=557,2=0.000000
L 5.15813337 2.37759931 5.16081683 2.37553307 1 P 0 ;0,1=557,2=0.000000
L 5.16081683 2.37553307 5.16349961 2.3745 1 P 0 ;0,1=557,2=0.000000
L 5.16349961 2.3745 5.16618307 2.3745 1 P 0 ;0,1=557,2=0.000000
L 5.16618307 2.3745 5.16886654 2.37553307 1 P 0 ;0,1=557,2=0.000000
L 5.16886654 2.37553307 5.17116673 2.37708278 1 P 0 ;0,1=557,2=0.000000
L 5.17116673 2.37708278 5.17308366 2.37914892 1 P 0 ;0,1=557,2=0.000000
L 5.19449961 2.3745 5.19449961 2.4055 1 P 0 ;0,1=557,2=0.000000
L 5.19449961 2.4055 5.1898999 2.3993003 1 P 0 ;0,1=557,2=0.000000
L 5.1898999 2.3745 5.19909931 2.3745 1 P 0 ;0,1=557,2=0.000000
L 5.21898287 2.37811585 5.22166634 2.37553307 1 P 0 ;0,1=557,2=0.000000
L 5.22166634 2.37553307 5.22473307 2.3745 1 P 0 ;0,1=557,2=0.000000
L 5.22473307 2.3745 5.2277998 2.37553307 1 P 0 ;0,1=557,2=0.000000
L 5.2277998 2.37553307 5.23048327 2.37863238 1 P 0 ;0,1=557,2=0.000000
L 5.23048327 2.37863238 5.2324002 2.38328327 1 P 0 ;0,1=557,2=0.000000
L 5.2324002 2.38328327 5.23316673 2.38793327 1 P 0 ;0,1=557,2=0.000000
L 5.23316673 2.38793327 5.23316673 2.39361634 1 P 0 ;0,1=557,2=0.000000
L 5.23316673 2.39361634 5.2324002 2.39826624 1 P 0 ;0,1=557,2=0.000000
L 5.2324002 2.39826624 5.23048327 2.4023997 1 P 0 ;0,1=557,2=0.000000
L 5.23048327 2.4023997 5.22818307 2.40446683 1 P 0 ;0,1=557,2=0.000000
L 5.22818307 2.40446683 5.22549961 2.4055 1 P 0 ;0,1=557,2=0.000000
L 5.22549961 2.4055 5.22243287 2.40446683 1 P 0 ;0,1=557,2=0.000000
L 5.22243287 2.40446683 5.22013337 2.4023997 1 P 0 ;0,1=557,2=0.000000
L 5.22013337 2.4023997 5.2185997 2.3993003 1 P 0 ;0,1=557,2=0.000000
L 5.2185997 2.3993003 5.21783317 2.39516594 1 P 0 ;0,1=557,2=0.000000
L 5.21783317 2.39516594 5.2185997 2.3915501 1 P 0 ;0,1=557,2=0.000000
L 5.2185997 2.3915501 5.22051663 2.38793327 1 P 0 ;0,1=557,2=0.000000
L 5.22051663 2.38793327 5.22281683 2.38586604 1 P 0 ;0,1=557,2=0.000000
L 5.22281683 2.38586604 5.22549961 2.38534951 1 P 0 ;0,1=557,2=0.000000
L 5.22549961 2.38534951 5.22856634 2.38638268 1 P 0 ;0,1=557,2=0.000000
L 5.22856634 2.38638268 5.23086654 2.38896634 1 P 0 ;0,1=557,2=0.000000
L 5.23086654 2.38896634 5.23316673 2.39361634 1 P 0 ;0,1=557,2=0.000000
L 5.24806663 2.37914892 5.25036614 2.37656614 1 P 0 ;0,1=557,2=0.000000
L 5.25036614 2.37656614 5.25304961 2.37501654 1 P 0 ;0,1=557,2=0.000000
L 5.25304961 2.37501654 5.25649961 2.3745 1 P 0 ;0,1=557,2=0.000000
L 5.25649961 2.3745 5.2599503 2.37553307 1 P 0 ;0,1=557,2=0.000000
L 5.2599503 2.37553307 5.26263307 2.37759931 1 P 0 ;0,1=557,2=0.000000
L 5.26263307 2.37759931 5.26455 2.38121614 1 P 0 ;0,1=557,2=0.000000
L 5.26455 2.38121614 5.26493327 2.38534951 1 P 0 ;0,1=557,2=0.000000
L 5.26493327 2.38534951 5.26416673 2.38948287 1 P 0 ;0,1=557,2=0.000000
L 5.26416673 2.38948287 5.2622498 2.39206663 1 P 0 ;0,1=557,2=0.000000
L 5.2622498 2.39206663 5.25956634 2.39413287 1 P 0 ;0,1=557,2=0.000000
L 5.25956634 2.39413287 5.25688356 2.39464941 1 P 0 ;0,1=557,2=0.000000
L 5.25688356 2.39464941 5.2542001 2.39413287 1 P 0 ;0,1=557,2=0.000000
L 5.2542001 2.39413287 5.2507501 2.39206663 1 P 0 ;0,1=557,2=0.000000
L 5.2507501 2.39206663 5.2518999 2.4055 1 P 0 ;0,1=557,2=0.000000
L 5.2518999 2.4055 5.2622498 2.4055 1 P 0 ;0,1=557,2=0.000000
L 5.797 2.058 5.797 2.182 1 P 0 
L 5.797 2.182 5.723 2.182 1 P 0 
L 5.723 2.182 5.723 2.058 1 P 0 
L 5.723 2.058 5.797 2.058 1 P 0 
L 5.85208376 2.03193327 5.85053317 2.02963307 1 P 0 ;0,1=558,2=270.000000
L 5.85053317 2.02963307 5.8495 2.0269503 1 P 0 ;0,1=558,2=270.000000
L 5.8495 2.0269503 5.8495 2.02388356 1 P 0 ;0,1=558,2=270.000000
L 5.8495 2.02388356 5.85105069 2.02043287 1 P 0 ;0,1=558,2=270.000000
L 5.85105069 2.02043287 5.85363346 2.0177501 1 P 0 ;0,1=558,2=270.000000
L 5.85363346 2.0177501 5.85673376 2.01583317 1 P 0 ;0,1=558,2=270.000000
L 5.85673376 2.01583317 5.8619002 2.01429951 1 P 0 ;0,1=558,2=270.000000
L 5.8619002 2.01429951 5.8665502 2.01391624 1 P 0 ;0,1=558,2=270.000000
L 5.8665502 2.01391624 5.8712001 2.01468337 1 P 0 ;0,1=558,2=270.000000
L 5.8712001 2.01468337 5.87430039 2.01583317 1 P 0 ;0,1=558,2=270.000000
L 5.87430039 2.01583317 5.87740069 2.01813337 1 P 0 ;0,1=558,2=270.000000
L 5.87740069 2.01813337 5.87946693 2.02081683 1 P 0 ;0,1=558,2=270.000000
L 5.87946693 2.02081683 5.8805 2.02349961 1 P 0 ;0,1=558,2=270.000000
L 5.8805 2.02349961 5.8805 2.02618307 1 P 0 ;0,1=558,2=270.000000
L 5.8805 2.02618307 5.87946693 2.02886654 1 P 0 ;0,1=558,2=270.000000
L 5.87946693 2.02886654 5.87791722 2.03116673 1 P 0 ;0,1=558,2=270.000000
L 5.87791722 2.03116673 5.87585108 2.03308366 1 P 0 ;0,1=558,2=270.000000
L 5.85466654 2.04721644 5.85156722 2.04951663 1 P 0 ;0,1=558,2=270.000000
L 5.85156722 2.04951663 5.85001663 2.0522001 1 P 0 ;0,1=558,2=270.000000
L 5.85001663 2.0522001 5.8495 2.05526683 1 P 0 ;0,1=558,2=270.000000
L 5.8495 2.05526683 5.85053317 2.0591 1 P 0 ;0,1=558,2=270.000000
L 5.85053317 2.0591 5.85311693 2.06178346 1 P 0 ;0,1=558,2=270.000000
L 5.85311693 2.06178346 5.85621624 2.06255 1 P 0 ;0,1=558,2=270.000000
L 5.85621624 2.06255 5.85931742 2.06216673 1 P 0 ;0,1=558,2=270.000000
L 5.85931742 2.06216673 5.8619002 2.06063307 1 P 0 ;0,1=558,2=270.000000
L 5.8619002 2.06063307 5.86706673 2.05296663 1 P 0 ;0,1=558,2=270.000000
L 5.86706673 2.05296663 5.87068356 2.04951663 1 P 0 ;0,1=558,2=270.000000
L 5.87068356 2.04951663 5.87585108 2.04721644 1 P 0 ;0,1=558,2=270.000000
L 5.87585108 2.04721644 5.8805 2.0464499 1 P 0 ;0,1=558,2=270.000000
L 5.8805 2.0464499 5.8805 2.06255 1 P 0 ;0,1=558,2=270.000000
L 5.87585108 2.07706663 5.87843386 2.07936614 1 P 0 ;0,1=558,2=270.000000
L 5.87843386 2.07936614 5.87998346 2.08204961 1 P 0 ;0,1=558,2=270.000000
L 5.87998346 2.08204961 5.8805 2.08549961 1 P 0 ;0,1=558,2=270.000000
L 5.8805 2.08549961 5.87946693 2.0889503 1 P 0 ;0,1=558,2=270.000000
L 5.87946693 2.0889503 5.87740069 2.09163307 1 P 0 ;0,1=558,2=270.000000
L 5.87740069 2.09163307 5.87378386 2.09355 1 P 0 ;0,1=558,2=270.000000
L 5.87378386 2.09355 5.86965049 2.09393327 1 P 0 ;0,1=558,2=270.000000
L 5.86965049 2.09393327 5.86551713 2.09316673 1 P 0 ;0,1=558,2=270.000000
L 5.86551713 2.09316673 5.86293337 2.0912498 1 P 0 ;0,1=558,2=270.000000
L 5.86293337 2.0912498 5.86086713 2.08856634 1 P 0 ;0,1=558,2=270.000000
L 5.86086713 2.08856634 5.86035059 2.08588356 1 P 0 ;0,1=558,2=270.000000
L 5.86035059 2.08588356 5.86086713 2.0832001 1 P 0 ;0,1=558,2=270.000000
L 5.86086713 2.0832001 5.86293337 2.0797501 1 P 0 ;0,1=558,2=270.000000
L 5.86293337 2.0797501 5.8495 2.0808999 1 P 0 ;0,1=558,2=270.000000
L 5.8495 2.0808999 5.8495 2.0912498 1 P 0 ;0,1=558,2=270.000000
L 5.8805 2.11573307 5.87378386 2.11649961 1 P 0 ;0,1=558,2=270.000000
L 5.87378386 2.11649961 5.86810079 2.1176501 1 P 0 ;0,1=558,2=270.000000
L 5.86810079 2.1176501 5.86293337 2.11918307 1 P 0 ;0,1=558,2=270.000000
L 5.86293337 2.11918307 5.8572503 2.1211 1 P 0 ;0,1=558,2=270.000000
L 5.8572503 2.1211 5.8495 2.12416673 1 P 0 ;0,1=558,2=270.000000
L 5.8495 2.12416673 5.8495 2.10883317 1 P 0 ;0,1=558,2=270.000000
L 6.262 2.06573996 6.188 2.06573996 1 P 0 
L 6.188 2.06573996 6.188 1.94173996 1 P 0 
L 6.188 1.94173996 6.262 1.94173996 1 P 0 
L 6.262 1.94173996 6.262 2.06573996 1 P 0 
L 6.11208376 2.01243327 6.11053317 2.01013307 1 P 0 ;0,1=559,2=270.000000
L 6.11053317 2.01013307 6.1095 2.0074503 1 P 0 ;0,1=559,2=270.000000
L 6.1095 2.0074503 6.1095 2.00438356 1 P 0 ;0,1=559,2=270.000000
L 6.1095 2.00438356 6.11105069 2.00093287 1 P 0 ;0,1=559,2=270.000000
L 6.11105069 2.00093287 6.11363346 1.9982501 1 P 0 ;0,1=559,2=270.000000
L 6.11363346 1.9982501 6.11673376 1.99633317 1 P 0 ;0,1=559,2=270.000000
L 6.11673376 1.99633317 6.1219002 1.99479951 1 P 0 ;0,1=559,2=270.000000
L 6.1219002 1.99479951 6.1265502 1.99441624 1 P 0 ;0,1=559,2=270.000000
L 6.1265502 1.99441624 6.1312001 1.99518337 1 P 0 ;0,1=559,2=270.000000
L 6.1312001 1.99518337 6.13430039 1.99633317 1 P 0 ;0,1=559,2=270.000000
L 6.13430039 1.99633317 6.13740069 1.99863337 1 P 0 ;0,1=559,2=270.000000
L 6.13740069 1.99863337 6.13946693 2.00131683 1 P 0 ;0,1=559,2=270.000000
L 6.13946693 2.00131683 6.1405 2.00399961 1 P 0 ;0,1=559,2=270.000000
L 6.1405 2.00399961 6.1405 2.00668307 1 P 0 ;0,1=559,2=270.000000
L 6.1405 2.00668307 6.13946693 2.00936654 1 P 0 ;0,1=559,2=270.000000
L 6.13946693 2.00936654 6.13791722 2.01166673 1 P 0 ;0,1=559,2=270.000000
L 6.13791722 2.01166673 6.13585108 2.01358366 1 P 0 ;0,1=559,2=270.000000
L 6.12758425 2.02771644 6.12396644 2.0303999 1 P 0 ;0,1=559,2=270.000000
L 6.12396644 2.0303999 6.1219002 2.0327001 1 P 0 ;0,1=559,2=270.000000
L 6.1219002 2.0327001 6.12086713 2.03576683 1 P 0 ;0,1=559,2=270.000000
L 6.12086713 2.03576683 6.1219002 2.0384503 1 P 0 ;0,1=559,2=270.000000
L 6.1219002 2.0384503 6.12396644 2.04036654 1 P 0 ;0,1=559,2=270.000000
L 6.12396644 2.04036654 6.12706673 2.0419002 1 P 0 ;0,1=559,2=270.000000
L 6.12706673 2.0419002 6.13068356 2.04228346 1 P 0 ;0,1=559,2=270.000000
L 6.13068356 2.04228346 6.13378386 2.0419002 1 P 0 ;0,1=559,2=270.000000
L 6.13378386 2.0419002 6.13688415 2.04036654 1 P 0 ;0,1=559,2=270.000000
L 6.13688415 2.04036654 6.13946693 2.03806634 1 P 0 ;0,1=559,2=270.000000
L 6.13946693 2.03806634 6.1405 2.03538356 1 P 0 ;0,1=559,2=270.000000
L 6.1405 2.03538356 6.13946693 2.03231683 1 P 0 ;0,1=559,2=270.000000
L 6.13946693 2.03231683 6.13636762 2.02963337 1 P 0 ;0,1=559,2=270.000000
L 6.13636762 2.02963337 6.13171673 2.0280997 1 P 0 ;0,1=559,2=270.000000
L 6.13171673 2.0280997 6.1265502 2.02771644 1 P 0 ;0,1=559,2=270.000000
L 6.1265502 2.02771644 6.11983406 2.02848287 1 P 0 ;0,1=559,2=270.000000
L 6.11983406 2.02848287 6.11621624 2.02963337 1 P 0 ;0,1=559,2=270.000000
L 6.11621624 2.02963337 6.1126003 2.03154961 1 P 0 ;0,1=559,2=270.000000
L 6.1126003 2.03154961 6.11001663 2.03423307 1 P 0 ;0,1=559,2=270.000000
L 6.11001663 2.03423307 6.1095 2.03691654 1 P 0 ;0,1=559,2=270.000000
L 6.1095 2.03691654 6.11053317 2.0396 1 P 0 ;0,1=559,2=270.000000
L 6.11053317 2.0396 6.11311693 2.04151703 1 P 0 ;0,1=559,2=270.000000
L 6.1405 2.06599961 6.1095 2.06599961 1 P 0 ;0,1=559,2=270.000000
L 6.1095 2.06599961 6.1156997 2.0613999 1 P 0 ;0,1=559,2=270.000000
L 6.1405 2.0613999 6.1405 2.07059931 1 P 0 ;0,1=559,2=270.000000
L 4.033 1.005 4.077 1.005 1 P 0 
L 4.033 1.095 4.033 1.005 1 P 0 
L 4.077 1.095 4.033 1.095 1 P 0 
L 4.077 1.005 4.077 1.095 1 P 0 
L 3.95208376 1.03193327 3.95053317 1.02963307 1 P 0 ;0,1=560,2=270.000000
L 3.95053317 1.02963307 3.9495 1.0269503 1 P 0 ;0,1=560,2=270.000000
L 3.9495 1.0269503 3.9495 1.02388356 1 P 0 ;0,1=560,2=270.000000
L 3.9495 1.02388356 3.95105069 1.02043287 1 P 0 ;0,1=560,2=270.000000
L 3.95105069 1.02043287 3.95363346 1.0177501 1 P 0 ;0,1=560,2=270.000000
L 3.95363346 1.0177501 3.95673376 1.01583317 1 P 0 ;0,1=560,2=270.000000
L 3.95673376 1.01583317 3.9619002 1.01429951 1 P 0 ;0,1=560,2=270.000000
L 3.9619002 1.01429951 3.9665502 1.01391624 1 P 0 ;0,1=560,2=270.000000
L 3.9665502 1.01391624 3.9712001 1.01468337 1 P 0 ;0,1=560,2=270.000000
L 3.9712001 1.01468337 3.97430039 1.01583317 1 P 0 ;0,1=560,2=270.000000
L 3.97430039 1.01583317 3.97740069 1.01813337 1 P 0 ;0,1=560,2=270.000000
L 3.97740069 1.01813337 3.97946693 1.02081683 1 P 0 ;0,1=560,2=270.000000
L 3.97946693 1.02081683 3.9805 1.02349961 1 P 0 ;0,1=560,2=270.000000
L 3.9805 1.02349961 3.9805 1.02618307 1 P 0 ;0,1=560,2=270.000000
L 3.9805 1.02618307 3.97946693 1.02886654 1 P 0 ;0,1=560,2=270.000000
L 3.97946693 1.02886654 3.97791722 1.03116673 1 P 0 ;0,1=560,2=270.000000
L 3.97791722 1.03116673 3.97585108 1.03308366 1 P 0 ;0,1=560,2=270.000000
L 3.95466654 1.04721644 3.95156722 1.04951663 1 P 0 ;0,1=560,2=270.000000
L 3.95156722 1.04951663 3.95001663 1.0522001 1 P 0 ;0,1=560,2=270.000000
L 3.95001663 1.0522001 3.9495 1.05526683 1 P 0 ;0,1=560,2=270.000000
L 3.9495 1.05526683 3.95053317 1.0591 1 P 0 ;0,1=560,2=270.000000
L 3.95053317 1.0591 3.95311693 1.06178346 1 P 0 ;0,1=560,2=270.000000
L 3.95311693 1.06178346 3.95621624 1.06255 1 P 0 ;0,1=560,2=270.000000
L 3.95621624 1.06255 3.95931742 1.06216673 1 P 0 ;0,1=560,2=270.000000
L 3.95931742 1.06216673 3.9619002 1.06063307 1 P 0 ;0,1=560,2=270.000000
L 3.9619002 1.06063307 3.96706673 1.05296663 1 P 0 ;0,1=560,2=270.000000
L 3.96706673 1.05296663 3.97068356 1.04951663 1 P 0 ;0,1=560,2=270.000000
L 3.97068356 1.04951663 3.97585108 1.04721644 1 P 0 ;0,1=560,2=270.000000
L 3.97585108 1.04721644 3.9805 1.0464499 1 P 0 ;0,1=560,2=270.000000
L 3.9805 1.0464499 3.9805 1.06255 1 P 0 ;0,1=560,2=270.000000
L 3.97585108 1.07706663 3.97843386 1.07936614 1 P 0 ;0,1=560,2=270.000000
L 3.97843386 1.07936614 3.97998346 1.08204961 1 P 0 ;0,1=560,2=270.000000
L 3.97998346 1.08204961 3.9805 1.08549961 1 P 0 ;0,1=560,2=270.000000
L 3.9805 1.08549961 3.97946693 1.0889503 1 P 0 ;0,1=560,2=270.000000
L 3.97946693 1.0889503 3.97740069 1.09163307 1 P 0 ;0,1=560,2=270.000000
L 3.97740069 1.09163307 3.97378386 1.09355 1 P 0 ;0,1=560,2=270.000000
L 3.97378386 1.09355 3.96965049 1.09393327 1 P 0 ;0,1=560,2=270.000000
L 3.96965049 1.09393327 3.96551713 1.09316673 1 P 0 ;0,1=560,2=270.000000
L 3.96551713 1.09316673 3.96293337 1.0912498 1 P 0 ;0,1=560,2=270.000000
L 3.96293337 1.0912498 3.96086713 1.08856634 1 P 0 ;0,1=560,2=270.000000
L 3.96086713 1.08856634 3.96035059 1.08588356 1 P 0 ;0,1=560,2=270.000000
L 3.96035059 1.08588356 3.96086713 1.0832001 1 P 0 ;0,1=560,2=270.000000
L 3.96086713 1.0832001 3.96293337 1.0797501 1 P 0 ;0,1=560,2=270.000000
L 3.96293337 1.0797501 3.9495 1.0808999 1 P 0 ;0,1=560,2=270.000000
L 3.9495 1.0808999 3.9495 1.0912498 1 P 0 ;0,1=560,2=270.000000
L 3.97430039 1.10806663 3.97791722 1.11036614 1 P 0 ;0,1=560,2=270.000000
L 3.97791722 1.11036614 3.97998346 1.11343287 1 P 0 ;0,1=560,2=270.000000
L 3.97998346 1.11343287 3.9805 1.11688356 1 P 0 ;0,1=560,2=270.000000
L 3.9805 1.11688356 3.97998346 1.1199503 1 P 0 ;0,1=560,2=270.000000
L 3.97998346 1.1199503 3.97740069 1.12301703 1 P 0 ;0,1=560,2=270.000000
L 3.97740069 1.12301703 3.97430039 1.12493327 1 P 0 ;0,1=560,2=270.000000
L 3.97430039 1.12493327 3.9712001 1.12531654 1 P 0 ;0,1=560,2=270.000000
L 3.9712001 1.12531654 3.96758425 1.12455 1 P 0 ;0,1=560,2=270.000000
L 3.96758425 1.12455 3.96500049 1.12186654 1 P 0 ;0,1=560,2=270.000000
L 3.96500049 1.12186654 3.96396644 1.11918307 1 P 0 ;0,1=560,2=270.000000
L 3.96396644 1.11918307 3.96396644 1.11573307 1 P 0 ;0,1=560,2=270.000000
L 3.96396644 1.11918307 3.96241683 1.12148327 1 P 0 ;0,1=560,2=270.000000
L 3.96241683 1.12148327 3.95983406 1.1234002 1 P 0 ;0,1=560,2=270.000000
L 3.95983406 1.1234002 3.95673376 1.12416673 1 P 0 ;0,1=560,2=270.000000
L 3.95673376 1.12416673 3.95363346 1.1234002 1 P 0 ;0,1=560,2=270.000000
L 3.95363346 1.1234002 3.95105069 1.12148327 1 P 0 ;0,1=560,2=270.000000
L 3.95105069 1.12148327 3.9495 1.11803327 1 P 0 ;0,1=560,2=270.000000
L 3.9495 1.11803327 3.95001663 1.11458337 1 P 0 ;0,1=560,2=270.000000
L 3.95001663 1.11458337 3.95208376 1.11113337 1 P 0 ;0,1=560,2=270.000000
L 3.988 1.005 4.032 1.005 1 P 0 
L 3.988 1.095 3.988 1.005 1 P 0 
L 4.032 1.095 3.988 1.095 1 P 0 
L 4.032 1.005 4.032 1.095 1 P 0 
L 3.91208376 1.03193327 3.91053317 1.02963307 1 P 0 ;0,1=561,2=270.000000
L 3.91053317 1.02963307 3.9095 1.0269503 1 P 0 ;0,1=561,2=270.000000
L 3.9095 1.0269503 3.9095 1.02388356 1 P 0 ;0,1=561,2=270.000000
L 3.9095 1.02388356 3.91105069 1.02043287 1 P 0 ;0,1=561,2=270.000000
L 3.91105069 1.02043287 3.91363346 1.0177501 1 P 0 ;0,1=561,2=270.000000
L 3.91363346 1.0177501 3.91673376 1.01583317 1 P 0 ;0,1=561,2=270.000000
L 3.91673376 1.01583317 3.9219002 1.01429951 1 P 0 ;0,1=561,2=270.000000
L 3.9219002 1.01429951 3.9265502 1.01391624 1 P 0 ;0,1=561,2=270.000000
L 3.9265502 1.01391624 3.9312001 1.01468337 1 P 0 ;0,1=561,2=270.000000
L 3.9312001 1.01468337 3.93430039 1.01583317 1 P 0 ;0,1=561,2=270.000000
L 3.93430039 1.01583317 3.93740069 1.01813337 1 P 0 ;0,1=561,2=270.000000
L 3.93740069 1.01813337 3.93946693 1.02081683 1 P 0 ;0,1=561,2=270.000000
L 3.93946693 1.02081683 3.9405 1.02349961 1 P 0 ;0,1=561,2=270.000000
L 3.9405 1.02349961 3.9405 1.02618307 1 P 0 ;0,1=561,2=270.000000
L 3.9405 1.02618307 3.93946693 1.02886654 1 P 0 ;0,1=561,2=270.000000
L 3.93946693 1.02886654 3.93791722 1.03116673 1 P 0 ;0,1=561,2=270.000000
L 3.93791722 1.03116673 3.93585108 1.03308366 1 P 0 ;0,1=561,2=270.000000
L 3.91466654 1.04721644 3.91156722 1.04951663 1 P 0 ;0,1=561,2=270.000000
L 3.91156722 1.04951663 3.91001663 1.0522001 1 P 0 ;0,1=561,2=270.000000
L 3.91001663 1.0522001 3.9095 1.05526683 1 P 0 ;0,1=561,2=270.000000
L 3.9095 1.05526683 3.91053317 1.0591 1 P 0 ;0,1=561,2=270.000000
L 3.91053317 1.0591 3.91311693 1.06178346 1 P 0 ;0,1=561,2=270.000000
L 3.91311693 1.06178346 3.91621624 1.06255 1 P 0 ;0,1=561,2=270.000000
L 3.91621624 1.06255 3.91931742 1.06216673 1 P 0 ;0,1=561,2=270.000000
L 3.91931742 1.06216673 3.9219002 1.06063307 1 P 0 ;0,1=561,2=270.000000
L 3.9219002 1.06063307 3.92706673 1.05296663 1 P 0 ;0,1=561,2=270.000000
L 3.92706673 1.05296663 3.93068356 1.04951663 1 P 0 ;0,1=561,2=270.000000
L 3.93068356 1.04951663 3.93585108 1.04721644 1 P 0 ;0,1=561,2=270.000000
L 3.93585108 1.04721644 3.9405 1.0464499 1 P 0 ;0,1=561,2=270.000000
L 3.9405 1.0464499 3.9405 1.06255 1 P 0 ;0,1=561,2=270.000000
L 3.93585108 1.07706663 3.93843386 1.07936614 1 P 0 ;0,1=561,2=270.000000
L 3.93843386 1.07936614 3.93998346 1.08204961 1 P 0 ;0,1=561,2=270.000000
L 3.93998346 1.08204961 3.9405 1.08549961 1 P 0 ;0,1=561,2=270.000000
L 3.9405 1.08549961 3.93946693 1.0889503 1 P 0 ;0,1=561,2=270.000000
L 3.93946693 1.0889503 3.93740069 1.09163307 1 P 0 ;0,1=561,2=270.000000
L 3.93740069 1.09163307 3.93378386 1.09355 1 P 0 ;0,1=561,2=270.000000
L 3.93378386 1.09355 3.92965049 1.09393327 1 P 0 ;0,1=561,2=270.000000
L 3.92965049 1.09393327 3.92551713 1.09316673 1 P 0 ;0,1=561,2=270.000000
L 3.92551713 1.09316673 3.92293337 1.0912498 1 P 0 ;0,1=561,2=270.000000
L 3.92293337 1.0912498 3.92086713 1.08856634 1 P 0 ;0,1=561,2=270.000000
L 3.92086713 1.08856634 3.92035059 1.08588356 1 P 0 ;0,1=561,2=270.000000
L 3.92035059 1.08588356 3.92086713 1.0832001 1 P 0 ;0,1=561,2=270.000000
L 3.92086713 1.0832001 3.92293337 1.0797501 1 P 0 ;0,1=561,2=270.000000
L 3.92293337 1.0797501 3.9095 1.0808999 1 P 0 ;0,1=561,2=270.000000
L 3.9095 1.0808999 3.9095 1.0912498 1 P 0 ;0,1=561,2=270.000000
L 3.9405 1.1211 3.9095 1.1211 1 P 0 ;0,1=561,2=270.000000
L 3.9095 1.1211 3.93171673 1.10691624 1 P 0 ;0,1=561,2=270.000000
L 3.93171673 1.10691624 3.93171673 1.12608366 1 P 0 ;0,1=561,2=270.000000
L 3.745 0.948 3.835 0.948 1 P 0 
L 3.745 0.992 3.745 0.948 1 P 0 
L 3.835 0.992 3.745 0.992 1 P 0 
L 3.835 0.948 3.835 0.992 1 P 0 
L 3.27693327 0.97291624 3.27463307 0.97446683 1 P 0 ;0,1=562,2=0.000000
L 3.27463307 0.97446683 3.2719503 0.9755 1 P 0 ;0,1=562,2=0.000000
L 3.2719503 0.9755 3.26888356 0.9755 1 P 0 ;0,1=562,2=0.000000
L 3.26888356 0.9755 3.26543287 0.97394931 1 P 0 ;0,1=562,2=0.000000
L 3.26543287 0.97394931 3.2627501 0.97136654 1 P 0 ;0,1=562,2=0.000000
L 3.2627501 0.97136654 3.26083317 0.96826624 1 P 0 ;0,1=562,2=0.000000
L 3.26083317 0.96826624 3.25929951 0.9630998 1 P 0 ;0,1=562,2=0.000000
L 3.25929951 0.9630998 3.25891624 0.9584498 1 P 0 ;0,1=562,2=0.000000
L 3.25891624 0.9584498 3.25968337 0.9537999 1 P 0 ;0,1=562,2=0.000000
L 3.25968337 0.9537999 3.26083317 0.95069961 1 P 0 ;0,1=562,2=0.000000
L 3.26083317 0.95069961 3.26313337 0.94759931 1 P 0 ;0,1=562,2=0.000000
L 3.26313337 0.94759931 3.26581683 0.94553307 1 P 0 ;0,1=562,2=0.000000
L 3.26581683 0.94553307 3.26849961 0.9445 1 P 0 ;0,1=562,2=0.000000
L 3.26849961 0.9445 3.27118307 0.9445 1 P 0 ;0,1=562,2=0.000000
L 3.27118307 0.9445 3.27386654 0.94553307 1 P 0 ;0,1=562,2=0.000000
L 3.27386654 0.94553307 3.27616673 0.94708278 1 P 0 ;0,1=562,2=0.000000
L 3.27616673 0.94708278 3.27808366 0.94914892 1 P 0 ;0,1=562,2=0.000000
L 3.29221644 0.97033346 3.29451663 0.97343278 1 P 0 ;0,1=562,2=0.000000
L 3.29451663 0.97343278 3.2972001 0.97498337 1 P 0 ;0,1=562,2=0.000000
L 3.2972001 0.97498337 3.30026683 0.9755 1 P 0 ;0,1=562,2=0.000000
L 3.30026683 0.9755 3.3041 0.97446683 1 P 0 ;0,1=562,2=0.000000
L 3.3041 0.97446683 3.30678346 0.97188307 1 P 0 ;0,1=562,2=0.000000
L 3.30678346 0.97188307 3.30755 0.96878376 1 P 0 ;0,1=562,2=0.000000
L 3.30755 0.96878376 3.30716673 0.96568258 1 P 0 ;0,1=562,2=0.000000
L 3.30716673 0.96568258 3.30563307 0.9630998 1 P 0 ;0,1=562,2=0.000000
L 3.30563307 0.9630998 3.29796663 0.95793327 1 P 0 ;0,1=562,2=0.000000
L 3.29796663 0.95793327 3.29451663 0.95431644 1 P 0 ;0,1=562,2=0.000000
L 3.29451663 0.95431644 3.29221644 0.94914892 1 P 0 ;0,1=562,2=0.000000
L 3.29221644 0.94914892 3.2914499 0.9445 1 P 0 ;0,1=562,2=0.000000
L 3.2914499 0.9445 3.30755 0.9445 1 P 0 ;0,1=562,2=0.000000
L 3.3351 0.9445 3.3351 0.9755 1 P 0 ;0,1=562,2=0.000000
L 3.3351 0.9755 3.32091624 0.95328327 1 P 0 ;0,1=562,2=0.000000
L 3.32091624 0.95328327 3.34008366 0.95328327 1 P 0 ;0,1=562,2=0.000000
L 3.36073307 0.9445 3.36149961 0.95121614 1 P 0 ;0,1=562,2=0.000000
L 3.36149961 0.95121614 3.3626501 0.95689921 1 P 0 ;0,1=562,2=0.000000
L 3.3626501 0.95689921 3.36418307 0.96206663 1 P 0 ;0,1=562,2=0.000000
L 3.36418307 0.96206663 3.3661 0.9677497 1 P 0 ;0,1=562,2=0.000000
L 3.3661 0.9677497 3.36916673 0.9755 1 P 0 ;0,1=562,2=0.000000
L 3.36916673 0.9755 3.35383317 0.9755 1 P 0 ;0,1=562,2=0.000000
L 3.553 1.555 3.597 1.555 1 P 0 
L 3.553 1.645 3.553 1.555 1 P 0 
L 3.597 1.555 3.597 1.645 1 P 0 
L 3.597 1.645 3.553 1.645 1 P 0 
L 3.53708376 1.44193327 3.53553317 1.43963307 1 P 0 ;0,1=563,2=270.000000
L 3.53553317 1.43963307 3.5345 1.4369503 1 P 0 ;0,1=563,2=270.000000
L 3.5345 1.4369503 3.5345 1.43388356 1 P 0 ;0,1=563,2=270.000000
L 3.5345 1.43388356 3.53605069 1.43043287 1 P 0 ;0,1=563,2=270.000000
L 3.53605069 1.43043287 3.53863346 1.4277501 1 P 0 ;0,1=563,2=270.000000
L 3.53863346 1.4277501 3.54173376 1.42583317 1 P 0 ;0,1=563,2=270.000000
L 3.54173376 1.42583317 3.5469002 1.42429951 1 P 0 ;0,1=563,2=270.000000
L 3.5469002 1.42429951 3.5515502 1.42391624 1 P 0 ;0,1=563,2=270.000000
L 3.5515502 1.42391624 3.5562001 1.42468337 1 P 0 ;0,1=563,2=270.000000
L 3.5562001 1.42468337 3.55930039 1.42583317 1 P 0 ;0,1=563,2=270.000000
L 3.55930039 1.42583317 3.56240069 1.42813337 1 P 0 ;0,1=563,2=270.000000
L 3.56240069 1.42813337 3.56446693 1.43081683 1 P 0 ;0,1=563,2=270.000000
L 3.56446693 1.43081683 3.5655 1.43349961 1 P 0 ;0,1=563,2=270.000000
L 3.5655 1.43349961 3.5655 1.43618307 1 P 0 ;0,1=563,2=270.000000
L 3.5655 1.43618307 3.56446693 1.43886654 1 P 0 ;0,1=563,2=270.000000
L 3.56446693 1.43886654 3.56291722 1.44116673 1 P 0 ;0,1=563,2=270.000000
L 3.56291722 1.44116673 3.56085108 1.44308366 1 P 0 ;0,1=563,2=270.000000
L 3.5655 1.46449961 3.5345 1.46449961 1 P 0 ;0,1=563,2=270.000000
L 3.5345 1.46449961 3.5406997 1.4598999 1 P 0 ;0,1=563,2=270.000000
L 3.5655 1.4598999 3.5655 1.46909931 1 P 0 ;0,1=563,2=270.000000
L 3.5655 1.5001 3.5345 1.5001 1 P 0 ;0,1=563,2=270.000000
L 3.5345 1.5001 3.55671673 1.48591624 1 P 0 ;0,1=563,2=270.000000
L 3.55671673 1.48591624 3.55671673 1.50508366 1 P 0 ;0,1=563,2=270.000000
L 3.5655 1.52649961 3.56498346 1.52918307 1 P 0 ;0,1=563,2=270.000000
L 3.56498346 1.52918307 3.56343386 1.5322498 1 P 0 ;0,1=563,2=270.000000
L 3.56343386 1.5322498 3.56085108 1.53416673 1 P 0 ;0,1=563,2=270.000000
L 3.56085108 1.53416673 3.55723327 1.53493327 1 P 0 ;0,1=563,2=270.000000
L 3.55723327 1.53493327 3.55361732 1.53416673 1 P 0 ;0,1=563,2=270.000000
L 3.55361732 1.53416673 3.55051713 1.53186654 1 P 0 ;0,1=563,2=270.000000
L 3.55051713 1.53186654 3.54896644 1.52841654 1 P 0 ;0,1=563,2=270.000000
L 3.54896644 1.52841654 3.54896644 1.52458337 1 P 0 ;0,1=563,2=270.000000
L 3.54896644 1.52458337 3.54793337 1.52228317 1 P 0 ;0,1=563,2=270.000000
L 3.54793337 1.52228317 3.54535059 1.52036614 1 P 0 ;0,1=563,2=270.000000
L 3.54535059 1.52036614 3.54173376 1.5195997 1 P 0 ;0,1=563,2=270.000000
L 3.54173376 1.5195997 3.53811693 1.5207501 1 P 0 ;0,1=563,2=270.000000
L 3.53811693 1.5207501 3.53553317 1.52343287 1 P 0 ;0,1=563,2=270.000000
L 3.53553317 1.52343287 3.5345 1.52649961 1 P 0 ;0,1=563,2=270.000000
L 3.5345 1.52649961 3.53553317 1.52956634 1 P 0 ;0,1=563,2=270.000000
L 3.53553317 1.52956634 3.53811693 1.5322498 1 P 0 ;0,1=563,2=270.000000
L 3.53811693 1.5322498 3.54173376 1.5334002 1 P 0 ;0,1=563,2=270.000000
L 3.54173376 1.5334002 3.54535059 1.53263307 1 P 0 ;0,1=563,2=270.000000
L 3.54535059 1.53263307 3.54793337 1.53071673 1 P 0 ;0,1=563,2=270.000000
L 3.54793337 1.53071673 3.54896644 1.52841654 1 P 0 ;0,1=563,2=270.000000
L 3.54896644 1.52841654 3.54896644 1.52458337 1 P 0 ;0,1=563,2=270.000000
L 3.54896644 1.52458337 3.55051713 1.52113337 1 P 0 ;0,1=563,2=270.000000
L 3.55051713 1.52113337 3.55361732 1.51883317 1 P 0 ;0,1=563,2=270.000000
L 3.55361732 1.51883317 3.55723327 1.51806663 1 P 0 ;0,1=563,2=270.000000
L 3.55723327 1.51806663 3.56085108 1.51883317 1 P 0 ;0,1=563,2=270.000000
L 3.56085108 1.51883317 3.56343386 1.5207501 1 P 0 ;0,1=563,2=270.000000
L 3.56343386 1.5207501 3.56498346 1.52381683 1 P 0 ;0,1=563,2=270.000000
L 3.56498346 1.52381683 3.5655 1.52649961 1 P 0 ;0,1=563,2=270.000000
L 2.9312 0.6898 2.9312 0.6458 1 P 0 
L 3.0212 0.6898 2.9312 0.6898 1 P 0 
L 2.9312 0.6458 3.0212 0.6458 1 P 0 
L 3.0212 0.6458 3.0212 0.6898 1 P 0 
L 2.96743327 0.79291624 2.96513307 0.79446683 1 P 0 ;0,1=564,2=0.000000
L 2.96513307 0.79446683 2.9624503 0.7955 1 P 0 ;0,1=564,2=0.000000
L 2.9624503 0.7955 2.95938356 0.7955 1 P 0 ;0,1=564,2=0.000000
L 2.95938356 0.7955 2.95593287 0.79394931 1 P 0 ;0,1=564,2=0.000000
L 2.95593287 0.79394931 2.9532501 0.79136654 1 P 0 ;0,1=564,2=0.000000
L 2.9532501 0.79136654 2.95133317 0.78826624 1 P 0 ;0,1=564,2=0.000000
L 2.95133317 0.78826624 2.94979951 0.7830998 1 P 0 ;0,1=564,2=0.000000
L 2.94979951 0.7830998 2.94941624 0.7784498 1 P 0 ;0,1=564,2=0.000000
L 2.94941624 0.7784498 2.95018337 0.7737999 1 P 0 ;0,1=564,2=0.000000
L 2.95018337 0.7737999 2.95133317 0.77069961 1 P 0 ;0,1=564,2=0.000000
L 2.95133317 0.77069961 2.95363337 0.76759931 1 P 0 ;0,1=564,2=0.000000
L 2.95363337 0.76759931 2.95631683 0.76553307 1 P 0 ;0,1=564,2=0.000000
L 2.95631683 0.76553307 2.95899961 0.7645 1 P 0 ;0,1=564,2=0.000000
L 2.95899961 0.7645 2.96168307 0.7645 1 P 0 ;0,1=564,2=0.000000
L 2.96168307 0.7645 2.96436654 0.76553307 1 P 0 ;0,1=564,2=0.000000
L 2.96436654 0.76553307 2.96666673 0.76708278 1 P 0 ;0,1=564,2=0.000000
L 2.96666673 0.76708278 2.96858366 0.76914892 1 P 0 ;0,1=564,2=0.000000
L 2.98156663 0.77069961 2.98386614 0.76708278 1 P 0 ;0,1=564,2=0.000000
L 2.98386614 0.76708278 2.98693287 0.76501654 1 P 0 ;0,1=564,2=0.000000
L 2.98693287 0.76501654 2.99038356 0.7645 1 P 0 ;0,1=564,2=0.000000
L 2.99038356 0.7645 2.9934503 0.76501654 1 P 0 ;0,1=564,2=0.000000
L 2.9934503 0.76501654 2.99651703 0.76759931 1 P 0 ;0,1=564,2=0.000000
L 2.99651703 0.76759931 2.99843327 0.77069961 1 P 0 ;0,1=564,2=0.000000
L 2.99843327 0.77069961 2.99881654 0.7737999 1 P 0 ;0,1=564,2=0.000000
L 2.99881654 0.7737999 2.99805 0.77741575 1 P 0 ;0,1=564,2=0.000000
L 2.99805 0.77741575 2.99536654 0.77999951 1 P 0 ;0,1=564,2=0.000000
L 2.99536654 0.77999951 2.99268307 0.78103356 1 P 0 ;0,1=564,2=0.000000
L 2.99268307 0.78103356 2.98923307 0.78103356 1 P 0 ;0,1=564,2=0.000000
L 2.99268307 0.78103356 2.99498327 0.78258317 1 P 0 ;0,1=564,2=0.000000
L 2.99498327 0.78258317 2.9969002 0.78516594 1 P 0 ;0,1=564,2=0.000000
L 2.9969002 0.78516594 2.99766673 0.78826624 1 P 0 ;0,1=564,2=0.000000
L 2.99766673 0.78826624 2.9969002 0.79136654 1 P 0 ;0,1=564,2=0.000000
L 2.9969002 0.79136654 2.99498327 0.79394931 1 P 0 ;0,1=564,2=0.000000
L 2.99498327 0.79394931 2.99153327 0.7955 1 P 0 ;0,1=564,2=0.000000
L 2.99153327 0.7955 2.98808337 0.79498337 1 P 0 ;0,1=564,2=0.000000
L 2.98808337 0.79498337 2.98463337 0.79291624 1 P 0 ;0,1=564,2=0.000000
L 3.02023307 0.7645 3.02099961 0.77121614 1 P 0 ;0,1=564,2=0.000000
L 3.02099961 0.77121614 3.0221501 0.77689921 1 P 0 ;0,1=564,2=0.000000
L 3.0221501 0.77689921 3.02368307 0.78206663 1 P 0 ;0,1=564,2=0.000000
L 3.02368307 0.78206663 3.0256 0.7877497 1 P 0 ;0,1=564,2=0.000000
L 3.0256 0.7877497 3.02866673 0.7955 1 P 0 ;0,1=564,2=0.000000
L 3.02866673 0.7955 3.01333317 0.7955 1 P 0 ;0,1=564,2=0.000000
L 2.128 0.57 2.172 0.57 1 P 0 
L 2.128 0.66 2.128 0.57 1 P 0 
L 2.172 0.57 2.172 0.66 1 P 0 
L 2.172 0.66 2.128 0.66 1 P 0 
L 2.15708376 0.71693327 2.15553317 0.71463307 1 P 0 ;0,1=565,2=270.000000
L 2.15553317 0.71463307 2.1545 0.7119503 1 P 0 ;0,1=565,2=270.000000
L 2.1545 0.7119503 2.1545 0.70888356 1 P 0 ;0,1=565,2=270.000000
L 2.1545 0.70888356 2.15605069 0.70543287 1 P 0 ;0,1=565,2=270.000000
L 2.15605069 0.70543287 2.15863346 0.7027501 1 P 0 ;0,1=565,2=270.000000
L 2.15863346 0.7027501 2.16173376 0.70083317 1 P 0 ;0,1=565,2=270.000000
L 2.16173376 0.70083317 2.1669002 0.69929951 1 P 0 ;0,1=565,2=270.000000
L 2.1669002 0.69929951 2.1715502 0.69891624 1 P 0 ;0,1=565,2=270.000000
L 2.1715502 0.69891624 2.1762001 0.69968337 1 P 0 ;0,1=565,2=270.000000
L 2.1762001 0.69968337 2.17930039 0.70083317 1 P 0 ;0,1=565,2=270.000000
L 2.17930039 0.70083317 2.18240069 0.70313337 1 P 0 ;0,1=565,2=270.000000
L 2.18240069 0.70313337 2.18446693 0.70581683 1 P 0 ;0,1=565,2=270.000000
L 2.18446693 0.70581683 2.1855 0.70849961 1 P 0 ;0,1=565,2=270.000000
L 2.1855 0.70849961 2.1855 0.71118307 1 P 0 ;0,1=565,2=270.000000
L 2.1855 0.71118307 2.18446693 0.71386654 1 P 0 ;0,1=565,2=270.000000
L 2.18446693 0.71386654 2.18291722 0.71616673 1 P 0 ;0,1=565,2=270.000000
L 2.18291722 0.71616673 2.18085108 0.71808366 1 P 0 ;0,1=565,2=270.000000
L 2.15966654 0.73221644 2.15656722 0.73451663 1 P 0 ;0,1=565,2=270.000000
L 2.15656722 0.73451663 2.15501663 0.7372001 1 P 0 ;0,1=565,2=270.000000
L 2.15501663 0.7372001 2.1545 0.74026683 1 P 0 ;0,1=565,2=270.000000
L 2.1545 0.74026683 2.15553317 0.7441 1 P 0 ;0,1=565,2=270.000000
L 2.15553317 0.7441 2.15811693 0.74678346 1 P 0 ;0,1=565,2=270.000000
L 2.15811693 0.74678346 2.16121624 0.74755 1 P 0 ;0,1=565,2=270.000000
L 2.16121624 0.74755 2.16431742 0.74716673 1 P 0 ;0,1=565,2=270.000000
L 2.16431742 0.74716673 2.1669002 0.74563307 1 P 0 ;0,1=565,2=270.000000
L 2.1669002 0.74563307 2.17206673 0.73796663 1 P 0 ;0,1=565,2=270.000000
L 2.17206673 0.73796663 2.17568356 0.73451663 1 P 0 ;0,1=565,2=270.000000
L 2.17568356 0.73451663 2.18085108 0.73221644 1 P 0 ;0,1=565,2=270.000000
L 2.18085108 0.73221644 2.1855 0.7314499 1 P 0 ;0,1=565,2=270.000000
L 2.1855 0.7314499 2.1855 0.74755 1 P 0 ;0,1=565,2=270.000000
L 2.1855 0.77049961 2.18498346 0.77318307 1 P 0 ;0,1=565,2=270.000000
L 2.18498346 0.77318307 2.18343386 0.7762498 1 P 0 ;0,1=565,2=270.000000
L 2.18343386 0.7762498 2.18085108 0.77816673 1 P 0 ;0,1=565,2=270.000000
L 2.18085108 0.77816673 2.17723327 0.77893327 1 P 0 ;0,1=565,2=270.000000
L 2.17723327 0.77893327 2.17361732 0.77816673 1 P 0 ;0,1=565,2=270.000000
L 2.17361732 0.77816673 2.17051713 0.77586654 1 P 0 ;0,1=565,2=270.000000
L 2.17051713 0.77586654 2.16896644 0.77241654 1 P 0 ;0,1=565,2=270.000000
L 2.16896644 0.77241654 2.16896644 0.76858337 1 P 0 ;0,1=565,2=270.000000
L 2.16896644 0.76858337 2.16793337 0.76628317 1 P 0 ;0,1=565,2=270.000000
L 2.16793337 0.76628317 2.16535059 0.76436614 1 P 0 ;0,1=565,2=270.000000
L 2.16535059 0.76436614 2.16173376 0.7635997 1 P 0 ;0,1=565,2=270.000000
L 2.16173376 0.7635997 2.15811693 0.7647501 1 P 0 ;0,1=565,2=270.000000
L 2.15811693 0.7647501 2.15553317 0.76743287 1 P 0 ;0,1=565,2=270.000000
L 2.15553317 0.76743287 2.1545 0.77049961 1 P 0 ;0,1=565,2=270.000000
L 2.1545 0.77049961 2.15553317 0.77356634 1 P 0 ;0,1=565,2=270.000000
L 2.15553317 0.77356634 2.15811693 0.7762498 1 P 0 ;0,1=565,2=270.000000
L 2.15811693 0.7762498 2.16173376 0.7774002 1 P 0 ;0,1=565,2=270.000000
L 2.16173376 0.7774002 2.16535059 0.77663307 1 P 0 ;0,1=565,2=270.000000
L 2.16535059 0.77663307 2.16793337 0.77471673 1 P 0 ;0,1=565,2=270.000000
L 2.16793337 0.77471673 2.16896644 0.77241654 1 P 0 ;0,1=565,2=270.000000
L 2.16896644 0.77241654 2.16896644 0.76858337 1 P 0 ;0,1=565,2=270.000000
L 2.16896644 0.76858337 2.17051713 0.76513337 1 P 0 ;0,1=565,2=270.000000
L 2.17051713 0.76513337 2.17361732 0.76283317 1 P 0 ;0,1=565,2=270.000000
L 2.17361732 0.76283317 2.17723327 0.76206663 1 P 0 ;0,1=565,2=270.000000
L 2.17723327 0.76206663 2.18085108 0.76283317 1 P 0 ;0,1=565,2=270.000000
L 2.18085108 0.76283317 2.18343386 0.7647501 1 P 0 ;0,1=565,2=270.000000
L 2.18343386 0.7647501 2.18498346 0.76781683 1 P 0 ;0,1=565,2=270.000000
L 2.18498346 0.76781683 2.1855 0.77049961 1 P 0 ;0,1=565,2=270.000000
L 2.1855 0.80149961 2.18498346 0.80418307 1 P 0 ;0,1=565,2=270.000000
L 2.18498346 0.80418307 2.18343386 0.8072498 1 P 0 ;0,1=565,2=270.000000
L 2.18343386 0.8072498 2.18085108 0.80916673 1 P 0 ;0,1=565,2=270.000000
L 2.18085108 0.80916673 2.17723327 0.80993327 1 P 0 ;0,1=565,2=270.000000
L 2.17723327 0.80993327 2.17361732 0.80916673 1 P 0 ;0,1=565,2=270.000000
L 2.17361732 0.80916673 2.17051713 0.80686654 1 P 0 ;0,1=565,2=270.000000
L 2.17051713 0.80686654 2.16896644 0.80341654 1 P 0 ;0,1=565,2=270.000000
L 2.16896644 0.80341654 2.16896644 0.79958337 1 P 0 ;0,1=565,2=270.000000
L 2.16896644 0.79958337 2.16793337 0.79728317 1 P 0 ;0,1=565,2=270.000000
L 2.16793337 0.79728317 2.16535059 0.79536614 1 P 0 ;0,1=565,2=270.000000
L 2.16535059 0.79536614 2.16173376 0.7945997 1 P 0 ;0,1=565,2=270.000000
L 2.16173376 0.7945997 2.15811693 0.7957501 1 P 0 ;0,1=565,2=270.000000
L 2.15811693 0.7957501 2.15553317 0.79843287 1 P 0 ;0,1=565,2=270.000000
L 2.15553317 0.79843287 2.1545 0.80149961 1 P 0 ;0,1=565,2=270.000000
L 2.1545 0.80149961 2.15553317 0.80456634 1 P 0 ;0,1=565,2=270.000000
L 2.15553317 0.80456634 2.15811693 0.8072498 1 P 0 ;0,1=565,2=270.000000
L 2.15811693 0.8072498 2.16173376 0.8084002 1 P 0 ;0,1=565,2=270.000000
L 2.16173376 0.8084002 2.16535059 0.80763307 1 P 0 ;0,1=565,2=270.000000
L 2.16535059 0.80763307 2.16793337 0.80571673 1 P 0 ;0,1=565,2=270.000000
L 2.16793337 0.80571673 2.16896644 0.80341654 1 P 0 ;0,1=565,2=270.000000
L 2.16896644 0.80341654 2.16896644 0.79958337 1 P 0 ;0,1=565,2=270.000000
L 2.16896644 0.79958337 2.17051713 0.79613337 1 P 0 ;0,1=565,2=270.000000
L 2.17051713 0.79613337 2.17361732 0.79383317 1 P 0 ;0,1=565,2=270.000000
L 2.17361732 0.79383317 2.17723327 0.79306663 1 P 0 ;0,1=565,2=270.000000
L 2.17723327 0.79306663 2.18085108 0.79383317 1 P 0 ;0,1=565,2=270.000000
L 2.18085108 0.79383317 2.18343386 0.7957501 1 P 0 ;0,1=565,2=270.000000
L 2.18343386 0.7957501 2.18498346 0.79881683 1 P 0 ;0,1=565,2=270.000000
L 2.18498346 0.79881683 2.1855 0.80149961 1 P 0 ;0,1=565,2=270.000000
L 2.083 0.57 2.127 0.57 1 P 0 
L 2.083 0.66 2.083 0.57 1 P 0 
L 2.127 0.57 2.127 0.66 1 P 0 
L 2.127 0.66 2.083 0.66 1 P 0 
L 2.10708376 0.71693327 2.10553317 0.71463307 1 P 0 ;0,1=566,2=270.000000
L 2.10553317 0.71463307 2.1045 0.7119503 1 P 0 ;0,1=566,2=270.000000
L 2.1045 0.7119503 2.1045 0.70888356 1 P 0 ;0,1=566,2=270.000000
L 2.1045 0.70888356 2.10605069 0.70543287 1 P 0 ;0,1=566,2=270.000000
L 2.10605069 0.70543287 2.10863346 0.7027501 1 P 0 ;0,1=566,2=270.000000
L 2.10863346 0.7027501 2.11173376 0.70083317 1 P 0 ;0,1=566,2=270.000000
L 2.11173376 0.70083317 2.1169002 0.69929951 1 P 0 ;0,1=566,2=270.000000
L 2.1169002 0.69929951 2.1215502 0.69891624 1 P 0 ;0,1=566,2=270.000000
L 2.1215502 0.69891624 2.1262001 0.69968337 1 P 0 ;0,1=566,2=270.000000
L 2.1262001 0.69968337 2.12930039 0.70083317 1 P 0 ;0,1=566,2=270.000000
L 2.12930039 0.70083317 2.13240069 0.70313337 1 P 0 ;0,1=566,2=270.000000
L 2.13240069 0.70313337 2.13446693 0.70581683 1 P 0 ;0,1=566,2=270.000000
L 2.13446693 0.70581683 2.1355 0.70849961 1 P 0 ;0,1=566,2=270.000000
L 2.1355 0.70849961 2.1355 0.71118307 1 P 0 ;0,1=566,2=270.000000
L 2.1355 0.71118307 2.13446693 0.71386654 1 P 0 ;0,1=566,2=270.000000
L 2.13446693 0.71386654 2.13291722 0.71616673 1 P 0 ;0,1=566,2=270.000000
L 2.13291722 0.71616673 2.13085108 0.71808366 1 P 0 ;0,1=566,2=270.000000
L 2.10966654 0.73221644 2.10656722 0.73451663 1 P 0 ;0,1=566,2=270.000000
L 2.10656722 0.73451663 2.10501663 0.7372001 1 P 0 ;0,1=566,2=270.000000
L 2.10501663 0.7372001 2.1045 0.74026683 1 P 0 ;0,1=566,2=270.000000
L 2.1045 0.74026683 2.10553317 0.7441 1 P 0 ;0,1=566,2=270.000000
L 2.10553317 0.7441 2.10811693 0.74678346 1 P 0 ;0,1=566,2=270.000000
L 2.10811693 0.74678346 2.11121624 0.74755 1 P 0 ;0,1=566,2=270.000000
L 2.11121624 0.74755 2.11431742 0.74716673 1 P 0 ;0,1=566,2=270.000000
L 2.11431742 0.74716673 2.1169002 0.74563307 1 P 0 ;0,1=566,2=270.000000
L 2.1169002 0.74563307 2.12206673 0.73796663 1 P 0 ;0,1=566,2=270.000000
L 2.12206673 0.73796663 2.12568356 0.73451663 1 P 0 ;0,1=566,2=270.000000
L 2.12568356 0.73451663 2.13085108 0.73221644 1 P 0 ;0,1=566,2=270.000000
L 2.13085108 0.73221644 2.1355 0.7314499 1 P 0 ;0,1=566,2=270.000000
L 2.1355 0.7314499 2.1355 0.74755 1 P 0 ;0,1=566,2=270.000000
L 2.1355 0.77049961 2.13498346 0.77318307 1 P 0 ;0,1=566,2=270.000000
L 2.13498346 0.77318307 2.13343386 0.7762498 1 P 0 ;0,1=566,2=270.000000
L 2.13343386 0.7762498 2.13085108 0.77816673 1 P 0 ;0,1=566,2=270.000000
L 2.13085108 0.77816673 2.12723327 0.77893327 1 P 0 ;0,1=566,2=270.000000
L 2.12723327 0.77893327 2.12361732 0.77816673 1 P 0 ;0,1=566,2=270.000000
L 2.12361732 0.77816673 2.12051713 0.77586654 1 P 0 ;0,1=566,2=270.000000
L 2.12051713 0.77586654 2.11896644 0.77241654 1 P 0 ;0,1=566,2=270.000000
L 2.11896644 0.77241654 2.11896644 0.76858337 1 P 0 ;0,1=566,2=270.000000
L 2.11896644 0.76858337 2.11793337 0.76628317 1 P 0 ;0,1=566,2=270.000000
L 2.11793337 0.76628317 2.11535059 0.76436614 1 P 0 ;0,1=566,2=270.000000
L 2.11535059 0.76436614 2.11173376 0.7635997 1 P 0 ;0,1=566,2=270.000000
L 2.11173376 0.7635997 2.10811693 0.7647501 1 P 0 ;0,1=566,2=270.000000
L 2.10811693 0.7647501 2.10553317 0.76743287 1 P 0 ;0,1=566,2=270.000000
L 2.10553317 0.76743287 2.1045 0.77049961 1 P 0 ;0,1=566,2=270.000000
L 2.1045 0.77049961 2.10553317 0.77356634 1 P 0 ;0,1=566,2=270.000000
L 2.10553317 0.77356634 2.10811693 0.7762498 1 P 0 ;0,1=566,2=270.000000
L 2.10811693 0.7762498 2.11173376 0.7774002 1 P 0 ;0,1=566,2=270.000000
L 2.11173376 0.7774002 2.11535059 0.77663307 1 P 0 ;0,1=566,2=270.000000
L 2.11535059 0.77663307 2.11793337 0.77471673 1 P 0 ;0,1=566,2=270.000000
L 2.11793337 0.77471673 2.11896644 0.77241654 1 P 0 ;0,1=566,2=270.000000
L 2.11896644 0.77241654 2.11896644 0.76858337 1 P 0 ;0,1=566,2=270.000000
L 2.11896644 0.76858337 2.12051713 0.76513337 1 P 0 ;0,1=566,2=270.000000
L 2.12051713 0.76513337 2.12361732 0.76283317 1 P 0 ;0,1=566,2=270.000000
L 2.12361732 0.76283317 2.12723327 0.76206663 1 P 0 ;0,1=566,2=270.000000
L 2.12723327 0.76206663 2.13085108 0.76283317 1 P 0 ;0,1=566,2=270.000000
L 2.13085108 0.76283317 2.13343386 0.7647501 1 P 0 ;0,1=566,2=270.000000
L 2.13343386 0.7647501 2.13498346 0.76781683 1 P 0 ;0,1=566,2=270.000000
L 2.13498346 0.76781683 2.1355 0.77049961 1 P 0 ;0,1=566,2=270.000000
L 2.1355 0.80073307 2.12878386 0.80149961 1 P 0 ;0,1=566,2=270.000000
L 2.12878386 0.80149961 2.12310079 0.8026501 1 P 0 ;0,1=566,2=270.000000
L 2.12310079 0.8026501 2.11793337 0.80418307 1 P 0 ;0,1=566,2=270.000000
L 2.11793337 0.80418307 2.1122503 0.8061 1 P 0 ;0,1=566,2=270.000000
L 2.1122503 0.8061 2.1045 0.80916673 1 P 0 ;0,1=566,2=270.000000
L 2.1045 0.80916673 2.1045 0.79383317 1 P 0 ;0,1=566,2=270.000000
L 3.845 0.992 3.845 0.948 1 P 0 
L 3.935 0.992 3.845 0.992 1 P 0 
L 3.935 0.948 3.935 0.992 1 P 0 
L 3.845 0.948 3.935 0.948 1 P 0 
L 3.40193327 0.97791624 3.39963307 0.97946683 1 P 0 ;0,1=567,2=0.000000
L 3.39963307 0.97946683 3.3969503 0.9805 1 P 0 ;0,1=567,2=0.000000
L 3.3969503 0.9805 3.39388356 0.9805 1 P 0 ;0,1=567,2=0.000000
L 3.39388356 0.9805 3.39043287 0.97894931 1 P 0 ;0,1=567,2=0.000000
L 3.39043287 0.97894931 3.3877501 0.97636654 1 P 0 ;0,1=567,2=0.000000
L 3.3877501 0.97636654 3.38583317 0.97326624 1 P 0 ;0,1=567,2=0.000000
L 3.38583317 0.97326624 3.38429951 0.9680998 1 P 0 ;0,1=567,2=0.000000
L 3.38429951 0.9680998 3.38391624 0.9634498 1 P 0 ;0,1=567,2=0.000000
L 3.38391624 0.9634498 3.38468337 0.9587999 1 P 0 ;0,1=567,2=0.000000
L 3.38468337 0.9587999 3.38583317 0.95569961 1 P 0 ;0,1=567,2=0.000000
L 3.38583317 0.95569961 3.38813337 0.95259931 1 P 0 ;0,1=567,2=0.000000
L 3.38813337 0.95259931 3.39081683 0.95053307 1 P 0 ;0,1=567,2=0.000000
L 3.39081683 0.95053307 3.39349961 0.9495 1 P 0 ;0,1=567,2=0.000000
L 3.39349961 0.9495 3.39618307 0.9495 1 P 0 ;0,1=567,2=0.000000
L 3.39618307 0.9495 3.39886654 0.95053307 1 P 0 ;0,1=567,2=0.000000
L 3.39886654 0.95053307 3.40116673 0.95208278 1 P 0 ;0,1=567,2=0.000000
L 3.40116673 0.95208278 3.40308366 0.95414892 1 P 0 ;0,1=567,2=0.000000
L 3.41721644 0.97533346 3.41951663 0.97843278 1 P 0 ;0,1=567,2=0.000000
L 3.41951663 0.97843278 3.4222001 0.97998337 1 P 0 ;0,1=567,2=0.000000
L 3.4222001 0.97998337 3.42526683 0.9805 1 P 0 ;0,1=567,2=0.000000
L 3.42526683 0.9805 3.4291 0.97946683 1 P 0 ;0,1=567,2=0.000000
L 3.4291 0.97946683 3.43178346 0.97688307 1 P 0 ;0,1=567,2=0.000000
L 3.43178346 0.97688307 3.43255 0.97378376 1 P 0 ;0,1=567,2=0.000000
L 3.43255 0.97378376 3.43216673 0.97068258 1 P 0 ;0,1=567,2=0.000000
L 3.43216673 0.97068258 3.43063307 0.9680998 1 P 0 ;0,1=567,2=0.000000
L 3.43063307 0.9680998 3.42296663 0.96293327 1 P 0 ;0,1=567,2=0.000000
L 3.42296663 0.96293327 3.41951663 0.95931644 1 P 0 ;0,1=567,2=0.000000
L 3.41951663 0.95931644 3.41721644 0.95414892 1 P 0 ;0,1=567,2=0.000000
L 3.41721644 0.95414892 3.4164499 0.9495 1 P 0 ;0,1=567,2=0.000000
L 3.4164499 0.9495 3.43255 0.9495 1 P 0 ;0,1=567,2=0.000000
L 3.4601 0.9495 3.4601 0.9805 1 P 0 ;0,1=567,2=0.000000
L 3.4601 0.9805 3.44591624 0.95828327 1 P 0 ;0,1=567,2=0.000000
L 3.44591624 0.95828327 3.46508366 0.95828327 1 P 0 ;0,1=567,2=0.000000
L 3.47998287 0.95311585 3.48266634 0.95053307 1 P 0 ;0,1=567,2=0.000000
L 3.48266634 0.95053307 3.48573307 0.9495 1 P 0 ;0,1=567,2=0.000000
L 3.48573307 0.9495 3.4887998 0.95053307 1 P 0 ;0,1=567,2=0.000000
L 3.4887998 0.95053307 3.49148327 0.95363238 1 P 0 ;0,1=567,2=0.000000
L 3.49148327 0.95363238 3.4934002 0.95828327 1 P 0 ;0,1=567,2=0.000000
L 3.4934002 0.95828327 3.49416673 0.96293327 1 P 0 ;0,1=567,2=0.000000
L 3.49416673 0.96293327 3.49416673 0.96861634 1 P 0 ;0,1=567,2=0.000000
L 3.49416673 0.96861634 3.4934002 0.97326624 1 P 0 ;0,1=567,2=0.000000
L 3.4934002 0.97326624 3.49148327 0.9773997 1 P 0 ;0,1=567,2=0.000000
L 3.49148327 0.9773997 3.48918307 0.97946683 1 P 0 ;0,1=567,2=0.000000
L 3.48918307 0.97946683 3.48649961 0.9805 1 P 0 ;0,1=567,2=0.000000
L 3.48649961 0.9805 3.48343287 0.97946683 1 P 0 ;0,1=567,2=0.000000
L 3.48343287 0.97946683 3.48113337 0.9773997 1 P 0 ;0,1=567,2=0.000000
L 3.48113337 0.9773997 3.4795997 0.9743003 1 P 0 ;0,1=567,2=0.000000
L 3.4795997 0.9743003 3.47883317 0.97016594 1 P 0 ;0,1=567,2=0.000000
L 3.47883317 0.97016594 3.4795997 0.9665501 1 P 0 ;0,1=567,2=0.000000
L 3.4795997 0.9665501 3.48151663 0.96293327 1 P 0 ;0,1=567,2=0.000000
L 3.48151663 0.96293327 3.48381683 0.96086604 1 P 0 ;0,1=567,2=0.000000
L 3.48381683 0.96086604 3.48649961 0.96034951 1 P 0 ;0,1=567,2=0.000000
L 3.48649961 0.96034951 3.48956634 0.96138268 1 P 0 ;0,1=567,2=0.000000
L 3.48956634 0.96138268 3.49186654 0.96396634 1 P 0 ;0,1=567,2=0.000000
L 3.49186654 0.96396634 3.49416673 0.96861634 1 P 0 ;0,1=567,2=0.000000
L 3.683 2.45 3.683 2.36 1 P 0 
L 3.683 2.36 3.727 2.36 1 P 0 
L 3.727 2.36 3.727 2.45 1 P 0 
L 3.727 2.45 3.683 2.45 1 P 0 
L 3.68708376 2.25693327 3.68553317 2.25463307 1 P 0 ;0,1=568,2=270.000000
L 3.68553317 2.25463307 3.6845 2.2519503 1 P 0 ;0,1=568,2=270.000000
L 3.6845 2.2519503 3.6845 2.24888356 1 P 0 ;0,1=568,2=270.000000
L 3.6845 2.24888356 3.68605069 2.24543287 1 P 0 ;0,1=568,2=270.000000
L 3.68605069 2.24543287 3.68863346 2.2427501 1 P 0 ;0,1=568,2=270.000000
L 3.68863346 2.2427501 3.69173376 2.24083317 1 P 0 ;0,1=568,2=270.000000
L 3.69173376 2.24083317 3.6969002 2.23929951 1 P 0 ;0,1=568,2=270.000000
L 3.6969002 2.23929951 3.7015502 2.23891624 1 P 0 ;0,1=568,2=270.000000
L 3.7015502 2.23891624 3.7062001 2.23968337 1 P 0 ;0,1=568,2=270.000000
L 3.7062001 2.23968337 3.70930039 2.24083317 1 P 0 ;0,1=568,2=270.000000
L 3.70930039 2.24083317 3.71240069 2.24313337 1 P 0 ;0,1=568,2=270.000000
L 3.71240069 2.24313337 3.71446693 2.24581683 1 P 0 ;0,1=568,2=270.000000
L 3.71446693 2.24581683 3.7155 2.24849961 1 P 0 ;0,1=568,2=270.000000
L 3.7155 2.24849961 3.7155 2.25118307 1 P 0 ;0,1=568,2=270.000000
L 3.7155 2.25118307 3.71446693 2.25386654 1 P 0 ;0,1=568,2=270.000000
L 3.71446693 2.25386654 3.71291722 2.25616673 1 P 0 ;0,1=568,2=270.000000
L 3.71291722 2.25616673 3.71085108 2.25808366 1 P 0 ;0,1=568,2=270.000000
L 3.68966654 2.27221644 3.68656722 2.27451663 1 P 0 ;0,1=568,2=270.000000
L 3.68656722 2.27451663 3.68501663 2.2772001 1 P 0 ;0,1=568,2=270.000000
L 3.68501663 2.2772001 3.6845 2.28026683 1 P 0 ;0,1=568,2=270.000000
L 3.6845 2.28026683 3.68553317 2.2841 1 P 0 ;0,1=568,2=270.000000
L 3.68553317 2.2841 3.68811693 2.28678346 1 P 0 ;0,1=568,2=270.000000
L 3.68811693 2.28678346 3.69121624 2.28755 1 P 0 ;0,1=568,2=270.000000
L 3.69121624 2.28755 3.69431742 2.28716673 1 P 0 ;0,1=568,2=270.000000
L 3.69431742 2.28716673 3.6969002 2.28563307 1 P 0 ;0,1=568,2=270.000000
L 3.6969002 2.28563307 3.70206673 2.27796663 1 P 0 ;0,1=568,2=270.000000
L 3.70206673 2.27796663 3.70568356 2.27451663 1 P 0 ;0,1=568,2=270.000000
L 3.70568356 2.27451663 3.71085108 2.27221644 1 P 0 ;0,1=568,2=270.000000
L 3.71085108 2.27221644 3.7155 2.2714499 1 P 0 ;0,1=568,2=270.000000
L 3.7155 2.2714499 3.7155 2.28755 1 P 0 ;0,1=568,2=270.000000
L 3.71085108 2.30206663 3.71343386 2.30436614 1 P 0 ;0,1=568,2=270.000000
L 3.71343386 2.30436614 3.71498346 2.30704961 1 P 0 ;0,1=568,2=270.000000
L 3.71498346 2.30704961 3.7155 2.31049961 1 P 0 ;0,1=568,2=270.000000
L 3.7155 2.31049961 3.71446693 2.3139503 1 P 0 ;0,1=568,2=270.000000
L 3.71446693 2.3139503 3.71240069 2.31663307 1 P 0 ;0,1=568,2=270.000000
L 3.71240069 2.31663307 3.70878386 2.31855 1 P 0 ;0,1=568,2=270.000000
L 3.70878386 2.31855 3.70465049 2.31893327 1 P 0 ;0,1=568,2=270.000000
L 3.70465049 2.31893327 3.70051713 2.31816673 1 P 0 ;0,1=568,2=270.000000
L 3.70051713 2.31816673 3.69793337 2.3162498 1 P 0 ;0,1=568,2=270.000000
L 3.69793337 2.3162498 3.69586713 2.31356634 1 P 0 ;0,1=568,2=270.000000
L 3.69586713 2.31356634 3.69535059 2.31088356 1 P 0 ;0,1=568,2=270.000000
L 3.69535059 2.31088356 3.69586713 2.3082001 1 P 0 ;0,1=568,2=270.000000
L 3.69586713 2.3082001 3.69793337 2.3047501 1 P 0 ;0,1=568,2=270.000000
L 3.69793337 2.3047501 3.6845 2.3058999 1 P 0 ;0,1=568,2=270.000000
L 3.6845 2.3058999 3.6845 2.3162498 1 P 0 ;0,1=568,2=270.000000
L 3.6845 2.34149961 3.68553317 2.33843287 1 P 0 ;0,1=568,2=270.000000
L 3.68553317 2.33843287 3.68811693 2.33613337 1 P 0 ;0,1=568,2=270.000000
L 3.68811693 2.33613337 3.69121624 2.3345997 1 P 0 ;0,1=568,2=270.000000
L 3.69121624 2.3345997 3.69535059 2.3334499 1 P 0 ;0,1=568,2=270.000000
L 3.69535059 2.3334499 3.70000049 2.33306663 1 P 0 ;0,1=568,2=270.000000
L 3.70000049 2.33306663 3.70465049 2.3334499 1 P 0 ;0,1=568,2=270.000000
L 3.70465049 2.3334499 3.70878386 2.3345997 1 P 0 ;0,1=568,2=270.000000
L 3.70878386 2.3345997 3.71188415 2.33613337 1 P 0 ;0,1=568,2=270.000000
L 3.71188415 2.33613337 3.71446693 2.33843287 1 P 0 ;0,1=568,2=270.000000
L 3.71446693 2.33843287 3.7155 2.34149961 1 P 0 ;0,1=568,2=270.000000
L 3.7155 2.34149961 3.71446693 2.34456634 1 P 0 ;0,1=568,2=270.000000
L 3.71446693 2.34456634 3.71188415 2.34686654 1 P 0 ;0,1=568,2=270.000000
L 3.71188415 2.34686654 3.70878386 2.3484002 1 P 0 ;0,1=568,2=270.000000
L 3.70878386 2.3484002 3.70465049 2.34955 1 P 0 ;0,1=568,2=270.000000
L 3.70465049 2.34955 3.70000049 2.34993327 1 P 0 ;0,1=568,2=270.000000
L 3.70000049 2.34993327 3.69535059 2.34955 1 P 0 ;0,1=568,2=270.000000
L 3.69535059 2.34955 3.69121624 2.3484002 1 P 0 ;0,1=568,2=270.000000
L 3.69121624 2.3484002 3.68811693 2.34686654 1 P 0 ;0,1=568,2=270.000000
L 3.68811693 2.34686654 3.68553317 2.34456634 1 P 0 ;0,1=568,2=270.000000
L 3.68553317 2.34456634 3.6845 2.34149961 1 P 0 ;0,1=568,2=270.000000
L 1.532 3.23 1.488 3.23 1 P 0 
L 1.532 3.14 1.532 3.23 1 P 0 
L 1.488 3.23 1.488 3.14 1 P 0 
L 1.488 3.14 1.532 3.14 1 P 0 
L 1.49208376 3.28693327 1.49053317 3.28463307 1 P 0 ;0,1=569,2=270.000000
L 1.49053317 3.28463307 1.4895 3.2819503 1 P 0 ;0,1=569,2=270.000000
L 1.4895 3.2819503 1.4895 3.27888356 1 P 0 ;0,1=569,2=270.000000
L 1.4895 3.27888356 1.49105069 3.27543287 1 P 0 ;0,1=569,2=270.000000
L 1.49105069 3.27543287 1.49363346 3.2727501 1 P 0 ;0,1=569,2=270.000000
L 1.49363346 3.2727501 1.49673376 3.27083317 1 P 0 ;0,1=569,2=270.000000
L 1.49673376 3.27083317 1.5019002 3.26929951 1 P 0 ;0,1=569,2=270.000000
L 1.5019002 3.26929951 1.5065502 3.26891624 1 P 0 ;0,1=569,2=270.000000
L 1.5065502 3.26891624 1.5112001 3.26968337 1 P 0 ;0,1=569,2=270.000000
L 1.5112001 3.26968337 1.51430039 3.27083317 1 P 0 ;0,1=569,2=270.000000
L 1.51430039 3.27083317 1.51740069 3.27313337 1 P 0 ;0,1=569,2=270.000000
L 1.51740069 3.27313337 1.51946693 3.27581683 1 P 0 ;0,1=569,2=270.000000
L 1.51946693 3.27581683 1.5205 3.27849961 1 P 0 ;0,1=569,2=270.000000
L 1.5205 3.27849961 1.5205 3.28118307 1 P 0 ;0,1=569,2=270.000000
L 1.5205 3.28118307 1.51946693 3.28386654 1 P 0 ;0,1=569,2=270.000000
L 1.51946693 3.28386654 1.51791722 3.28616673 1 P 0 ;0,1=569,2=270.000000
L 1.51791722 3.28616673 1.51585108 3.28808366 1 P 0 ;0,1=569,2=270.000000
L 1.51430039 3.30106663 1.51791722 3.30336614 1 P 0 ;0,1=569,2=270.000000
L 1.51791722 3.30336614 1.51998346 3.30643287 1 P 0 ;0,1=569,2=270.000000
L 1.51998346 3.30643287 1.5205 3.30988356 1 P 0 ;0,1=569,2=270.000000
L 1.5205 3.30988356 1.51998346 3.3129503 1 P 0 ;0,1=569,2=270.000000
L 1.51998346 3.3129503 1.51740069 3.31601703 1 P 0 ;0,1=569,2=270.000000
L 1.51740069 3.31601703 1.51430039 3.31793327 1 P 0 ;0,1=569,2=270.000000
L 1.51430039 3.31793327 1.5112001 3.31831654 1 P 0 ;0,1=569,2=270.000000
L 1.5112001 3.31831654 1.50758425 3.31755 1 P 0 ;0,1=569,2=270.000000
L 1.50758425 3.31755 1.50500049 3.31486654 1 P 0 ;0,1=569,2=270.000000
L 1.50500049 3.31486654 1.50396644 3.31218307 1 P 0 ;0,1=569,2=270.000000
L 1.50396644 3.31218307 1.50396644 3.30873307 1 P 0 ;0,1=569,2=270.000000
L 1.50396644 3.31218307 1.50241683 3.31448327 1 P 0 ;0,1=569,2=270.000000
L 1.50241683 3.31448327 1.49983406 3.3164002 1 P 0 ;0,1=569,2=270.000000
L 1.49983406 3.3164002 1.49673376 3.31716673 1 P 0 ;0,1=569,2=270.000000
L 1.49673376 3.31716673 1.49363346 3.3164002 1 P 0 ;0,1=569,2=270.000000
L 1.49363346 3.3164002 1.49105069 3.31448327 1 P 0 ;0,1=569,2=270.000000
L 1.49105069 3.31448327 1.4895 3.31103327 1 P 0 ;0,1=569,2=270.000000
L 1.4895 3.31103327 1.49001663 3.30758337 1 P 0 ;0,1=569,2=270.000000
L 1.49001663 3.30758337 1.49208376 3.30413337 1 P 0 ;0,1=569,2=270.000000
L 1.4895 3.34049961 1.49053317 3.33743287 1 P 0 ;0,1=569,2=270.000000
L 1.49053317 3.33743287 1.49311693 3.33513337 1 P 0 ;0,1=569,2=270.000000
L 1.49311693 3.33513337 1.49621624 3.3335997 1 P 0 ;0,1=569,2=270.000000
L 1.49621624 3.3335997 1.50035059 3.3324499 1 P 0 ;0,1=569,2=270.000000
L 1.50035059 3.3324499 1.50500049 3.33206663 1 P 0 ;0,1=569,2=270.000000
L 1.50500049 3.33206663 1.50965049 3.3324499 1 P 0 ;0,1=569,2=270.000000
L 1.50965049 3.3324499 1.51378386 3.3335997 1 P 0 ;0,1=569,2=270.000000
L 1.51378386 3.3335997 1.51688415 3.33513337 1 P 0 ;0,1=569,2=270.000000
L 1.51688415 3.33513337 1.51946693 3.33743287 1 P 0 ;0,1=569,2=270.000000
L 1.51946693 3.33743287 1.5205 3.34049961 1 P 0 ;0,1=569,2=270.000000
L 1.5205 3.34049961 1.51946693 3.34356634 1 P 0 ;0,1=569,2=270.000000
L 1.51946693 3.34356634 1.51688415 3.34586654 1 P 0 ;0,1=569,2=270.000000
L 1.51688415 3.34586654 1.51378386 3.3474002 1 P 0 ;0,1=569,2=270.000000
L 1.51378386 3.3474002 1.50965049 3.34855 1 P 0 ;0,1=569,2=270.000000
L 1.50965049 3.34855 1.50500049 3.34893327 1 P 0 ;0,1=569,2=270.000000
L 1.50500049 3.34893327 1.50035059 3.34855 1 P 0 ;0,1=569,2=270.000000
L 1.50035059 3.34855 1.49621624 3.3474002 1 P 0 ;0,1=569,2=270.000000
L 1.49621624 3.3474002 1.49311693 3.34586654 1 P 0 ;0,1=569,2=270.000000
L 1.49311693 3.34586654 1.49053317 3.34356634 1 P 0 ;0,1=569,2=270.000000
L 1.49053317 3.34356634 1.4895 3.34049961 1 P 0 ;0,1=569,2=270.000000
L 1.51688415 3.36498287 1.51946693 3.36766634 1 P 0 ;0,1=569,2=270.000000
L 1.51946693 3.36766634 1.5205 3.37073307 1 P 0 ;0,1=569,2=270.000000
L 1.5205 3.37073307 1.51946693 3.3737998 1 P 0 ;0,1=569,2=270.000000
L 1.51946693 3.3737998 1.51636762 3.37648327 1 P 0 ;0,1=569,2=270.000000
L 1.51636762 3.37648327 1.51171673 3.3784002 1 P 0 ;0,1=569,2=270.000000
L 1.51171673 3.3784002 1.50706673 3.37916673 1 P 0 ;0,1=569,2=270.000000
L 1.50706673 3.37916673 1.50138366 3.37916673 1 P 0 ;0,1=569,2=270.000000
L 1.50138366 3.37916673 1.49673376 3.3784002 1 P 0 ;0,1=569,2=270.000000
L 1.49673376 3.3784002 1.4926003 3.37648327 1 P 0 ;0,1=569,2=270.000000
L 1.4926003 3.37648327 1.49053317 3.37418307 1 P 0 ;0,1=569,2=270.000000
L 1.49053317 3.37418307 1.4895 3.37149961 1 P 0 ;0,1=569,2=270.000000
L 1.4895 3.37149961 1.49053317 3.36843287 1 P 0 ;0,1=569,2=270.000000
L 1.49053317 3.36843287 1.4926003 3.36613337 1 P 0 ;0,1=569,2=270.000000
L 1.4926003 3.36613337 1.4956997 3.3645997 1 P 0 ;0,1=569,2=270.000000
L 1.4956997 3.3645997 1.49983406 3.36383317 1 P 0 ;0,1=569,2=270.000000
L 1.49983406 3.36383317 1.5034499 3.3645997 1 P 0 ;0,1=569,2=270.000000
L 1.5034499 3.3645997 1.50706673 3.36651663 1 P 0 ;0,1=569,2=270.000000
L 1.50706673 3.36651663 1.50913396 3.36881683 1 P 0 ;0,1=569,2=270.000000
L 1.50913396 3.36881683 1.50965049 3.37149961 1 P 0 ;0,1=569,2=270.000000
L 1.50965049 3.37149961 1.50861732 3.37456634 1 P 0 ;0,1=569,2=270.000000
L 1.50861732 3.37456634 1.50603366 3.37686654 1 P 0 ;0,1=569,2=270.000000
L 1.50603366 3.37686654 1.50138366 3.37916673 1 P 0 ;0,1=569,2=270.000000
L 4.575 3.248 4.575 3.292 1 P 0 
L 4.485 3.248 4.575 3.248 1 P 0 
L 4.575 3.292 4.485 3.292 1 P 0 
L 4.485 3.292 4.485 3.248 1 P 0 
L 4.54743327 3.32791624 4.54513307 3.32946683 1 P 0 ;0,1=570,2=0.000000
L 4.54513307 3.32946683 4.5424503 3.3305 1 P 0 ;0,1=570,2=0.000000
L 4.5424503 3.3305 4.53938356 3.3305 1 P 0 ;0,1=570,2=0.000000
L 4.53938356 3.3305 4.53593287 3.32894931 1 P 0 ;0,1=570,2=0.000000
L 4.53593287 3.32894931 4.5332501 3.32636654 1 P 0 ;0,1=570,2=0.000000
L 4.5332501 3.32636654 4.53133317 3.32326624 1 P 0 ;0,1=570,2=0.000000
L 4.53133317 3.32326624 4.52979951 3.3180998 1 P 0 ;0,1=570,2=0.000000
L 4.52979951 3.3180998 4.52941624 3.3134498 1 P 0 ;0,1=570,2=0.000000
L 4.52941624 3.3134498 4.53018337 3.3087999 1 P 0 ;0,1=570,2=0.000000
L 4.53018337 3.3087999 4.53133317 3.30569961 1 P 0 ;0,1=570,2=0.000000
L 4.53133317 3.30569961 4.53363337 3.30259931 1 P 0 ;0,1=570,2=0.000000
L 4.53363337 3.30259931 4.53631683 3.30053307 1 P 0 ;0,1=570,2=0.000000
L 4.53631683 3.30053307 4.53899961 3.2995 1 P 0 ;0,1=570,2=0.000000
L 4.53899961 3.2995 4.54168307 3.2995 1 P 0 ;0,1=570,2=0.000000
L 4.54168307 3.2995 4.54436654 3.30053307 1 P 0 ;0,1=570,2=0.000000
L 4.54436654 3.30053307 4.54666673 3.30208278 1 P 0 ;0,1=570,2=0.000000
L 4.54666673 3.30208278 4.54858366 3.30414892 1 P 0 ;0,1=570,2=0.000000
L 4.56348287 3.30311585 4.56616634 3.30053307 1 P 0 ;0,1=570,2=0.000000
L 4.56616634 3.30053307 4.56923307 3.2995 1 P 0 ;0,1=570,2=0.000000
L 4.56923307 3.2995 4.5722998 3.30053307 1 P 0 ;0,1=570,2=0.000000
L 4.5722998 3.30053307 4.57498327 3.30363238 1 P 0 ;0,1=570,2=0.000000
L 4.57498327 3.30363238 4.5769002 3.30828327 1 P 0 ;0,1=570,2=0.000000
L 4.5769002 3.30828327 4.57766673 3.31293327 1 P 0 ;0,1=570,2=0.000000
L 4.57766673 3.31293327 4.57766673 3.31861634 1 P 0 ;0,1=570,2=0.000000
L 4.57766673 3.31861634 4.5769002 3.32326624 1 P 0 ;0,1=570,2=0.000000
L 4.5769002 3.32326624 4.57498327 3.3273997 1 P 0 ;0,1=570,2=0.000000
L 4.57498327 3.3273997 4.57268307 3.32946683 1 P 0 ;0,1=570,2=0.000000
L 4.57268307 3.32946683 4.56999961 3.3305 1 P 0 ;0,1=570,2=0.000000
L 4.56999961 3.3305 4.56693287 3.32946683 1 P 0 ;0,1=570,2=0.000000
L 4.56693287 3.32946683 4.56463337 3.3273997 1 P 0 ;0,1=570,2=0.000000
L 4.56463337 3.3273997 4.5630997 3.3243003 1 P 0 ;0,1=570,2=0.000000
L 4.5630997 3.3243003 4.56233317 3.32016594 1 P 0 ;0,1=570,2=0.000000
L 4.56233317 3.32016594 4.5630997 3.3165501 1 P 0 ;0,1=570,2=0.000000
L 4.5630997 3.3165501 4.56501663 3.31293327 1 P 0 ;0,1=570,2=0.000000
L 4.56501663 3.31293327 4.56731683 3.31086604 1 P 0 ;0,1=570,2=0.000000
L 4.56731683 3.31086604 4.56999961 3.31034951 1 P 0 ;0,1=570,2=0.000000
L 4.56999961 3.31034951 4.57306634 3.31138268 1 P 0 ;0,1=570,2=0.000000
L 4.57306634 3.31138268 4.57536654 3.31396634 1 P 0 ;0,1=570,2=0.000000
L 4.57536654 3.31396634 4.57766673 3.31861634 1 P 0 ;0,1=570,2=0.000000
L 4.60023307 3.2995 4.60099961 3.30621614 1 P 0 ;0,1=570,2=0.000000
L 4.60099961 3.30621614 4.6021501 3.31189921 1 P 0 ;0,1=570,2=0.000000
L 4.6021501 3.31189921 4.60368307 3.31706663 1 P 0 ;0,1=570,2=0.000000
L 4.60368307 3.31706663 4.6056 3.3227497 1 P 0 ;0,1=570,2=0.000000
L 4.6056 3.3227497 4.60866673 3.3305 1 P 0 ;0,1=570,2=0.000000
L 4.60866673 3.3305 4.59333317 3.3305 1 P 0 ;0,1=570,2=0.000000
L 1.885 3.212 1.795 3.212 1 P 0 
L 1.795 3.168 1.885 3.168 1 P 0 
L 1.885 3.168 1.885 3.212 1 P 0 
L 1.795 3.212 1.795 3.168 1 P 0 
L 1.95193327 3.19791624 1.94963307 3.19946683 1 P 0 ;0,1=571,2=0.000000
L 1.94963307 3.19946683 1.9469503 3.2005 1 P 0 ;0,1=571,2=0.000000
L 1.9469503 3.2005 1.94388356 3.2005 1 P 0 ;0,1=571,2=0.000000
L 1.94388356 3.2005 1.94043287 3.19894931 1 P 0 ;0,1=571,2=0.000000
L 1.94043287 3.19894931 1.9377501 3.19636654 1 P 0 ;0,1=571,2=0.000000
L 1.9377501 3.19636654 1.93583317 3.19326624 1 P 0 ;0,1=571,2=0.000000
L 1.93583317 3.19326624 1.93429951 3.1880998 1 P 0 ;0,1=571,2=0.000000
L 1.93429951 3.1880998 1.93391624 3.1834498 1 P 0 ;0,1=571,2=0.000000
L 1.93391624 3.1834498 1.93468337 3.1787999 1 P 0 ;0,1=571,2=0.000000
L 1.93468337 3.1787999 1.93583317 3.17569961 1 P 0 ;0,1=571,2=0.000000
L 1.93583317 3.17569961 1.93813337 3.17259931 1 P 0 ;0,1=571,2=0.000000
L 1.93813337 3.17259931 1.94081683 3.17053307 1 P 0 ;0,1=571,2=0.000000
L 1.94081683 3.17053307 1.94349961 3.1695 1 P 0 ;0,1=571,2=0.000000
L 1.94349961 3.1695 1.94618307 3.1695 1 P 0 ;0,1=571,2=0.000000
L 1.94618307 3.1695 1.94886654 3.17053307 1 P 0 ;0,1=571,2=0.000000
L 1.94886654 3.17053307 1.95116673 3.17208278 1 P 0 ;0,1=571,2=0.000000
L 1.95116673 3.17208278 1.95308366 3.17414892 1 P 0 ;0,1=571,2=0.000000
L 1.96721644 3.19533346 1.96951663 3.19843278 1 P 0 ;0,1=571,2=0.000000
L 1.96951663 3.19843278 1.9722001 3.19998337 1 P 0 ;0,1=571,2=0.000000
L 1.9722001 3.19998337 1.97526683 3.2005 1 P 0 ;0,1=571,2=0.000000
L 1.97526683 3.2005 1.9791 3.19946683 1 P 0 ;0,1=571,2=0.000000
L 1.9791 3.19946683 1.98178346 3.19688307 1 P 0 ;0,1=571,2=0.000000
L 1.98178346 3.19688307 1.98255 3.19378376 1 P 0 ;0,1=571,2=0.000000
L 1.98255 3.19378376 1.98216673 3.19068258 1 P 0 ;0,1=571,2=0.000000
L 1.98216673 3.19068258 1.98063307 3.1880998 1 P 0 ;0,1=571,2=0.000000
L 1.98063307 3.1880998 1.97296663 3.18293327 1 P 0 ;0,1=571,2=0.000000
L 1.97296663 3.18293327 1.96951663 3.17931644 1 P 0 ;0,1=571,2=0.000000
L 1.96951663 3.17931644 1.96721644 3.17414892 1 P 0 ;0,1=571,2=0.000000
L 1.96721644 3.17414892 1.9664499 3.1695 1 P 0 ;0,1=571,2=0.000000
L 1.9664499 3.1695 1.98255 3.1695 1 P 0 ;0,1=571,2=0.000000
L 1.99898287 3.17311585 2.00166634 3.17053307 1 P 0 ;0,1=571,2=0.000000
L 2.00166634 3.17053307 2.00473307 3.1695 1 P 0 ;0,1=571,2=0.000000
L 2.00473307 3.1695 2.0077998 3.17053307 1 P 0 ;0,1=571,2=0.000000
L 2.0077998 3.17053307 2.01048327 3.17363238 1 P 0 ;0,1=571,2=0.000000
L 2.01048327 3.17363238 2.0124002 3.17828327 1 P 0 ;0,1=571,2=0.000000
L 2.0124002 3.17828327 2.01316673 3.18293327 1 P 0 ;0,1=571,2=0.000000
L 2.01316673 3.18293327 2.01316673 3.18861634 1 P 0 ;0,1=571,2=0.000000
L 2.01316673 3.18861634 2.0124002 3.19326624 1 P 0 ;0,1=571,2=0.000000
L 2.0124002 3.19326624 2.01048327 3.1973997 1 P 0 ;0,1=571,2=0.000000
L 2.01048327 3.1973997 2.00818307 3.19946683 1 P 0 ;0,1=571,2=0.000000
L 2.00818307 3.19946683 2.00549961 3.2005 1 P 0 ;0,1=571,2=0.000000
L 2.00549961 3.2005 2.00243287 3.19946683 1 P 0 ;0,1=571,2=0.000000
L 2.00243287 3.19946683 2.00013337 3.1973997 1 P 0 ;0,1=571,2=0.000000
L 2.00013337 3.1973997 1.9985997 3.1943003 1 P 0 ;0,1=571,2=0.000000
L 1.9985997 3.1943003 1.99783317 3.19016594 1 P 0 ;0,1=571,2=0.000000
L 1.99783317 3.19016594 1.9985997 3.1865501 1 P 0 ;0,1=571,2=0.000000
L 1.9985997 3.1865501 2.00051663 3.18293327 1 P 0 ;0,1=571,2=0.000000
L 2.00051663 3.18293327 2.00281683 3.18086604 1 P 0 ;0,1=571,2=0.000000
L 2.00281683 3.18086604 2.00549961 3.18034951 1 P 0 ;0,1=571,2=0.000000
L 2.00549961 3.18034951 2.00856634 3.18138268 1 P 0 ;0,1=571,2=0.000000
L 2.00856634 3.18138268 2.01086654 3.18396634 1 P 0 ;0,1=571,2=0.000000
L 2.01086654 3.18396634 2.01316673 3.18861634 1 P 0 ;0,1=571,2=0.000000
L 2.03649961 3.1695 2.03918307 3.17001654 1 P 0 ;0,1=571,2=0.000000
L 2.03918307 3.17001654 2.0422498 3.17156614 1 P 0 ;0,1=571,2=0.000000
L 2.0422498 3.17156614 2.04416673 3.17414892 1 P 0 ;0,1=571,2=0.000000
L 2.04416673 3.17414892 2.04493327 3.17776673 1 P 0 ;0,1=571,2=0.000000
L 2.04493327 3.17776673 2.04416673 3.18138268 1 P 0 ;0,1=571,2=0.000000
L 2.04416673 3.18138268 2.04186654 3.18448287 1 P 0 ;0,1=571,2=0.000000
L 2.04186654 3.18448287 2.03841654 3.18603356 1 P 0 ;0,1=571,2=0.000000
L 2.03841654 3.18603356 2.03458337 3.18603356 1 P 0 ;0,1=571,2=0.000000
L 2.03458337 3.18603356 2.03228317 3.18706663 1 P 0 ;0,1=571,2=0.000000
L 2.03228317 3.18706663 2.03036614 3.18964941 1 P 0 ;0,1=571,2=0.000000
L 2.03036614 3.18964941 2.0295997 3.19326624 1 P 0 ;0,1=571,2=0.000000
L 2.0295997 3.19326624 2.0307501 3.19688307 1 P 0 ;0,1=571,2=0.000000
L 2.0307501 3.19688307 2.03343287 3.19946683 1 P 0 ;0,1=571,2=0.000000
L 2.03343287 3.19946683 2.03649961 3.2005 1 P 0 ;0,1=571,2=0.000000
L 2.03649961 3.2005 2.03956634 3.19946683 1 P 0 ;0,1=571,2=0.000000
L 2.03956634 3.19946683 2.0422498 3.19688307 1 P 0 ;0,1=571,2=0.000000
L 2.0422498 3.19688307 2.0434002 3.19326624 1 P 0 ;0,1=571,2=0.000000
L 2.0434002 3.19326624 2.04263307 3.18964941 1 P 0 ;0,1=571,2=0.000000
L 2.04263307 3.18964941 2.04071673 3.18706663 1 P 0 ;0,1=571,2=0.000000
L 2.04071673 3.18706663 2.03841654 3.18603356 1 P 0 ;0,1=571,2=0.000000
L 2.03841654 3.18603356 2.03458337 3.18603356 1 P 0 ;0,1=571,2=0.000000
L 2.03458337 3.18603356 2.03113337 3.18448287 1 P 0 ;0,1=571,2=0.000000
L 2.03113337 3.18448287 2.02883317 3.18138268 1 P 0 ;0,1=571,2=0.000000
L 2.02883317 3.18138268 2.02806663 3.17776673 1 P 0 ;0,1=571,2=0.000000
L 2.02806663 3.17776673 2.02883317 3.17414892 1 P 0 ;0,1=571,2=0.000000
L 2.02883317 3.17414892 2.0307501 3.17156614 1 P 0 ;0,1=571,2=0.000000
L 2.0307501 3.17156614 2.03381683 3.17001654 1 P 0 ;0,1=571,2=0.000000
L 2.03381683 3.17001654 2.03649961 3.1695 1 P 0 ;0,1=571,2=0.000000
L 1.907 2.915 1.907 3.005 1 P 0 
L 1.907 3.005 1.863 3.005 1 P 0 
L 1.863 3.005 1.863 2.915 1 P 0 
L 1.863 2.915 1.907 2.915 1 P 0 
L 1.95708376 2.90693327 1.95553317 2.90463307 1 P 0 ;0,1=572,2=270.000000
L 1.95553317 2.90463307 1.9545 2.9019503 1 P 0 ;0,1=572,2=270.000000
L 1.9545 2.9019503 1.9545 2.89888356 1 P 0 ;0,1=572,2=270.000000
L 1.9545 2.89888356 1.95605069 2.89543287 1 P 0 ;0,1=572,2=270.000000
L 1.95605069 2.89543287 1.95863346 2.8927501 1 P 0 ;0,1=572,2=270.000000
L 1.95863346 2.8927501 1.96173376 2.89083317 1 P 0 ;0,1=572,2=270.000000
L 1.96173376 2.89083317 1.9669002 2.88929951 1 P 0 ;0,1=572,2=270.000000
L 1.9669002 2.88929951 1.9715502 2.88891624 1 P 0 ;0,1=572,2=270.000000
L 1.9715502 2.88891624 1.9762001 2.88968337 1 P 0 ;0,1=572,2=270.000000
L 1.9762001 2.88968337 1.97930039 2.89083317 1 P 0 ;0,1=572,2=270.000000
L 1.97930039 2.89083317 1.98240069 2.89313337 1 P 0 ;0,1=572,2=270.000000
L 1.98240069 2.89313337 1.98446693 2.89581683 1 P 0 ;0,1=572,2=270.000000
L 1.98446693 2.89581683 1.9855 2.89849961 1 P 0 ;0,1=572,2=270.000000
L 1.9855 2.89849961 1.9855 2.90118307 1 P 0 ;0,1=572,2=270.000000
L 1.9855 2.90118307 1.98446693 2.90386654 1 P 0 ;0,1=572,2=270.000000
L 1.98446693 2.90386654 1.98291722 2.90616673 1 P 0 ;0,1=572,2=270.000000
L 1.98291722 2.90616673 1.98085108 2.90808366 1 P 0 ;0,1=572,2=270.000000
L 1.97930039 2.92106663 1.98291722 2.92336614 1 P 0 ;0,1=572,2=270.000000
L 1.98291722 2.92336614 1.98498346 2.92643287 1 P 0 ;0,1=572,2=270.000000
L 1.98498346 2.92643287 1.9855 2.92988356 1 P 0 ;0,1=572,2=270.000000
L 1.9855 2.92988356 1.98498346 2.9329503 1 P 0 ;0,1=572,2=270.000000
L 1.98498346 2.9329503 1.98240069 2.93601703 1 P 0 ;0,1=572,2=270.000000
L 1.98240069 2.93601703 1.97930039 2.93793327 1 P 0 ;0,1=572,2=270.000000
L 1.97930039 2.93793327 1.9762001 2.93831654 1 P 0 ;0,1=572,2=270.000000
L 1.9762001 2.93831654 1.97258425 2.93755 1 P 0 ;0,1=572,2=270.000000
L 1.97258425 2.93755 1.97000049 2.93486654 1 P 0 ;0,1=572,2=270.000000
L 1.97000049 2.93486654 1.96896644 2.93218307 1 P 0 ;0,1=572,2=270.000000
L 1.96896644 2.93218307 1.96896644 2.92873307 1 P 0 ;0,1=572,2=270.000000
L 1.96896644 2.93218307 1.96741683 2.93448327 1 P 0 ;0,1=572,2=270.000000
L 1.96741683 2.93448327 1.96483406 2.9364002 1 P 0 ;0,1=572,2=270.000000
L 1.96483406 2.9364002 1.96173376 2.93716673 1 P 0 ;0,1=572,2=270.000000
L 1.96173376 2.93716673 1.95863346 2.9364002 1 P 0 ;0,1=572,2=270.000000
L 1.95863346 2.9364002 1.95605069 2.93448327 1 P 0 ;0,1=572,2=270.000000
L 1.95605069 2.93448327 1.9545 2.93103327 1 P 0 ;0,1=572,2=270.000000
L 1.9545 2.93103327 1.95501663 2.92758337 1 P 0 ;0,1=572,2=270.000000
L 1.95501663 2.92758337 1.95708376 2.92413337 1 P 0 ;0,1=572,2=270.000000
L 1.9545 2.96049961 1.95553317 2.95743287 1 P 0 ;0,1=572,2=270.000000
L 1.95553317 2.95743287 1.95811693 2.95513337 1 P 0 ;0,1=572,2=270.000000
L 1.95811693 2.95513337 1.96121624 2.9535997 1 P 0 ;0,1=572,2=270.000000
L 1.96121624 2.9535997 1.96535059 2.9524499 1 P 0 ;0,1=572,2=270.000000
L 1.96535059 2.9524499 1.97000049 2.95206663 1 P 0 ;0,1=572,2=270.000000
L 1.97000049 2.95206663 1.97465049 2.9524499 1 P 0 ;0,1=572,2=270.000000
L 1.97465049 2.9524499 1.97878386 2.9535997 1 P 0 ;0,1=572,2=270.000000
L 1.97878386 2.9535997 1.98188415 2.95513337 1 P 0 ;0,1=572,2=270.000000
L 1.98188415 2.95513337 1.98446693 2.95743287 1 P 0 ;0,1=572,2=270.000000
L 1.98446693 2.95743287 1.9855 2.96049961 1 P 0 ;0,1=572,2=270.000000
L 1.9855 2.96049961 1.98446693 2.96356634 1 P 0 ;0,1=572,2=270.000000
L 1.98446693 2.96356634 1.98188415 2.96586654 1 P 0 ;0,1=572,2=270.000000
L 1.98188415 2.96586654 1.97878386 2.9674002 1 P 0 ;0,1=572,2=270.000000
L 1.97878386 2.9674002 1.97465049 2.96855 1 P 0 ;0,1=572,2=270.000000
L 1.97465049 2.96855 1.97000049 2.96893327 1 P 0 ;0,1=572,2=270.000000
L 1.97000049 2.96893327 1.96535059 2.96855 1 P 0 ;0,1=572,2=270.000000
L 1.96535059 2.96855 1.96121624 2.9674002 1 P 0 ;0,1=572,2=270.000000
L 1.96121624 2.9674002 1.95811693 2.96586654 1 P 0 ;0,1=572,2=270.000000
L 1.95811693 2.96586654 1.95553317 2.96356634 1 P 0 ;0,1=572,2=270.000000
L 1.95553317 2.96356634 1.9545 2.96049961 1 P 0 ;0,1=572,2=270.000000
L 1.95966654 2.98421644 1.95656722 2.98651663 1 P 0 ;0,1=572,2=270.000000
L 1.95656722 2.98651663 1.95501663 2.9892001 1 P 0 ;0,1=572,2=270.000000
L 1.95501663 2.9892001 1.9545 2.99226683 1 P 0 ;0,1=572,2=270.000000
L 1.9545 2.99226683 1.95553317 2.9961 1 P 0 ;0,1=572,2=270.000000
L 1.95553317 2.9961 1.95811693 2.99878346 1 P 0 ;0,1=572,2=270.000000
L 1.95811693 2.99878346 1.96121624 2.99955 1 P 0 ;0,1=572,2=270.000000
L 1.96121624 2.99955 1.96431742 2.99916673 1 P 0 ;0,1=572,2=270.000000
L 1.96431742 2.99916673 1.9669002 2.99763307 1 P 0 ;0,1=572,2=270.000000
L 1.9669002 2.99763307 1.97206673 2.98996663 1 P 0 ;0,1=572,2=270.000000
L 1.97206673 2.98996663 1.97568356 2.98651663 1 P 0 ;0,1=572,2=270.000000
L 1.97568356 2.98651663 1.98085108 2.98421644 1 P 0 ;0,1=572,2=270.000000
L 1.98085108 2.98421644 1.9855 2.9834499 1 P 0 ;0,1=572,2=270.000000
L 1.9855 2.9834499 1.9855 2.99955 1 P 0 ;0,1=572,2=270.000000
L 1.89 3.062 1.8 3.062 1 P 0 
L 1.8 3.018 1.89 3.018 1 P 0 
L 1.89 3.018 1.89 3.062 1 P 0 
L 1.8 3.062 1.8 3.018 1 P 0 
L 1.93193327 3.04791624 1.92963307 3.04946683 1 P 0 ;0,1=573,2=0.000000
L 1.92963307 3.04946683 1.9269503 3.0505 1 P 0 ;0,1=573,2=0.000000
L 1.9269503 3.0505 1.92388356 3.0505 1 P 0 ;0,1=573,2=0.000000
L 1.92388356 3.0505 1.92043287 3.04894931 1 P 0 ;0,1=573,2=0.000000
L 1.92043287 3.04894931 1.9177501 3.04636654 1 P 0 ;0,1=573,2=0.000000
L 1.9177501 3.04636654 1.91583317 3.04326624 1 P 0 ;0,1=573,2=0.000000
L 1.91583317 3.04326624 1.91429951 3.0380998 1 P 0 ;0,1=573,2=0.000000
L 1.91429951 3.0380998 1.91391624 3.0334498 1 P 0 ;0,1=573,2=0.000000
L 1.91391624 3.0334498 1.91468337 3.0287999 1 P 0 ;0,1=573,2=0.000000
L 1.91468337 3.0287999 1.91583317 3.02569961 1 P 0 ;0,1=573,2=0.000000
L 1.91583317 3.02569961 1.91813337 3.02259931 1 P 0 ;0,1=573,2=0.000000
L 1.91813337 3.02259931 1.92081683 3.02053307 1 P 0 ;0,1=573,2=0.000000
L 1.92081683 3.02053307 1.92349961 3.0195 1 P 0 ;0,1=573,2=0.000000
L 1.92349961 3.0195 1.92618307 3.0195 1 P 0 ;0,1=573,2=0.000000
L 1.92618307 3.0195 1.92886654 3.02053307 1 P 0 ;0,1=573,2=0.000000
L 1.92886654 3.02053307 1.93116673 3.02208278 1 P 0 ;0,1=573,2=0.000000
L 1.93116673 3.02208278 1.93308366 3.02414892 1 P 0 ;0,1=573,2=0.000000
L 1.94606663 3.02569961 1.94836614 3.02208278 1 P 0 ;0,1=573,2=0.000000
L 1.94836614 3.02208278 1.95143287 3.02001654 1 P 0 ;0,1=573,2=0.000000
L 1.95143287 3.02001654 1.95488356 3.0195 1 P 0 ;0,1=573,2=0.000000
L 1.95488356 3.0195 1.9579503 3.02001654 1 P 0 ;0,1=573,2=0.000000
L 1.9579503 3.02001654 1.96101703 3.02259931 1 P 0 ;0,1=573,2=0.000000
L 1.96101703 3.02259931 1.96293327 3.02569961 1 P 0 ;0,1=573,2=0.000000
L 1.96293327 3.02569961 1.96331654 3.0287999 1 P 0 ;0,1=573,2=0.000000
L 1.96331654 3.0287999 1.96255 3.03241575 1 P 0 ;0,1=573,2=0.000000
L 1.96255 3.03241575 1.95986654 3.03499951 1 P 0 ;0,1=573,2=0.000000
L 1.95986654 3.03499951 1.95718307 3.03603356 1 P 0 ;0,1=573,2=0.000000
L 1.95718307 3.03603356 1.95373307 3.03603356 1 P 0 ;0,1=573,2=0.000000
L 1.95718307 3.03603356 1.95948327 3.03758317 1 P 0 ;0,1=573,2=0.000000
L 1.95948327 3.03758317 1.9614002 3.04016594 1 P 0 ;0,1=573,2=0.000000
L 1.9614002 3.04016594 1.96216673 3.04326624 1 P 0 ;0,1=573,2=0.000000
L 1.96216673 3.04326624 1.9614002 3.04636654 1 P 0 ;0,1=573,2=0.000000
L 1.9614002 3.04636654 1.95948327 3.04894931 1 P 0 ;0,1=573,2=0.000000
L 1.95948327 3.04894931 1.95603327 3.0505 1 P 0 ;0,1=573,2=0.000000
L 1.95603327 3.0505 1.95258337 3.04998337 1 P 0 ;0,1=573,2=0.000000
L 1.95258337 3.04998337 1.94913337 3.04791624 1 P 0 ;0,1=573,2=0.000000
L 1.98549961 3.0505 1.98243287 3.04946683 1 P 0 ;0,1=573,2=0.000000
L 1.98243287 3.04946683 1.98013337 3.04688307 1 P 0 ;0,1=573,2=0.000000
L 1.98013337 3.04688307 1.9785997 3.04378376 1 P 0 ;0,1=573,2=0.000000
L 1.9785997 3.04378376 1.9774499 3.03964941 1 P 0 ;0,1=573,2=0.000000
L 1.9774499 3.03964941 1.97706663 3.03499951 1 P 0 ;0,1=573,2=0.000000
L 1.97706663 3.03499951 1.9774499 3.03034951 1 P 0 ;0,1=573,2=0.000000
L 1.9774499 3.03034951 1.9785997 3.02621614 1 P 0 ;0,1=573,2=0.000000
L 1.9785997 3.02621614 1.98013337 3.02311585 1 P 0 ;0,1=573,2=0.000000
L 1.98013337 3.02311585 1.98243287 3.02053307 1 P 0 ;0,1=573,2=0.000000
L 1.98243287 3.02053307 1.98549961 3.0195 1 P 0 ;0,1=573,2=0.000000
L 1.98549961 3.0195 1.98856634 3.02053307 1 P 0 ;0,1=573,2=0.000000
L 1.98856634 3.02053307 1.99086654 3.02311585 1 P 0 ;0,1=573,2=0.000000
L 1.99086654 3.02311585 1.9924002 3.02621614 1 P 0 ;0,1=573,2=0.000000
L 1.9924002 3.02621614 1.99355 3.03034951 1 P 0 ;0,1=573,2=0.000000
L 1.99355 3.03034951 1.99393327 3.03499951 1 P 0 ;0,1=573,2=0.000000
L 1.99393327 3.03499951 1.99355 3.03964941 1 P 0 ;0,1=573,2=0.000000
L 1.99355 3.03964941 1.9924002 3.04378376 1 P 0 ;0,1=573,2=0.000000
L 1.9924002 3.04378376 1.99086654 3.04688307 1 P 0 ;0,1=573,2=0.000000
L 1.99086654 3.04688307 1.98856634 3.04946683 1 P 0 ;0,1=573,2=0.000000
L 1.98856634 3.04946683 1.98549961 3.0505 1 P 0 ;0,1=573,2=0.000000
L 2.0211 3.0195 2.0211 3.0505 1 P 0 ;0,1=573,2=0.000000
L 2.0211 3.0505 2.00691624 3.02828327 1 P 0 ;0,1=573,2=0.000000
L 2.00691624 3.02828327 2.02608366 3.02828327 1 P 0 ;0,1=573,2=0.000000
L 0.618 2.295 0.618 2.205 1 P 0 
L 0.618 2.205 0.662 2.205 1 P 0 
L 0.662 2.205 0.662 2.295 1 P 0 
L 0.662 2.295 0.618 2.295 1 P 0 
L 0.64708376 2.13743327 0.64553317 2.13513307 1 P 0 ;0,1=574,2=270.000000
L 0.64553317 2.13513307 0.6445 2.1324503 1 P 0 ;0,1=574,2=270.000000
L 0.6445 2.1324503 0.6445 2.12938356 1 P 0 ;0,1=574,2=270.000000
L 0.6445 2.12938356 0.64605069 2.12593287 1 P 0 ;0,1=574,2=270.000000
L 0.64605069 2.12593287 0.64863346 2.1232501 1 P 0 ;0,1=574,2=270.000000
L 0.64863346 2.1232501 0.65173376 2.12133317 1 P 0 ;0,1=574,2=270.000000
L 0.65173376 2.12133317 0.6569002 2.11979951 1 P 0 ;0,1=574,2=270.000000
L 0.6569002 2.11979951 0.6615502 2.11941624 1 P 0 ;0,1=574,2=270.000000
L 0.6615502 2.11941624 0.6662001 2.12018337 1 P 0 ;0,1=574,2=270.000000
L 0.6662001 2.12018337 0.66930039 2.12133317 1 P 0 ;0,1=574,2=270.000000
L 0.66930039 2.12133317 0.67240069 2.12363337 1 P 0 ;0,1=574,2=270.000000
L 0.67240069 2.12363337 0.67446693 2.12631683 1 P 0 ;0,1=574,2=270.000000
L 0.67446693 2.12631683 0.6755 2.12899961 1 P 0 ;0,1=574,2=270.000000
L 0.6755 2.12899961 0.6755 2.13168307 1 P 0 ;0,1=574,2=270.000000
L 0.6755 2.13168307 0.67446693 2.13436654 1 P 0 ;0,1=574,2=270.000000
L 0.67446693 2.13436654 0.67291722 2.13666673 1 P 0 ;0,1=574,2=270.000000
L 0.67291722 2.13666673 0.67085108 2.13858366 1 P 0 ;0,1=574,2=270.000000
L 0.6755 2.15999961 0.67498346 2.16268307 1 P 0 ;0,1=574,2=270.000000
L 0.67498346 2.16268307 0.67343386 2.1657498 1 P 0 ;0,1=574,2=270.000000
L 0.67343386 2.1657498 0.67085108 2.16766673 1 P 0 ;0,1=574,2=270.000000
L 0.67085108 2.16766673 0.66723327 2.16843327 1 P 0 ;0,1=574,2=270.000000
L 0.66723327 2.16843327 0.66361732 2.16766673 1 P 0 ;0,1=574,2=270.000000
L 0.66361732 2.16766673 0.66051713 2.16536654 1 P 0 ;0,1=574,2=270.000000
L 0.66051713 2.16536654 0.65896644 2.16191654 1 P 0 ;0,1=574,2=270.000000
L 0.65896644 2.16191654 0.65896644 2.15808337 1 P 0 ;0,1=574,2=270.000000
L 0.65896644 2.15808337 0.65793337 2.15578317 1 P 0 ;0,1=574,2=270.000000
L 0.65793337 2.15578317 0.65535059 2.15386614 1 P 0 ;0,1=574,2=270.000000
L 0.65535059 2.15386614 0.65173376 2.1530997 1 P 0 ;0,1=574,2=270.000000
L 0.65173376 2.1530997 0.64811693 2.1542501 1 P 0 ;0,1=574,2=270.000000
L 0.64811693 2.1542501 0.64553317 2.15693287 1 P 0 ;0,1=574,2=270.000000
L 0.64553317 2.15693287 0.6445 2.15999961 1 P 0 ;0,1=574,2=270.000000
L 0.6445 2.15999961 0.64553317 2.16306634 1 P 0 ;0,1=574,2=270.000000
L 0.64553317 2.16306634 0.64811693 2.1657498 1 P 0 ;0,1=574,2=270.000000
L 0.64811693 2.1657498 0.65173376 2.1669002 1 P 0 ;0,1=574,2=270.000000
L 0.65173376 2.1669002 0.65535059 2.16613307 1 P 0 ;0,1=574,2=270.000000
L 0.65535059 2.16613307 0.65793337 2.16421673 1 P 0 ;0,1=574,2=270.000000
L 0.65793337 2.16421673 0.65896644 2.16191654 1 P 0 ;0,1=574,2=270.000000
L 0.65896644 2.16191654 0.65896644 2.15808337 1 P 0 ;0,1=574,2=270.000000
L 0.65896644 2.15808337 0.66051713 2.15463337 1 P 0 ;0,1=574,2=270.000000
L 0.66051713 2.15463337 0.66361732 2.15233317 1 P 0 ;0,1=574,2=270.000000
L 0.66361732 2.15233317 0.66723327 2.15156663 1 P 0 ;0,1=574,2=270.000000
L 0.66723327 2.15156663 0.67085108 2.15233317 1 P 0 ;0,1=574,2=270.000000
L 0.67085108 2.15233317 0.67343386 2.1542501 1 P 0 ;0,1=574,2=270.000000
L 0.67343386 2.1542501 0.67498346 2.15731683 1 P 0 ;0,1=574,2=270.000000
L 0.67498346 2.15731683 0.6755 2.15999961 1 P 0 ;0,1=574,2=270.000000
L 0.67085108 2.18256663 0.67343386 2.18486614 1 P 0 ;0,1=574,2=270.000000
L 0.67343386 2.18486614 0.67498346 2.18754961 1 P 0 ;0,1=574,2=270.000000
L 0.67498346 2.18754961 0.6755 2.19099961 1 P 0 ;0,1=574,2=270.000000
L 0.6755 2.19099961 0.67446693 2.1944503 1 P 0 ;0,1=574,2=270.000000
L 0.67446693 2.1944503 0.67240069 2.19713307 1 P 0 ;0,1=574,2=270.000000
L 0.67240069 2.19713307 0.66878386 2.19905 1 P 0 ;0,1=574,2=270.000000
L 0.66878386 2.19905 0.66465049 2.19943327 1 P 0 ;0,1=574,2=270.000000
L 0.66465049 2.19943327 0.66051713 2.19866673 1 P 0 ;0,1=574,2=270.000000
L 0.66051713 2.19866673 0.65793337 2.1967498 1 P 0 ;0,1=574,2=270.000000
L 0.65793337 2.1967498 0.65586713 2.19406634 1 P 0 ;0,1=574,2=270.000000
L 0.65586713 2.19406634 0.65535059 2.19138356 1 P 0 ;0,1=574,2=270.000000
L 0.65535059 2.19138356 0.65586713 2.1887001 1 P 0 ;0,1=574,2=270.000000
L 0.65586713 2.1887001 0.65793337 2.1852501 1 P 0 ;0,1=574,2=270.000000
L 0.65793337 2.1852501 0.6445 2.1863999 1 P 0 ;0,1=574,2=270.000000
L 0.6445 2.1863999 0.6445 2.1967498 1 P 0 ;0,1=574,2=270.000000
L 0.628 1.71345 0.584 1.71345 1 P 0 
L 0.584 1.71345 0.584 1.62345 1 P 0 
L 0.584 1.62345 0.628 1.62345 1 P 0 
L 0.628 1.62345 0.628 1.71345 1 P 0 
L 0.61958366 1.56886663 0.61833317 1.56726644 1 P 0 ;0,1=575,2=270.000000
L 0.61833317 1.56726644 0.6175 1.5654002 1 P 0 ;0,1=575,2=270.000000
L 0.6175 1.5654002 0.6175 1.56326683 1 P 0 ;0,1=575,2=270.000000
L 0.6175 1.56326683 0.61875059 1.56086634 1 P 0 ;0,1=575,2=270.000000
L 0.61875059 1.56086634 0.62083346 1.5590001 1 P 0 ;0,1=575,2=270.000000
L 0.62083346 1.5590001 0.62333366 1.55766654 1 P 0 ;0,1=575,2=270.000000
L 0.62333366 1.55766654 0.6275002 1.55659961 1 P 0 ;0,1=575,2=270.000000
L 0.6275002 1.55659961 0.6312502 1.55633297 1 P 0 ;0,1=575,2=270.000000
L 0.6312502 1.55633297 0.6350001 1.55686673 1 P 0 ;0,1=575,2=270.000000
L 0.6350001 1.55686673 0.63750039 1.55766654 1 P 0 ;0,1=575,2=270.000000
L 0.63750039 1.55766654 0.64000059 1.55926663 1 P 0 ;0,1=575,2=270.000000
L 0.64000059 1.55926663 0.64166693 1.56113346 1 P 0 ;0,1=575,2=270.000000
L 0.64166693 1.56113346 0.6425 1.5629997 1 P 0 ;0,1=575,2=270.000000
L 0.6425 1.5629997 0.6425 1.56486644 1 P 0 ;0,1=575,2=270.000000
L 0.6425 1.56486644 0.64166693 1.56673327 1 P 0 ;0,1=575,2=270.000000
L 0.64166693 1.56673327 0.64041713 1.56833337 1 P 0 ;0,1=575,2=270.000000
L 0.64041713 1.56833337 0.63875089 1.56966693 1 P 0 ;0,1=575,2=270.000000
L 0.6425 1.5849997 0.64208346 1.58686644 1 P 0 ;0,1=575,2=270.000000
L 0.64208346 1.58686644 0.64083376 1.5889998 1 P 0 ;0,1=575,2=270.000000
L 0.64083376 1.5889998 0.63875089 1.59033337 1 P 0 ;0,1=575,2=270.000000
L 0.63875089 1.59033337 0.63583327 1.59086663 1 P 0 ;0,1=575,2=270.000000
L 0.63583327 1.59086663 0.63291722 1.59033337 1 P 0 ;0,1=575,2=270.000000
L 0.63291722 1.59033337 0.63041703 1.58873327 1 P 0 ;0,1=575,2=270.000000
L 0.63041703 1.58873327 0.62916654 1.58633327 1 P 0 ;0,1=575,2=270.000000
L 0.62916654 1.58633327 0.62916654 1.58366663 1 P 0 ;0,1=575,2=270.000000
L 0.62916654 1.58366663 0.62833337 1.58206654 1 P 0 ;0,1=575,2=270.000000
L 0.62833337 1.58206654 0.62625049 1.58073297 1 P 0 ;0,1=575,2=270.000000
L 0.62625049 1.58073297 0.62333366 1.5801998 1 P 0 ;0,1=575,2=270.000000
L 0.62333366 1.5801998 0.62041683 1.5810001 1 P 0 ;0,1=575,2=270.000000
L 0.62041683 1.5810001 0.61833317 1.58286634 1 P 0 ;0,1=575,2=270.000000
L 0.61833317 1.58286634 0.6175 1.5849997 1 P 0 ;0,1=575,2=270.000000
L 0.6175 1.5849997 0.61833317 1.58713307 1 P 0 ;0,1=575,2=270.000000
L 0.61833317 1.58713307 0.62041683 1.5889998 1 P 0 ;0,1=575,2=270.000000
L 0.62041683 1.5889998 0.62333366 1.5898001 1 P 0 ;0,1=575,2=270.000000
L 0.62333366 1.5898001 0.62625049 1.58926644 1 P 0 ;0,1=575,2=270.000000
L 0.62625049 1.58926644 0.62833337 1.58793337 1 P 0 ;0,1=575,2=270.000000
L 0.62833337 1.58793337 0.62916654 1.58633327 1 P 0 ;0,1=575,2=270.000000
L 0.62916654 1.58633327 0.62916654 1.58366663 1 P 0 ;0,1=575,2=270.000000
L 0.62916654 1.58366663 0.63041703 1.58126663 1 P 0 ;0,1=575,2=270.000000
L 0.63041703 1.58126663 0.63291722 1.57966654 1 P 0 ;0,1=575,2=270.000000
L 0.63291722 1.57966654 0.63583327 1.57913327 1 P 0 ;0,1=575,2=270.000000
L 0.63583327 1.57913327 0.63875089 1.57966654 1 P 0 ;0,1=575,2=270.000000
L 0.63875089 1.57966654 0.64083376 1.5810001 1 P 0 ;0,1=575,2=270.000000
L 0.64083376 1.5810001 0.64208346 1.58313346 1 P 0 ;0,1=575,2=270.000000
L 0.64208346 1.58313346 0.6425 1.5849997 1 P 0 ;0,1=575,2=270.000000
L 0.6425 1.6102 0.6175 1.6102 1 P 0 ;0,1=575,2=270.000000
L 0.6175 1.6102 0.63541673 1.60033297 1 P 0 ;0,1=575,2=270.000000
L 0.63541673 1.60033297 0.63541673 1.61366693 1 P 0 ;0,1=575,2=270.000000
L 0.647 1.15 0.603 1.15 1 P 0 
L 0.603 1.15 0.603 1.06 1 P 0 
L 0.603 1.06 0.647 1.06 1 P 0 
L 0.647 1.06 0.647 1.15 1 P 0 
L 0.68208376 1.07743327 0.68053317 1.07513307 1 P 0 ;0,1=576,2=270.000000
L 0.68053317 1.07513307 0.6795 1.0724503 1 P 0 ;0,1=576,2=270.000000
L 0.6795 1.0724503 0.6795 1.06938356 1 P 0 ;0,1=576,2=270.000000
L 0.6795 1.06938356 0.68105069 1.06593287 1 P 0 ;0,1=576,2=270.000000
L 0.68105069 1.06593287 0.68363346 1.0632501 1 P 0 ;0,1=576,2=270.000000
L 0.68363346 1.0632501 0.68673376 1.06133317 1 P 0 ;0,1=576,2=270.000000
L 0.68673376 1.06133317 0.6919002 1.05979951 1 P 0 ;0,1=576,2=270.000000
L 0.6919002 1.05979951 0.6965502 1.05941624 1 P 0 ;0,1=576,2=270.000000
L 0.6965502 1.05941624 0.7012001 1.06018337 1 P 0 ;0,1=576,2=270.000000
L 0.7012001 1.06018337 0.70430039 1.06133317 1 P 0 ;0,1=576,2=270.000000
L 0.70430039 1.06133317 0.70740069 1.06363337 1 P 0 ;0,1=576,2=270.000000
L 0.70740069 1.06363337 0.70946693 1.06631683 1 P 0 ;0,1=576,2=270.000000
L 0.70946693 1.06631683 0.7105 1.06899961 1 P 0 ;0,1=576,2=270.000000
L 0.7105 1.06899961 0.7105 1.07168307 1 P 0 ;0,1=576,2=270.000000
L 0.7105 1.07168307 0.70946693 1.07436654 1 P 0 ;0,1=576,2=270.000000
L 0.70946693 1.07436654 0.70791722 1.07666673 1 P 0 ;0,1=576,2=270.000000
L 0.70791722 1.07666673 0.70585108 1.07858366 1 P 0 ;0,1=576,2=270.000000
L 0.7105 1.09999961 0.70998346 1.10268307 1 P 0 ;0,1=576,2=270.000000
L 0.70998346 1.10268307 0.70843386 1.1057498 1 P 0 ;0,1=576,2=270.000000
L 0.70843386 1.1057498 0.70585108 1.10766673 1 P 0 ;0,1=576,2=270.000000
L 0.70585108 1.10766673 0.70223327 1.10843327 1 P 0 ;0,1=576,2=270.000000
L 0.70223327 1.10843327 0.69861732 1.10766673 1 P 0 ;0,1=576,2=270.000000
L 0.69861732 1.10766673 0.69551713 1.10536654 1 P 0 ;0,1=576,2=270.000000
L 0.69551713 1.10536654 0.69396644 1.10191654 1 P 0 ;0,1=576,2=270.000000
L 0.69396644 1.10191654 0.69396644 1.09808337 1 P 0 ;0,1=576,2=270.000000
L 0.69396644 1.09808337 0.69293337 1.09578317 1 P 0 ;0,1=576,2=270.000000
L 0.69293337 1.09578317 0.69035059 1.09386614 1 P 0 ;0,1=576,2=270.000000
L 0.69035059 1.09386614 0.68673376 1.0930997 1 P 0 ;0,1=576,2=270.000000
L 0.68673376 1.0930997 0.68311693 1.0942501 1 P 0 ;0,1=576,2=270.000000
L 0.68311693 1.0942501 0.68053317 1.09693287 1 P 0 ;0,1=576,2=270.000000
L 0.68053317 1.09693287 0.6795 1.09999961 1 P 0 ;0,1=576,2=270.000000
L 0.6795 1.09999961 0.68053317 1.10306634 1 P 0 ;0,1=576,2=270.000000
L 0.68053317 1.10306634 0.68311693 1.1057498 1 P 0 ;0,1=576,2=270.000000
L 0.68311693 1.1057498 0.68673376 1.1069002 1 P 0 ;0,1=576,2=270.000000
L 0.68673376 1.1069002 0.69035059 1.10613307 1 P 0 ;0,1=576,2=270.000000
L 0.69035059 1.10613307 0.69293337 1.10421673 1 P 0 ;0,1=576,2=270.000000
L 0.69293337 1.10421673 0.69396644 1.10191654 1 P 0 ;0,1=576,2=270.000000
L 0.69396644 1.10191654 0.69396644 1.09808337 1 P 0 ;0,1=576,2=270.000000
L 0.69396644 1.09808337 0.69551713 1.09463337 1 P 0 ;0,1=576,2=270.000000
L 0.69551713 1.09463337 0.69861732 1.09233317 1 P 0 ;0,1=576,2=270.000000
L 0.69861732 1.09233317 0.70223327 1.09156663 1 P 0 ;0,1=576,2=270.000000
L 0.70223327 1.09156663 0.70585108 1.09233317 1 P 0 ;0,1=576,2=270.000000
L 0.70585108 1.09233317 0.70843386 1.0942501 1 P 0 ;0,1=576,2=270.000000
L 0.70843386 1.0942501 0.70998346 1.09731683 1 P 0 ;0,1=576,2=270.000000
L 0.70998346 1.09731683 0.7105 1.09999961 1 P 0 ;0,1=576,2=270.000000
L 0.70430039 1.12256663 0.70791722 1.12486614 1 P 0 ;0,1=576,2=270.000000
L 0.70791722 1.12486614 0.70998346 1.12793287 1 P 0 ;0,1=576,2=270.000000
L 0.70998346 1.12793287 0.7105 1.13138356 1 P 0 ;0,1=576,2=270.000000
L 0.7105 1.13138356 0.70998346 1.1344503 1 P 0 ;0,1=576,2=270.000000
L 0.70998346 1.1344503 0.70740069 1.13751703 1 P 0 ;0,1=576,2=270.000000
L 0.70740069 1.13751703 0.70430039 1.13943327 1 P 0 ;0,1=576,2=270.000000
L 0.70430039 1.13943327 0.7012001 1.13981654 1 P 0 ;0,1=576,2=270.000000
L 0.7012001 1.13981654 0.69758425 1.13905 1 P 0 ;0,1=576,2=270.000000
L 0.69758425 1.13905 0.69500049 1.13636654 1 P 0 ;0,1=576,2=270.000000
L 0.69500049 1.13636654 0.69396644 1.13368307 1 P 0 ;0,1=576,2=270.000000
L 0.69396644 1.13368307 0.69396644 1.13023307 1 P 0 ;0,1=576,2=270.000000
L 0.69396644 1.13368307 0.69241683 1.13598327 1 P 0 ;0,1=576,2=270.000000
L 0.69241683 1.13598327 0.68983406 1.1379002 1 P 0 ;0,1=576,2=270.000000
L 0.68983406 1.1379002 0.68673376 1.13866673 1 P 0 ;0,1=576,2=270.000000
L 0.68673376 1.13866673 0.68363346 1.1379002 1 P 0 ;0,1=576,2=270.000000
L 0.68363346 1.1379002 0.68105069 1.13598327 1 P 0 ;0,1=576,2=270.000000
L 0.68105069 1.13598327 0.6795 1.13253327 1 P 0 ;0,1=576,2=270.000000
L 0.6795 1.13253327 0.68001663 1.12908337 1 P 0 ;0,1=576,2=270.000000
L 0.68001663 1.12908337 0.68208376 1.12563337 1 P 0 ;0,1=576,2=270.000000
L 5.786 3.545 5.786 3.589 1 P 0 
L 5.786 3.589 5.696 3.589 1 P 0 
L 5.696 3.545 5.786 3.545 1 P 0 
L 5.696 3.589 5.696 3.545 1 P 0 
L 5.72293327 3.25791624 5.72063307 3.25946683 1 P 0 ;0,1=577,2=0.000000
L 5.72063307 3.25946683 5.7179503 3.2605 1 P 0 ;0,1=577,2=0.000000
L 5.7179503 3.2605 5.71488356 3.2605 1 P 0 ;0,1=577,2=0.000000
L 5.71488356 3.2605 5.71143287 3.25894931 1 P 0 ;0,1=577,2=0.000000
L 5.71143287 3.25894931 5.7087501 3.25636654 1 P 0 ;0,1=577,2=0.000000
L 5.7087501 3.25636654 5.70683317 3.25326624 1 P 0 ;0,1=577,2=0.000000
L 5.70683317 3.25326624 5.70529951 3.2480998 1 P 0 ;0,1=577,2=0.000000
L 5.70529951 3.2480998 5.70491624 3.2434498 1 P 0 ;0,1=577,2=0.000000
L 5.70491624 3.2434498 5.70568337 3.2387999 1 P 0 ;0,1=577,2=0.000000
L 5.70568337 3.2387999 5.70683317 3.23569961 1 P 0 ;0,1=577,2=0.000000
L 5.70683317 3.23569961 5.70913337 3.23259931 1 P 0 ;0,1=577,2=0.000000
L 5.70913337 3.23259931 5.71181683 3.23053307 1 P 0 ;0,1=577,2=0.000000
L 5.71181683 3.23053307 5.71449961 3.2295 1 P 0 ;0,1=577,2=0.000000
L 5.71449961 3.2295 5.71718307 3.2295 1 P 0 ;0,1=577,2=0.000000
L 5.71718307 3.2295 5.71986654 3.23053307 1 P 0 ;0,1=577,2=0.000000
L 5.71986654 3.23053307 5.72216673 3.23208278 1 P 0 ;0,1=577,2=0.000000
L 5.72216673 3.23208278 5.72408366 3.23414892 1 P 0 ;0,1=577,2=0.000000
L 5.73706663 3.23569961 5.73936614 3.23208278 1 P 0 ;0,1=577,2=0.000000
L 5.73936614 3.23208278 5.74243287 3.23001654 1 P 0 ;0,1=577,2=0.000000
L 5.74243287 3.23001654 5.74588356 3.2295 1 P 0 ;0,1=577,2=0.000000
L 5.74588356 3.2295 5.7489503 3.23001654 1 P 0 ;0,1=577,2=0.000000
L 5.7489503 3.23001654 5.75201703 3.23259931 1 P 0 ;0,1=577,2=0.000000
L 5.75201703 3.23259931 5.75393327 3.23569961 1 P 0 ;0,1=577,2=0.000000
L 5.75393327 3.23569961 5.75431654 3.2387999 1 P 0 ;0,1=577,2=0.000000
L 5.75431654 3.2387999 5.75355 3.24241575 1 P 0 ;0,1=577,2=0.000000
L 5.75355 3.24241575 5.75086654 3.24499951 1 P 0 ;0,1=577,2=0.000000
L 5.75086654 3.24499951 5.74818307 3.24603356 1 P 0 ;0,1=577,2=0.000000
L 5.74818307 3.24603356 5.74473307 3.24603356 1 P 0 ;0,1=577,2=0.000000
L 5.74818307 3.24603356 5.75048327 3.24758317 1 P 0 ;0,1=577,2=0.000000
L 5.75048327 3.24758317 5.7524002 3.25016594 1 P 0 ;0,1=577,2=0.000000
L 5.7524002 3.25016594 5.75316673 3.25326624 1 P 0 ;0,1=577,2=0.000000
L 5.75316673 3.25326624 5.7524002 3.25636654 1 P 0 ;0,1=577,2=0.000000
L 5.7524002 3.25636654 5.75048327 3.25894931 1 P 0 ;0,1=577,2=0.000000
L 5.75048327 3.25894931 5.74703327 3.2605 1 P 0 ;0,1=577,2=0.000000
L 5.74703327 3.2605 5.74358337 3.25998337 1 P 0 ;0,1=577,2=0.000000
L 5.74358337 3.25998337 5.74013337 3.25791624 1 P 0 ;0,1=577,2=0.000000
L 5.661 3.547 5.661 3.591 1 P 0 
L 5.661 3.591 5.571 3.591 1 P 0 
L 5.571 3.547 5.661 3.547 1 P 0 
L 5.571 3.591 5.571 3.547 1 P 0 
L 5.58293327 3.53791624 5.58063307 3.53946683 1 P 0 ;0,1=578,2=0.000000
L 5.58063307 3.53946683 5.5779503 3.5405 1 P 0 ;0,1=578,2=0.000000
L 5.5779503 3.5405 5.57488356 3.5405 1 P 0 ;0,1=578,2=0.000000
L 5.57488356 3.5405 5.57143287 3.53894931 1 P 0 ;0,1=578,2=0.000000
L 5.57143287 3.53894931 5.5687501 3.53636654 1 P 0 ;0,1=578,2=0.000000
L 5.5687501 3.53636654 5.56683317 3.53326624 1 P 0 ;0,1=578,2=0.000000
L 5.56683317 3.53326624 5.56529951 3.5280998 1 P 0 ;0,1=578,2=0.000000
L 5.56529951 3.5280998 5.56491624 3.5234498 1 P 0 ;0,1=578,2=0.000000
L 5.56491624 3.5234498 5.56568337 3.5187999 1 P 0 ;0,1=578,2=0.000000
L 5.56568337 3.5187999 5.56683317 3.51569961 1 P 0 ;0,1=578,2=0.000000
L 5.56683317 3.51569961 5.56913337 3.51259931 1 P 0 ;0,1=578,2=0.000000
L 5.56913337 3.51259931 5.57181683 3.51053307 1 P 0 ;0,1=578,2=0.000000
L 5.57181683 3.51053307 5.57449961 3.5095 1 P 0 ;0,1=578,2=0.000000
L 5.57449961 3.5095 5.57718307 3.5095 1 P 0 ;0,1=578,2=0.000000
L 5.57718307 3.5095 5.57986654 3.51053307 1 P 0 ;0,1=578,2=0.000000
L 5.57986654 3.51053307 5.58216673 3.51208278 1 P 0 ;0,1=578,2=0.000000
L 5.58216673 3.51208278 5.58408366 3.51414892 1 P 0 ;0,1=578,2=0.000000
L 5.59821644 3.53533346 5.60051663 3.53843278 1 P 0 ;0,1=578,2=0.000000
L 5.60051663 3.53843278 5.6032001 3.53998337 1 P 0 ;0,1=578,2=0.000000
L 5.6032001 3.53998337 5.60626683 3.5405 1 P 0 ;0,1=578,2=0.000000
L 5.60626683 3.5405 5.6101 3.53946683 1 P 0 ;0,1=578,2=0.000000
L 5.6101 3.53946683 5.61278346 3.53688307 1 P 0 ;0,1=578,2=0.000000
L 5.61278346 3.53688307 5.61355 3.53378376 1 P 0 ;0,1=578,2=0.000000
L 5.61355 3.53378376 5.61316673 3.53068258 1 P 0 ;0,1=578,2=0.000000
L 5.61316673 3.53068258 5.61163307 3.5280998 1 P 0 ;0,1=578,2=0.000000
L 5.61163307 3.5280998 5.60396663 3.52293327 1 P 0 ;0,1=578,2=0.000000
L 5.60396663 3.52293327 5.60051663 3.51931644 1 P 0 ;0,1=578,2=0.000000
L 5.60051663 3.51931644 5.59821644 3.51414892 1 P 0 ;0,1=578,2=0.000000
L 5.59821644 3.51414892 5.5974499 3.5095 1 P 0 ;0,1=578,2=0.000000
L 5.5974499 3.5095 5.61355 3.5095 1 P 0 ;0,1=578,2=0.000000
L 5.786 3.785 5.786 3.829 1 P 0 
L 5.696 3.785 5.786 3.785 1 P 0 
L 5.786 3.829 5.696 3.829 1 P 0 
L 5.696 3.829 5.696 3.785 1 P 0 
L 5.83893327 3.84491624 5.83663307 3.84646683 1 P 0 ;0,1=579,2=0.000000
L 5.83663307 3.84646683 5.8339503 3.8475 1 P 0 ;0,1=579,2=0.000000
L 5.8339503 3.8475 5.83088356 3.8475 1 P 0 ;0,1=579,2=0.000000
L 5.83088356 3.8475 5.82743287 3.84594931 1 P 0 ;0,1=579,2=0.000000
L 5.82743287 3.84594931 5.8247501 3.84336654 1 P 0 ;0,1=579,2=0.000000
L 5.8247501 3.84336654 5.82283317 3.84026624 1 P 0 ;0,1=579,2=0.000000
L 5.82283317 3.84026624 5.82129951 3.8350998 1 P 0 ;0,1=579,2=0.000000
L 5.82129951 3.8350998 5.82091624 3.8304498 1 P 0 ;0,1=579,2=0.000000
L 5.82091624 3.8304498 5.82168337 3.8257999 1 P 0 ;0,1=579,2=0.000000
L 5.82168337 3.8257999 5.82283317 3.82269961 1 P 0 ;0,1=579,2=0.000000
L 5.82283317 3.82269961 5.82513337 3.81959931 1 P 0 ;0,1=579,2=0.000000
L 5.82513337 3.81959931 5.82781683 3.81753307 1 P 0 ;0,1=579,2=0.000000
L 5.82781683 3.81753307 5.83049961 3.8165 1 P 0 ;0,1=579,2=0.000000
L 5.83049961 3.8165 5.83318307 3.8165 1 P 0 ;0,1=579,2=0.000000
L 5.83318307 3.8165 5.83586654 3.81753307 1 P 0 ;0,1=579,2=0.000000
L 5.83586654 3.81753307 5.83816673 3.81908278 1 P 0 ;0,1=579,2=0.000000
L 5.83816673 3.81908278 5.84008366 3.82114892 1 P 0 ;0,1=579,2=0.000000
L 5.85306663 3.82114892 5.85536614 3.81856614 1 P 0 ;0,1=579,2=0.000000
L 5.85536614 3.81856614 5.85804961 3.81701654 1 P 0 ;0,1=579,2=0.000000
L 5.85804961 3.81701654 5.86149961 3.8165 1 P 0 ;0,1=579,2=0.000000
L 5.86149961 3.8165 5.8649503 3.81753307 1 P 0 ;0,1=579,2=0.000000
L 5.8649503 3.81753307 5.86763307 3.81959931 1 P 0 ;0,1=579,2=0.000000
L 5.86763307 3.81959931 5.86955 3.82321614 1 P 0 ;0,1=579,2=0.000000
L 5.86955 3.82321614 5.86993327 3.82734951 1 P 0 ;0,1=579,2=0.000000
L 5.86993327 3.82734951 5.86916673 3.83148287 1 P 0 ;0,1=579,2=0.000000
L 5.86916673 3.83148287 5.8672498 3.83406663 1 P 0 ;0,1=579,2=0.000000
L 5.8672498 3.83406663 5.86456634 3.83613287 1 P 0 ;0,1=579,2=0.000000
L 5.86456634 3.83613287 5.86188356 3.83664941 1 P 0 ;0,1=579,2=0.000000
L 5.86188356 3.83664941 5.8592001 3.83613287 1 P 0 ;0,1=579,2=0.000000
L 5.8592001 3.83613287 5.8557501 3.83406663 1 P 0 ;0,1=579,2=0.000000
L 5.8557501 3.83406663 5.8568999 3.8475 1 P 0 ;0,1=579,2=0.000000
L 5.8568999 3.8475 5.8672498 3.8475 1 P 0 ;0,1=579,2=0.000000
L 5.786 3.835 5.786 3.879 1 P 0 
L 5.696 3.835 5.786 3.835 1 P 0 
L 5.786 3.879 5.696 3.879 1 P 0 
L 5.696 3.879 5.696 3.835 1 P 0 
L 5.83793327 3.88791624 5.83563307 3.88946683 1 P 0 ;0,1=580,2=0.000000
L 5.83563307 3.88946683 5.8329503 3.8905 1 P 0 ;0,1=580,2=0.000000
L 5.8329503 3.8905 5.82988356 3.8905 1 P 0 ;0,1=580,2=0.000000
L 5.82988356 3.8905 5.82643287 3.88894931 1 P 0 ;0,1=580,2=0.000000
L 5.82643287 3.88894931 5.8237501 3.88636654 1 P 0 ;0,1=580,2=0.000000
L 5.8237501 3.88636654 5.82183317 3.88326624 1 P 0 ;0,1=580,2=0.000000
L 5.82183317 3.88326624 5.82029951 3.8780998 1 P 0 ;0,1=580,2=0.000000
L 5.82029951 3.8780998 5.81991624 3.8734498 1 P 0 ;0,1=580,2=0.000000
L 5.81991624 3.8734498 5.82068337 3.8687999 1 P 0 ;0,1=580,2=0.000000
L 5.82068337 3.8687999 5.82183317 3.86569961 1 P 0 ;0,1=580,2=0.000000
L 5.82183317 3.86569961 5.82413337 3.86259931 1 P 0 ;0,1=580,2=0.000000
L 5.82413337 3.86259931 5.82681683 3.86053307 1 P 0 ;0,1=580,2=0.000000
L 5.82681683 3.86053307 5.82949961 3.8595 1 P 0 ;0,1=580,2=0.000000
L 5.82949961 3.8595 5.83218307 3.8595 1 P 0 ;0,1=580,2=0.000000
L 5.83218307 3.8595 5.83486654 3.86053307 1 P 0 ;0,1=580,2=0.000000
L 5.83486654 3.86053307 5.83716673 3.86208278 1 P 0 ;0,1=580,2=0.000000
L 5.83716673 3.86208278 5.83908366 3.86414892 1 P 0 ;0,1=580,2=0.000000
L 5.85973307 3.8595 5.86049961 3.86621614 1 P 0 ;0,1=580,2=0.000000
L 5.86049961 3.86621614 5.8616501 3.87189921 1 P 0 ;0,1=580,2=0.000000
L 5.8616501 3.87189921 5.86318307 3.87706663 1 P 0 ;0,1=580,2=0.000000
L 5.86318307 3.87706663 5.8651 3.8827497 1 P 0 ;0,1=580,2=0.000000
L 5.8651 3.8827497 5.86816673 3.8905 1 P 0 ;0,1=580,2=0.000000
L 5.86816673 3.8905 5.85283317 3.8905 1 P 0 ;0,1=580,2=0.000000
L 0.97448002 2.705 0.88448002 2.705 1 P 0 
L 0.88448002 2.661 0.97448002 2.661 1 P 0 
L 0.97448002 2.661 0.97448002 2.705 1 P 0 
L 0.88448002 2.705 0.88448002 2.661 1 P 0 
L 1.02193327 2.69791624 1.01963307 2.69946683 1 P 0 ;0,1=581,2=0.000000
L 1.01963307 2.69946683 1.0169503 2.7005 1 P 0 ;0,1=581,2=0.000000
L 1.0169503 2.7005 1.01388356 2.7005 1 P 0 ;0,1=581,2=0.000000
L 1.01388356 2.7005 1.01043287 2.69894931 1 P 0 ;0,1=581,2=0.000000
L 1.01043287 2.69894931 1.0077501 2.69636654 1 P 0 ;0,1=581,2=0.000000
L 1.0077501 2.69636654 1.00583317 2.69326624 1 P 0 ;0,1=581,2=0.000000
L 1.00583317 2.69326624 1.00429951 2.6880998 1 P 0 ;0,1=581,2=0.000000
L 1.00429951 2.6880998 1.00391624 2.6834498 1 P 0 ;0,1=581,2=0.000000
L 1.00391624 2.6834498 1.00468337 2.6787999 1 P 0 ;0,1=581,2=0.000000
L 1.00468337 2.6787999 1.00583317 2.67569961 1 P 0 ;0,1=581,2=0.000000
L 1.00583317 2.67569961 1.00813337 2.67259931 1 P 0 ;0,1=581,2=0.000000
L 1.00813337 2.67259931 1.01081683 2.67053307 1 P 0 ;0,1=581,2=0.000000
L 1.01081683 2.67053307 1.01349961 2.6695 1 P 0 ;0,1=581,2=0.000000
L 1.01349961 2.6695 1.01618307 2.6695 1 P 0 ;0,1=581,2=0.000000
L 1.01618307 2.6695 1.01886654 2.67053307 1 P 0 ;0,1=581,2=0.000000
L 1.01886654 2.67053307 1.02116673 2.67208278 1 P 0 ;0,1=581,2=0.000000
L 1.02116673 2.67208278 1.02308366 2.67414892 1 P 0 ;0,1=581,2=0.000000
L 1.03721644 2.69533346 1.03951663 2.69843278 1 P 0 ;0,1=581,2=0.000000
L 1.03951663 2.69843278 1.0422001 2.69998337 1 P 0 ;0,1=581,2=0.000000
L 1.0422001 2.69998337 1.04526683 2.7005 1 P 0 ;0,1=581,2=0.000000
L 1.04526683 2.7005 1.0491 2.69946683 1 P 0 ;0,1=581,2=0.000000
L 1.0491 2.69946683 1.05178346 2.69688307 1 P 0 ;0,1=581,2=0.000000
L 1.05178346 2.69688307 1.05255 2.69378376 1 P 0 ;0,1=581,2=0.000000
L 1.05255 2.69378376 1.05216673 2.69068258 1 P 0 ;0,1=581,2=0.000000
L 1.05216673 2.69068258 1.05063307 2.6880998 1 P 0 ;0,1=581,2=0.000000
L 1.05063307 2.6880998 1.04296663 2.68293327 1 P 0 ;0,1=581,2=0.000000
L 1.04296663 2.68293327 1.03951663 2.67931644 1 P 0 ;0,1=581,2=0.000000
L 1.03951663 2.67931644 1.03721644 2.67414892 1 P 0 ;0,1=581,2=0.000000
L 1.03721644 2.67414892 1.0364499 2.6695 1 P 0 ;0,1=581,2=0.000000
L 1.0364499 2.6695 1.05255 2.6695 1 P 0 ;0,1=581,2=0.000000
L 1.07473307 2.6695 1.07549961 2.67621614 1 P 0 ;0,1=581,2=0.000000
L 1.07549961 2.67621614 1.0766501 2.68189921 1 P 0 ;0,1=581,2=0.000000
L 1.0766501 2.68189921 1.07818307 2.68706663 1 P 0 ;0,1=581,2=0.000000
L 1.07818307 2.68706663 1.0801 2.6927497 1 P 0 ;0,1=581,2=0.000000
L 1.0801 2.6927497 1.08316673 2.7005 1 P 0 ;0,1=581,2=0.000000
L 1.08316673 2.7005 1.06783317 2.7005 1 P 0 ;0,1=581,2=0.000000
L 1.10649961 2.6695 1.10918307 2.67001654 1 P 0 ;0,1=581,2=0.000000
L 1.10918307 2.67001654 1.1122498 2.67156614 1 P 0 ;0,1=581,2=0.000000
L 1.1122498 2.67156614 1.11416673 2.67414892 1 P 0 ;0,1=581,2=0.000000
L 1.11416673 2.67414892 1.11493327 2.67776673 1 P 0 ;0,1=581,2=0.000000
L 1.11493327 2.67776673 1.11416673 2.68138268 1 P 0 ;0,1=581,2=0.000000
L 1.11416673 2.68138268 1.11186654 2.68448287 1 P 0 ;0,1=581,2=0.000000
L 1.11186654 2.68448287 1.10841654 2.68603356 1 P 0 ;0,1=581,2=0.000000
L 1.10841654 2.68603356 1.10458337 2.68603356 1 P 0 ;0,1=581,2=0.000000
L 1.10458337 2.68603356 1.10228317 2.68706663 1 P 0 ;0,1=581,2=0.000000
L 1.10228317 2.68706663 1.10036614 2.68964941 1 P 0 ;0,1=581,2=0.000000
L 1.10036614 2.68964941 1.0995997 2.69326624 1 P 0 ;0,1=581,2=0.000000
L 1.0995997 2.69326624 1.1007501 2.69688307 1 P 0 ;0,1=581,2=0.000000
L 1.1007501 2.69688307 1.10343287 2.69946683 1 P 0 ;0,1=581,2=0.000000
L 1.10343287 2.69946683 1.10649961 2.7005 1 P 0 ;0,1=581,2=0.000000
L 1.10649961 2.7005 1.10956634 2.69946683 1 P 0 ;0,1=581,2=0.000000
L 1.10956634 2.69946683 1.1122498 2.69688307 1 P 0 ;0,1=581,2=0.000000
L 1.1122498 2.69688307 1.1134002 2.69326624 1 P 0 ;0,1=581,2=0.000000
L 1.1134002 2.69326624 1.11263307 2.68964941 1 P 0 ;0,1=581,2=0.000000
L 1.11263307 2.68964941 1.11071673 2.68706663 1 P 0 ;0,1=581,2=0.000000
L 1.11071673 2.68706663 1.10841654 2.68603356 1 P 0 ;0,1=581,2=0.000000
L 1.10841654 2.68603356 1.10458337 2.68603356 1 P 0 ;0,1=581,2=0.000000
L 1.10458337 2.68603356 1.10113337 2.68448287 1 P 0 ;0,1=581,2=0.000000
L 1.10113337 2.68448287 1.09883317 2.68138268 1 P 0 ;0,1=581,2=0.000000
L 1.09883317 2.68138268 1.09806663 2.67776673 1 P 0 ;0,1=581,2=0.000000
L 1.09806663 2.67776673 1.09883317 2.67414892 1 P 0 ;0,1=581,2=0.000000
L 1.09883317 2.67414892 1.1007501 2.67156614 1 P 0 ;0,1=581,2=0.000000
L 1.1007501 2.67156614 1.10381683 2.67001654 1 P 0 ;0,1=581,2=0.000000
L 1.10381683 2.67001654 1.10649961 2.6695 1 P 0 ;0,1=581,2=0.000000
L 0.885 2.706 0.975 2.706 1 P 0 
L 0.975 2.706 0.975 2.75 1 P 0 
L 0.975 2.75 0.885 2.75 1 P 0 
L 0.885 2.75 0.885 2.706 1 P 0 
L 1.02193327 2.74791624 1.01963307 2.74946683 1 P 0 ;0,1=582,2=0.000000
L 1.01963307 2.74946683 1.0169503 2.7505 1 P 0 ;0,1=582,2=0.000000
L 1.0169503 2.7505 1.01388356 2.7505 1 P 0 ;0,1=582,2=0.000000
L 1.01388356 2.7505 1.01043287 2.74894931 1 P 0 ;0,1=582,2=0.000000
L 1.01043287 2.74894931 1.0077501 2.74636654 1 P 0 ;0,1=582,2=0.000000
L 1.0077501 2.74636654 1.00583317 2.74326624 1 P 0 ;0,1=582,2=0.000000
L 1.00583317 2.74326624 1.00429951 2.7380998 1 P 0 ;0,1=582,2=0.000000
L 1.00429951 2.7380998 1.00391624 2.7334498 1 P 0 ;0,1=582,2=0.000000
L 1.00391624 2.7334498 1.00468337 2.7287999 1 P 0 ;0,1=582,2=0.000000
L 1.00468337 2.7287999 1.00583317 2.72569961 1 P 0 ;0,1=582,2=0.000000
L 1.00583317 2.72569961 1.00813337 2.72259931 1 P 0 ;0,1=582,2=0.000000
L 1.00813337 2.72259931 1.01081683 2.72053307 1 P 0 ;0,1=582,2=0.000000
L 1.01081683 2.72053307 1.01349961 2.7195 1 P 0 ;0,1=582,2=0.000000
L 1.01349961 2.7195 1.01618307 2.7195 1 P 0 ;0,1=582,2=0.000000
L 1.01618307 2.7195 1.01886654 2.72053307 1 P 0 ;0,1=582,2=0.000000
L 1.01886654 2.72053307 1.02116673 2.72208278 1 P 0 ;0,1=582,2=0.000000
L 1.02116673 2.72208278 1.02308366 2.72414892 1 P 0 ;0,1=582,2=0.000000
L 1.03721644 2.74533346 1.03951663 2.74843278 1 P 0 ;0,1=582,2=0.000000
L 1.03951663 2.74843278 1.0422001 2.74998337 1 P 0 ;0,1=582,2=0.000000
L 1.0422001 2.74998337 1.04526683 2.7505 1 P 0 ;0,1=582,2=0.000000
L 1.04526683 2.7505 1.0491 2.74946683 1 P 0 ;0,1=582,2=0.000000
L 1.0491 2.74946683 1.05178346 2.74688307 1 P 0 ;0,1=582,2=0.000000
L 1.05178346 2.74688307 1.05255 2.74378376 1 P 0 ;0,1=582,2=0.000000
L 1.05255 2.74378376 1.05216673 2.74068258 1 P 0 ;0,1=582,2=0.000000
L 1.05216673 2.74068258 1.05063307 2.7380998 1 P 0 ;0,1=582,2=0.000000
L 1.05063307 2.7380998 1.04296663 2.73293327 1 P 0 ;0,1=582,2=0.000000
L 1.04296663 2.73293327 1.03951663 2.72931644 1 P 0 ;0,1=582,2=0.000000
L 1.03951663 2.72931644 1.03721644 2.72414892 1 P 0 ;0,1=582,2=0.000000
L 1.03721644 2.72414892 1.0364499 2.7195 1 P 0 ;0,1=582,2=0.000000
L 1.0364499 2.7195 1.05255 2.7195 1 P 0 ;0,1=582,2=0.000000
L 1.07473307 2.7195 1.07549961 2.72621614 1 P 0 ;0,1=582,2=0.000000
L 1.07549961 2.72621614 1.0766501 2.73189921 1 P 0 ;0,1=582,2=0.000000
L 1.0766501 2.73189921 1.07818307 2.73706663 1 P 0 ;0,1=582,2=0.000000
L 1.07818307 2.73706663 1.0801 2.7427497 1 P 0 ;0,1=582,2=0.000000
L 1.0801 2.7427497 1.08316673 2.7505 1 P 0 ;0,1=582,2=0.000000
L 1.08316673 2.7505 1.06783317 2.7505 1 P 0 ;0,1=582,2=0.000000
L 1.10573307 2.7195 1.10649961 2.72621614 1 P 0 ;0,1=582,2=0.000000
L 1.10649961 2.72621614 1.1076501 2.73189921 1 P 0 ;0,1=582,2=0.000000
L 1.1076501 2.73189921 1.10918307 2.73706663 1 P 0 ;0,1=582,2=0.000000
L 1.10918307 2.73706663 1.1111 2.7427497 1 P 0 ;0,1=582,2=0.000000
L 1.1111 2.7427497 1.11416673 2.7505 1 P 0 ;0,1=582,2=0.000000
L 1.11416673 2.7505 1.09883317 2.7505 1 P 0 ;0,1=582,2=0.000000
L 0.973 2.60248002 0.883 2.60248002 1 P 0 
L 0.883 2.60248002 0.883 2.55848002 1 P 0 
L 0.883 2.55848002 0.973 2.55848002 1 P 0 
L 0.973 2.55848002 0.973 2.60248002 1 P 0 
L 1.02693327 2.59291624 1.02463307 2.59446683 1 P 0 ;0,1=583,2=0.000000
L 1.02463307 2.59446683 1.0219503 2.5955 1 P 0 ;0,1=583,2=0.000000
L 1.0219503 2.5955 1.01888356 2.5955 1 P 0 ;0,1=583,2=0.000000
L 1.01888356 2.5955 1.01543287 2.59394931 1 P 0 ;0,1=583,2=0.000000
L 1.01543287 2.59394931 1.0127501 2.59136654 1 P 0 ;0,1=583,2=0.000000
L 1.0127501 2.59136654 1.01083317 2.58826624 1 P 0 ;0,1=583,2=0.000000
L 1.01083317 2.58826624 1.00929951 2.5830998 1 P 0 ;0,1=583,2=0.000000
L 1.00929951 2.5830998 1.00891624 2.5784498 1 P 0 ;0,1=583,2=0.000000
L 1.00891624 2.5784498 1.00968337 2.5737999 1 P 0 ;0,1=583,2=0.000000
L 1.00968337 2.5737999 1.01083317 2.57069961 1 P 0 ;0,1=583,2=0.000000
L 1.01083317 2.57069961 1.01313337 2.56759931 1 P 0 ;0,1=583,2=0.000000
L 1.01313337 2.56759931 1.01581683 2.56553307 1 P 0 ;0,1=583,2=0.000000
L 1.01581683 2.56553307 1.01849961 2.5645 1 P 0 ;0,1=583,2=0.000000
L 1.01849961 2.5645 1.02118307 2.5645 1 P 0 ;0,1=583,2=0.000000
L 1.02118307 2.5645 1.02386654 2.56553307 1 P 0 ;0,1=583,2=0.000000
L 1.02386654 2.56553307 1.02616673 2.56708278 1 P 0 ;0,1=583,2=0.000000
L 1.02616673 2.56708278 1.02808366 2.56914892 1 P 0 ;0,1=583,2=0.000000
L 1.04221644 2.59033346 1.04451663 2.59343278 1 P 0 ;0,1=583,2=0.000000
L 1.04451663 2.59343278 1.0472001 2.59498337 1 P 0 ;0,1=583,2=0.000000
L 1.0472001 2.59498337 1.05026683 2.5955 1 P 0 ;0,1=583,2=0.000000
L 1.05026683 2.5955 1.0541 2.59446683 1 P 0 ;0,1=583,2=0.000000
L 1.0541 2.59446683 1.05678346 2.59188307 1 P 0 ;0,1=583,2=0.000000
L 1.05678346 2.59188307 1.05755 2.58878376 1 P 0 ;0,1=583,2=0.000000
L 1.05755 2.58878376 1.05716673 2.58568258 1 P 0 ;0,1=583,2=0.000000
L 1.05716673 2.58568258 1.05563307 2.5830998 1 P 0 ;0,1=583,2=0.000000
L 1.05563307 2.5830998 1.04796663 2.57793327 1 P 0 ;0,1=583,2=0.000000
L 1.04796663 2.57793327 1.04451663 2.57431644 1 P 0 ;0,1=583,2=0.000000
L 1.04451663 2.57431644 1.04221644 2.56914892 1 P 0 ;0,1=583,2=0.000000
L 1.04221644 2.56914892 1.0414499 2.5645 1 P 0 ;0,1=583,2=0.000000
L 1.0414499 2.5645 1.05755 2.5645 1 P 0 ;0,1=583,2=0.000000
L 1.07973307 2.5645 1.08049961 2.57121614 1 P 0 ;0,1=583,2=0.000000
L 1.08049961 2.57121614 1.0816501 2.57689921 1 P 0 ;0,1=583,2=0.000000
L 1.0816501 2.57689921 1.08318307 2.58206663 1 P 0 ;0,1=583,2=0.000000
L 1.08318307 2.58206663 1.0851 2.5877497 1 P 0 ;0,1=583,2=0.000000
L 1.0851 2.5877497 1.08816673 2.5955 1 P 0 ;0,1=583,2=0.000000
L 1.08816673 2.5955 1.07283317 2.5955 1 P 0 ;0,1=583,2=0.000000
L 1.10421644 2.57741575 1.1068999 2.58103356 1 P 0 ;0,1=583,2=0.000000
L 1.1068999 2.58103356 1.1092001 2.5830998 1 P 0 ;0,1=583,2=0.000000
L 1.1092001 2.5830998 1.11226683 2.58413287 1 P 0 ;0,1=583,2=0.000000
L 1.11226683 2.58413287 1.1149503 2.5830998 1 P 0 ;0,1=583,2=0.000000
L 1.1149503 2.5830998 1.11686654 2.58103356 1 P 0 ;0,1=583,2=0.000000
L 1.11686654 2.58103356 1.1184002 2.57793327 1 P 0 ;0,1=583,2=0.000000
L 1.1184002 2.57793327 1.11878346 2.57431644 1 P 0 ;0,1=583,2=0.000000
L 1.11878346 2.57431644 1.1184002 2.57121614 1 P 0 ;0,1=583,2=0.000000
L 1.1184002 2.57121614 1.11686654 2.56811585 1 P 0 ;0,1=583,2=0.000000
L 1.11686654 2.56811585 1.11456634 2.56553307 1 P 0 ;0,1=583,2=0.000000
L 1.11456634 2.56553307 1.11188356 2.5645 1 P 0 ;0,1=583,2=0.000000
L 1.11188356 2.5645 1.10881683 2.56553307 1 P 0 ;0,1=583,2=0.000000
L 1.10881683 2.56553307 1.10613337 2.56863238 1 P 0 ;0,1=583,2=0.000000
L 1.10613337 2.56863238 1.1045997 2.57328327 1 P 0 ;0,1=583,2=0.000000
L 1.1045997 2.57328327 1.10421644 2.5784498 1 P 0 ;0,1=583,2=0.000000
L 1.10421644 2.5784498 1.10498287 2.58516594 1 P 0 ;0,1=583,2=0.000000
L 1.10498287 2.58516594 1.10613337 2.58878376 1 P 0 ;0,1=583,2=0.000000
L 1.10613337 2.58878376 1.10804961 2.5923997 1 P 0 ;0,1=583,2=0.000000
L 1.10804961 2.5923997 1.11073307 2.59498337 1 P 0 ;0,1=583,2=0.000000
L 1.11073307 2.59498337 1.11341654 2.5955 1 P 0 ;0,1=583,2=0.000000
L 1.11341654 2.5955 1.1161 2.59446683 1 P 0 ;0,1=583,2=0.000000
L 1.1161 2.59446683 1.11801703 2.59188307 1 P 0 ;0,1=583,2=0.000000
L 1.2397 0.5916 1.2397 0.6356 1 P 0 
L 1.1497 0.5916 1.2397 0.5916 1 P 0 
L 1.2397 0.6356 1.1497 0.6356 1 P 0 
L 1.1497 0.6356 1.1497 0.5916 1 P 0 
L 1.12163327 0.83651624 1.11933307 0.83806683 1 P 0 ;0,1=584,2=0.000000
L 1.11933307 0.83806683 1.1166503 0.8391 1 P 0 ;0,1=584,2=0.000000
L 1.1166503 0.8391 1.11358356 0.8391 1 P 0 ;0,1=584,2=0.000000
L 1.11358356 0.8391 1.11013287 0.83754931 1 P 0 ;0,1=584,2=0.000000
L 1.11013287 0.83754931 1.1074501 0.83496654 1 P 0 ;0,1=584,2=0.000000
L 1.1074501 0.83496654 1.10553317 0.83186624 1 P 0 ;0,1=584,2=0.000000
L 1.10553317 0.83186624 1.10399951 0.8266998 1 P 0 ;0,1=584,2=0.000000
L 1.10399951 0.8266998 1.10361624 0.8220498 1 P 0 ;0,1=584,2=0.000000
L 1.10361624 0.8220498 1.10438337 0.8173999 1 P 0 ;0,1=584,2=0.000000
L 1.10438337 0.8173999 1.10553317 0.81429961 1 P 0 ;0,1=584,2=0.000000
L 1.10553317 0.81429961 1.10783337 0.81119931 1 P 0 ;0,1=584,2=0.000000
L 1.10783337 0.81119931 1.11051683 0.80913307 1 P 0 ;0,1=584,2=0.000000
L 1.11051683 0.80913307 1.11319961 0.8081 1 P 0 ;0,1=584,2=0.000000
L 1.11319961 0.8081 1.11588307 0.8081 1 P 0 ;0,1=584,2=0.000000
L 1.11588307 0.8081 1.11856654 0.80913307 1 P 0 ;0,1=584,2=0.000000
L 1.11856654 0.80913307 1.12086673 0.81068278 1 P 0 ;0,1=584,2=0.000000
L 1.12086673 0.81068278 1.12278366 0.81274892 1 P 0 ;0,1=584,2=0.000000
L 1.13691644 0.83393346 1.13921663 0.83703278 1 P 0 ;0,1=584,2=0.000000
L 1.13921663 0.83703278 1.1419001 0.83858337 1 P 0 ;0,1=584,2=0.000000
L 1.1419001 0.83858337 1.14496683 0.8391 1 P 0 ;0,1=584,2=0.000000
L 1.14496683 0.8391 1.1488 0.83806683 1 P 0 ;0,1=584,2=0.000000
L 1.1488 0.83806683 1.15148346 0.83548307 1 P 0 ;0,1=584,2=0.000000
L 1.15148346 0.83548307 1.15225 0.83238376 1 P 0 ;0,1=584,2=0.000000
L 1.15225 0.83238376 1.15186673 0.82928258 1 P 0 ;0,1=584,2=0.000000
L 1.15186673 0.82928258 1.15033307 0.8266998 1 P 0 ;0,1=584,2=0.000000
L 1.15033307 0.8266998 1.14266663 0.82153327 1 P 0 ;0,1=584,2=0.000000
L 1.14266663 0.82153327 1.13921663 0.81791644 1 P 0 ;0,1=584,2=0.000000
L 1.13921663 0.81791644 1.13691644 0.81274892 1 P 0 ;0,1=584,2=0.000000
L 1.13691644 0.81274892 1.1361499 0.8081 1 P 0 ;0,1=584,2=0.000000
L 1.1361499 0.8081 1.15225 0.8081 1 P 0 ;0,1=584,2=0.000000
L 1.16791644 0.83393346 1.17021663 0.83703278 1 P 0 ;0,1=584,2=0.000000
L 1.17021663 0.83703278 1.1729001 0.83858337 1 P 0 ;0,1=584,2=0.000000
L 1.1729001 0.83858337 1.17596683 0.8391 1 P 0 ;0,1=584,2=0.000000
L 1.17596683 0.8391 1.1798 0.83806683 1 P 0 ;0,1=584,2=0.000000
L 1.1798 0.83806683 1.18248346 0.83548307 1 P 0 ;0,1=584,2=0.000000
L 1.18248346 0.83548307 1.18325 0.83238376 1 P 0 ;0,1=584,2=0.000000
L 1.18325 0.83238376 1.18286673 0.82928258 1 P 0 ;0,1=584,2=0.000000
L 1.18286673 0.82928258 1.18133307 0.8266998 1 P 0 ;0,1=584,2=0.000000
L 1.18133307 0.8266998 1.17366663 0.82153327 1 P 0 ;0,1=584,2=0.000000
L 1.17366663 0.82153327 1.17021663 0.81791644 1 P 0 ;0,1=584,2=0.000000
L 1.17021663 0.81791644 1.16791644 0.81274892 1 P 0 ;0,1=584,2=0.000000
L 1.16791644 0.81274892 1.1671499 0.8081 1 P 0 ;0,1=584,2=0.000000
L 1.1671499 0.8081 1.18325 0.8081 1 P 0 ;0,1=584,2=0.000000
L 1.19776663 0.81274892 1.20006614 0.81016614 1 P 0 ;0,1=584,2=0.000000
L 1.20006614 0.81016614 1.20274961 0.80861654 1 P 0 ;0,1=584,2=0.000000
L 1.20274961 0.80861654 1.20619961 0.8081 1 P 0 ;0,1=584,2=0.000000
L 1.20619961 0.8081 1.2096503 0.80913307 1 P 0 ;0,1=584,2=0.000000
L 1.2096503 0.80913307 1.21233307 0.81119931 1 P 0 ;0,1=584,2=0.000000
L 1.21233307 0.81119931 1.21425 0.81481614 1 P 0 ;0,1=584,2=0.000000
L 1.21425 0.81481614 1.21463327 0.81894951 1 P 0 ;0,1=584,2=0.000000
L 1.21463327 0.81894951 1.21386673 0.82308287 1 P 0 ;0,1=584,2=0.000000
L 1.21386673 0.82308287 1.2119498 0.82566663 1 P 0 ;0,1=584,2=0.000000
L 1.2119498 0.82566663 1.20926634 0.82773287 1 P 0 ;0,1=584,2=0.000000
L 1.20926634 0.82773287 1.20658356 0.82824941 1 P 0 ;0,1=584,2=0.000000
L 1.20658356 0.82824941 1.2039001 0.82773287 1 P 0 ;0,1=584,2=0.000000
L 1.2039001 0.82773287 1.2004501 0.82566663 1 P 0 ;0,1=584,2=0.000000
L 1.2004501 0.82566663 1.2015999 0.8391 1 P 0 ;0,1=584,2=0.000000
L 1.2015999 0.8391 1.2119498 0.8391 1 P 0 ;0,1=584,2=0.000000
L 0.737 2.378 0.737 2.468 1 P 0 
L 0.737 2.468 0.693 2.468 1 P 0 
L 0.693 2.468 0.693 2.378 1 P 0 
L 0.693 2.378 0.737 2.378 1 P 0 
L 0.66208376 2.39193327 0.66053317 2.38963307 1 P 0 ;0,1=585,2=270.000000
L 0.66053317 2.38963307 0.6595 2.3869503 1 P 0 ;0,1=585,2=270.000000
L 0.6595 2.3869503 0.6595 2.38388356 1 P 0 ;0,1=585,2=270.000000
L 0.6595 2.38388356 0.66105069 2.38043287 1 P 0 ;0,1=585,2=270.000000
L 0.66105069 2.38043287 0.66363346 2.3777501 1 P 0 ;0,1=585,2=270.000000
L 0.66363346 2.3777501 0.66673376 2.37583317 1 P 0 ;0,1=585,2=270.000000
L 0.66673376 2.37583317 0.6719002 2.37429951 1 P 0 ;0,1=585,2=270.000000
L 0.6719002 2.37429951 0.6765502 2.37391624 1 P 0 ;0,1=585,2=270.000000
L 0.6765502 2.37391624 0.6812001 2.37468337 1 P 0 ;0,1=585,2=270.000000
L 0.6812001 2.37468337 0.68430039 2.37583317 1 P 0 ;0,1=585,2=270.000000
L 0.68430039 2.37583317 0.68740069 2.37813337 1 P 0 ;0,1=585,2=270.000000
L 0.68740069 2.37813337 0.68946693 2.38081683 1 P 0 ;0,1=585,2=270.000000
L 0.68946693 2.38081683 0.6905 2.38349961 1 P 0 ;0,1=585,2=270.000000
L 0.6905 2.38349961 0.6905 2.38618307 1 P 0 ;0,1=585,2=270.000000
L 0.6905 2.38618307 0.68946693 2.38886654 1 P 0 ;0,1=585,2=270.000000
L 0.68946693 2.38886654 0.68791722 2.39116673 1 P 0 ;0,1=585,2=270.000000
L 0.68791722 2.39116673 0.68585108 2.39308366 1 P 0 ;0,1=585,2=270.000000
L 0.68430039 2.40606663 0.68791722 2.40836614 1 P 0 ;0,1=585,2=270.000000
L 0.68791722 2.40836614 0.68998346 2.41143287 1 P 0 ;0,1=585,2=270.000000
L 0.68998346 2.41143287 0.6905 2.41488356 1 P 0 ;0,1=585,2=270.000000
L 0.6905 2.41488356 0.68998346 2.4179503 1 P 0 ;0,1=585,2=270.000000
L 0.68998346 2.4179503 0.68740069 2.42101703 1 P 0 ;0,1=585,2=270.000000
L 0.68740069 2.42101703 0.68430039 2.42293327 1 P 0 ;0,1=585,2=270.000000
L 0.68430039 2.42293327 0.6812001 2.42331654 1 P 0 ;0,1=585,2=270.000000
L 0.6812001 2.42331654 0.67758425 2.42255 1 P 0 ;0,1=585,2=270.000000
L 0.67758425 2.42255 0.67500049 2.41986654 1 P 0 ;0,1=585,2=270.000000
L 0.67500049 2.41986654 0.67396644 2.41718307 1 P 0 ;0,1=585,2=270.000000
L 0.67396644 2.41718307 0.67396644 2.41373307 1 P 0 ;0,1=585,2=270.000000
L 0.67396644 2.41718307 0.67241683 2.41948327 1 P 0 ;0,1=585,2=270.000000
L 0.67241683 2.41948327 0.66983406 2.4214002 1 P 0 ;0,1=585,2=270.000000
L 0.66983406 2.4214002 0.66673376 2.42216673 1 P 0 ;0,1=585,2=270.000000
L 0.66673376 2.42216673 0.66363346 2.4214002 1 P 0 ;0,1=585,2=270.000000
L 0.66363346 2.4214002 0.66105069 2.41948327 1 P 0 ;0,1=585,2=270.000000
L 0.66105069 2.41948327 0.6595 2.41603327 1 P 0 ;0,1=585,2=270.000000
L 0.6595 2.41603327 0.66001663 2.41258337 1 P 0 ;0,1=585,2=270.000000
L 0.66001663 2.41258337 0.66208376 2.40913337 1 P 0 ;0,1=585,2=270.000000
L 0.6905 2.44549961 0.6595 2.44549961 1 P 0 ;0,1=585,2=270.000000
L 0.6595 2.44549961 0.6656997 2.4408999 1 P 0 ;0,1=585,2=270.000000
L 0.6905 2.4408999 0.6905 2.45009931 1 P 0 ;0,1=585,2=270.000000
L 0.66466654 2.46921644 0.66156722 2.47151663 1 P 0 ;0,1=585,2=270.000000
L 0.66156722 2.47151663 0.66001663 2.4742001 1 P 0 ;0,1=585,2=270.000000
L 0.66001663 2.4742001 0.6595 2.47726683 1 P 0 ;0,1=585,2=270.000000
L 0.6595 2.47726683 0.66053317 2.4811 1 P 0 ;0,1=585,2=270.000000
L 0.66053317 2.4811 0.66311693 2.48378346 1 P 0 ;0,1=585,2=270.000000
L 0.66311693 2.48378346 0.66621624 2.48455 1 P 0 ;0,1=585,2=270.000000
L 0.66621624 2.48455 0.66931742 2.48416673 1 P 0 ;0,1=585,2=270.000000
L 0.66931742 2.48416673 0.6719002 2.48263307 1 P 0 ;0,1=585,2=270.000000
L 0.6719002 2.48263307 0.67706673 2.47496663 1 P 0 ;0,1=585,2=270.000000
L 0.67706673 2.47496663 0.68068356 2.47151663 1 P 0 ;0,1=585,2=270.000000
L 0.68068356 2.47151663 0.68585108 2.46921644 1 P 0 ;0,1=585,2=270.000000
L 0.68585108 2.46921644 0.6905 2.4684499 1 P 0 ;0,1=585,2=270.000000
L 0.6905 2.4684499 0.6905 2.48455 1 P 0 ;0,1=585,2=270.000000
L 0.692 2.318 0.692 2.228 1 P 0 
L 0.692 2.228 0.736 2.228 1 P 0 
L 0.736 2.228 0.736 2.318 1 P 0 
L 0.736 2.318 0.692 2.318 1 P 0 
L 0.63286663 2.34541634 0.63126644 2.34666683 1 P 0 ;0,1=586,2=0.000000
L 0.63126644 2.34666683 0.6294002 2.3475 1 P 0 ;0,1=586,2=0.000000
L 0.6294002 2.3475 0.62726683 2.3475 1 P 0 ;0,1=586,2=0.000000
L 0.62726683 2.3475 0.62486634 2.34624941 1 P 0 ;0,1=586,2=0.000000
L 0.62486634 2.34624941 0.6230001 2.34416654 1 P 0 ;0,1=586,2=0.000000
L 0.6230001 2.34416654 0.62166654 2.34166634 1 P 0 ;0,1=586,2=0.000000
L 0.62166654 2.34166634 0.62059961 2.3374998 1 P 0 ;0,1=586,2=0.000000
L 0.62059961 2.3374998 0.62033297 2.3337498 1 P 0 ;0,1=586,2=0.000000
L 0.62033297 2.3337498 0.62086673 2.3299999 1 P 0 ;0,1=586,2=0.000000
L 0.62086673 2.3299999 0.62166654 2.32749961 1 P 0 ;0,1=586,2=0.000000
L 0.62166654 2.32749961 0.62326663 2.32499941 1 P 0 ;0,1=586,2=0.000000
L 0.62326663 2.32499941 0.62513346 2.32333307 1 P 0 ;0,1=586,2=0.000000
L 0.62513346 2.32333307 0.6269997 2.3225 1 P 0 ;0,1=586,2=0.000000
L 0.6269997 2.3225 0.62886644 2.3225 1 P 0 ;0,1=586,2=0.000000
L 0.62886644 2.3225 0.63073327 2.32333307 1 P 0 ;0,1=586,2=0.000000
L 0.63073327 2.32333307 0.63233337 2.32458287 1 P 0 ;0,1=586,2=0.000000
L 0.63233337 2.32458287 0.63366693 2.32624911 1 P 0 ;0,1=586,2=0.000000
L 0.64313327 2.32749961 0.64473297 2.32458287 1 P 0 ;0,1=586,2=0.000000
L 0.64473297 2.32458287 0.64686634 2.32291654 1 P 0 ;0,1=586,2=0.000000
L 0.64686634 2.32291654 0.64926683 2.3225 1 P 0 ;0,1=586,2=0.000000
L 0.64926683 2.3225 0.6514002 2.32291654 1 P 0 ;0,1=586,2=0.000000
L 0.6514002 2.32291654 0.65353356 2.32499941 1 P 0 ;0,1=586,2=0.000000
L 0.65353356 2.32499941 0.65486663 2.32749961 1 P 0 ;0,1=586,2=0.000000
L 0.65486663 2.32749961 0.65513317 2.3299999 1 P 0 ;0,1=586,2=0.000000
L 0.65513317 2.3299999 0.6546 2.33291594 1 P 0 ;0,1=586,2=0.000000
L 0.6546 2.33291594 0.65273327 2.33499961 1 P 0 ;0,1=586,2=0.000000
L 0.65273327 2.33499961 0.65086644 2.33583346 1 P 0 ;0,1=586,2=0.000000
L 0.65086644 2.33583346 0.64846654 2.33583346 1 P 0 ;0,1=586,2=0.000000
L 0.65086644 2.33583346 0.65246663 2.33708327 1 P 0 ;0,1=586,2=0.000000
L 0.65246663 2.33708327 0.6538001 2.33916614 1 P 0 ;0,1=586,2=0.000000
L 0.6538001 2.33916614 0.65433337 2.34166634 1 P 0 ;0,1=586,2=0.000000
L 0.65433337 2.34166634 0.6538001 2.34416654 1 P 0 ;0,1=586,2=0.000000
L 0.6538001 2.34416654 0.65246663 2.34624941 1 P 0 ;0,1=586,2=0.000000
L 0.65246663 2.34624941 0.65006663 2.3475 1 P 0 ;0,1=586,2=0.000000
L 0.65006663 2.3475 0.64766663 2.34708337 1 P 0 ;0,1=586,2=0.000000
L 0.64766663 2.34708337 0.64526663 2.34541634 1 P 0 ;0,1=586,2=0.000000
L 0.6709997 2.3225 0.6709997 2.3475 1 P 0 ;0,1=586,2=0.000000
L 0.6709997 2.3475 0.6677999 2.3425003 1 P 0 ;0,1=586,2=0.000000
L 0.6677999 2.3225 0.67419951 2.3225 1 P 0 ;0,1=586,2=0.000000
L 0.68713327 2.32749961 0.68873297 2.32458287 1 P 0 ;0,1=586,2=0.000000
L 0.68873297 2.32458287 0.69086634 2.32291654 1 P 0 ;0,1=586,2=0.000000
L 0.69086634 2.32291654 0.69326683 2.3225 1 P 0 ;0,1=586,2=0.000000
L 0.69326683 2.3225 0.6954002 2.32291654 1 P 0 ;0,1=586,2=0.000000
L 0.6954002 2.32291654 0.69753356 2.32499941 1 P 0 ;0,1=586,2=0.000000
L 0.69753356 2.32499941 0.69886663 2.32749961 1 P 0 ;0,1=586,2=0.000000
L 0.69886663 2.32749961 0.69913317 2.3299999 1 P 0 ;0,1=586,2=0.000000
L 0.69913317 2.3299999 0.6986 2.33291594 1 P 0 ;0,1=586,2=0.000000
L 0.6986 2.33291594 0.69673327 2.33499961 1 P 0 ;0,1=586,2=0.000000
L 0.69673327 2.33499961 0.69486644 2.33583346 1 P 0 ;0,1=586,2=0.000000
L 0.69486644 2.33583346 0.69246654 2.33583346 1 P 0 ;0,1=586,2=0.000000
L 0.69486644 2.33583346 0.69646663 2.33708327 1 P 0 ;0,1=586,2=0.000000
L 0.69646663 2.33708327 0.6978001 2.33916614 1 P 0 ;0,1=586,2=0.000000
L 0.6978001 2.33916614 0.69833337 2.34166634 1 P 0 ;0,1=586,2=0.000000
L 0.69833337 2.34166634 0.6978001 2.34416654 1 P 0 ;0,1=586,2=0.000000
L 0.6978001 2.34416654 0.69646663 2.34624941 1 P 0 ;0,1=586,2=0.000000
L 0.69646663 2.34624941 0.69406663 2.3475 1 P 0 ;0,1=586,2=0.000000
L 0.69406663 2.3475 0.69166663 2.34708337 1 P 0 ;0,1=586,2=0.000000
L 0.69166663 2.34708337 0.68926663 2.34541634 1 P 0 ;0,1=586,2=0.000000
L 1.716 4.113 1.626 4.113 1 P 0 
L 1.626 4.069 1.716 4.069 1 P 0 
L 1.716 4.069 1.716 4.113 1 P 0 
L 1.626 4.113 1.626 4.069 1 P 0 
L 1.80243327 4.16841624 1.80013307 4.16996683 1 P 0 ;0,1=587,2=0.000000
L 1.80013307 4.16996683 1.7974503 4.171 1 P 0 ;0,1=587,2=0.000000
L 1.7974503 4.171 1.79438356 4.171 1 P 0 ;0,1=587,2=0.000000
L 1.79438356 4.171 1.79093287 4.16944931 1 P 0 ;0,1=587,2=0.000000
L 1.79093287 4.16944931 1.7882501 4.16686654 1 P 0 ;0,1=587,2=0.000000
L 1.7882501 4.16686654 1.78633317 4.16376624 1 P 0 ;0,1=587,2=0.000000
L 1.78633317 4.16376624 1.78479951 4.1585998 1 P 0 ;0,1=587,2=0.000000
L 1.78479951 4.1585998 1.78441624 4.1539498 1 P 0 ;0,1=587,2=0.000000
L 1.78441624 4.1539498 1.78518337 4.1492999 1 P 0 ;0,1=587,2=0.000000
L 1.78518337 4.1492999 1.78633317 4.14619961 1 P 0 ;0,1=587,2=0.000000
L 1.78633317 4.14619961 1.78863337 4.14309931 1 P 0 ;0,1=587,2=0.000000
L 1.78863337 4.14309931 1.79131683 4.14103307 1 P 0 ;0,1=587,2=0.000000
L 1.79131683 4.14103307 1.79399961 4.14 1 P 0 ;0,1=587,2=0.000000
L 1.79399961 4.14 1.79668307 4.14 1 P 0 ;0,1=587,2=0.000000
L 1.79668307 4.14 1.79936654 4.14103307 1 P 0 ;0,1=587,2=0.000000
L 1.79936654 4.14103307 1.80166673 4.14258278 1 P 0 ;0,1=587,2=0.000000
L 1.80166673 4.14258278 1.80358366 4.14464892 1 P 0 ;0,1=587,2=0.000000
L 1.81656663 4.14619961 1.81886614 4.14258278 1 P 0 ;0,1=587,2=0.000000
L 1.81886614 4.14258278 1.82193287 4.14051654 1 P 0 ;0,1=587,2=0.000000
L 1.82193287 4.14051654 1.82538356 4.14 1 P 0 ;0,1=587,2=0.000000
L 1.82538356 4.14 1.8284503 4.14051654 1 P 0 ;0,1=587,2=0.000000
L 1.8284503 4.14051654 1.83151703 4.14309931 1 P 0 ;0,1=587,2=0.000000
L 1.83151703 4.14309931 1.83343327 4.14619961 1 P 0 ;0,1=587,2=0.000000
L 1.83343327 4.14619961 1.83381654 4.1492999 1 P 0 ;0,1=587,2=0.000000
L 1.83381654 4.1492999 1.83305 4.15291575 1 P 0 ;0,1=587,2=0.000000
L 1.83305 4.15291575 1.83036654 4.15549951 1 P 0 ;0,1=587,2=0.000000
L 1.83036654 4.15549951 1.82768307 4.15653356 1 P 0 ;0,1=587,2=0.000000
L 1.82768307 4.15653356 1.82423307 4.15653356 1 P 0 ;0,1=587,2=0.000000
L 1.82768307 4.15653356 1.82998327 4.15808317 1 P 0 ;0,1=587,2=0.000000
L 1.82998327 4.15808317 1.8319002 4.16066594 1 P 0 ;0,1=587,2=0.000000
L 1.8319002 4.16066594 1.83266673 4.16376624 1 P 0 ;0,1=587,2=0.000000
L 1.83266673 4.16376624 1.8319002 4.16686654 1 P 0 ;0,1=587,2=0.000000
L 1.8319002 4.16686654 1.82998327 4.16944931 1 P 0 ;0,1=587,2=0.000000
L 1.82998327 4.16944931 1.82653327 4.171 1 P 0 ;0,1=587,2=0.000000
L 1.82653327 4.171 1.82308337 4.17048337 1 P 0 ;0,1=587,2=0.000000
L 1.82308337 4.17048337 1.81963337 4.16841624 1 P 0 ;0,1=587,2=0.000000
L 1.84756663 4.14619961 1.84986614 4.14258278 1 P 0 ;0,1=587,2=0.000000
L 1.84986614 4.14258278 1.85293287 4.14051654 1 P 0 ;0,1=587,2=0.000000
L 1.85293287 4.14051654 1.85638356 4.14 1 P 0 ;0,1=587,2=0.000000
L 1.85638356 4.14 1.8594503 4.14051654 1 P 0 ;0,1=587,2=0.000000
L 1.8594503 4.14051654 1.86251703 4.14309931 1 P 0 ;0,1=587,2=0.000000
L 1.86251703 4.14309931 1.86443327 4.14619961 1 P 0 ;0,1=587,2=0.000000
L 1.86443327 4.14619961 1.86481654 4.1492999 1 P 0 ;0,1=587,2=0.000000
L 1.86481654 4.1492999 1.86405 4.15291575 1 P 0 ;0,1=587,2=0.000000
L 1.86405 4.15291575 1.86136654 4.15549951 1 P 0 ;0,1=587,2=0.000000
L 1.86136654 4.15549951 1.85868307 4.15653356 1 P 0 ;0,1=587,2=0.000000
L 1.85868307 4.15653356 1.85523307 4.15653356 1 P 0 ;0,1=587,2=0.000000
L 1.85868307 4.15653356 1.86098327 4.15808317 1 P 0 ;0,1=587,2=0.000000
L 1.86098327 4.15808317 1.8629002 4.16066594 1 P 0 ;0,1=587,2=0.000000
L 1.8629002 4.16066594 1.86366673 4.16376624 1 P 0 ;0,1=587,2=0.000000
L 1.86366673 4.16376624 1.8629002 4.16686654 1 P 0 ;0,1=587,2=0.000000
L 1.8629002 4.16686654 1.86098327 4.16944931 1 P 0 ;0,1=587,2=0.000000
L 1.86098327 4.16944931 1.85753327 4.171 1 P 0 ;0,1=587,2=0.000000
L 1.85753327 4.171 1.85408337 4.17048337 1 P 0 ;0,1=587,2=0.000000
L 1.85408337 4.17048337 1.85063337 4.16841624 1 P 0 ;0,1=587,2=0.000000
L 1.736 3.819 1.736 3.863 1 P 0 
L 1.646 3.819 1.736 3.819 1 P 0 
L 1.736 3.863 1.646 3.863 1 P 0 
L 1.646 3.863 1.646 3.819 1 P 0 
L 1.69343327 3.67491624 1.69113307 3.67646683 1 P 0 ;0,1=588,2=0.000000
L 1.69113307 3.67646683 1.6884503 3.6775 1 P 0 ;0,1=588,2=0.000000
L 1.6884503 3.6775 1.68538356 3.6775 1 P 0 ;0,1=588,2=0.000000
L 1.68538356 3.6775 1.68193287 3.67594931 1 P 0 ;0,1=588,2=0.000000
L 1.68193287 3.67594931 1.6792501 3.67336654 1 P 0 ;0,1=588,2=0.000000
L 1.6792501 3.67336654 1.67733317 3.67026624 1 P 0 ;0,1=588,2=0.000000
L 1.67733317 3.67026624 1.67579951 3.6650998 1 P 0 ;0,1=588,2=0.000000
L 1.67579951 3.6650998 1.67541624 3.6604498 1 P 0 ;0,1=588,2=0.000000
L 1.67541624 3.6604498 1.67618337 3.6557999 1 P 0 ;0,1=588,2=0.000000
L 1.67618337 3.6557999 1.67733317 3.65269961 1 P 0 ;0,1=588,2=0.000000
L 1.67733317 3.65269961 1.67963337 3.64959931 1 P 0 ;0,1=588,2=0.000000
L 1.67963337 3.64959931 1.68231683 3.64753307 1 P 0 ;0,1=588,2=0.000000
L 1.68231683 3.64753307 1.68499961 3.6465 1 P 0 ;0,1=588,2=0.000000
L 1.68499961 3.6465 1.68768307 3.6465 1 P 0 ;0,1=588,2=0.000000
L 1.68768307 3.6465 1.69036654 3.64753307 1 P 0 ;0,1=588,2=0.000000
L 1.69036654 3.64753307 1.69266673 3.64908278 1 P 0 ;0,1=588,2=0.000000
L 1.69266673 3.64908278 1.69458366 3.65114892 1 P 0 ;0,1=588,2=0.000000
L 1.7206 3.6465 1.7206 3.6775 1 P 0 ;0,1=588,2=0.000000
L 1.7206 3.6775 1.70641624 3.65528327 1 P 0 ;0,1=588,2=0.000000
L 1.70641624 3.65528327 1.72558366 3.65528327 1 P 0 ;0,1=588,2=0.000000
L 1.74699961 3.6465 1.74699961 3.6775 1 P 0 ;0,1=588,2=0.000000
L 1.74699961 3.6775 1.7423999 3.6713003 1 P 0 ;0,1=588,2=0.000000
L 1.7423999 3.6465 1.75159931 3.6465 1 P 0 ;0,1=588,2=0.000000
L 1.501 3.968 1.411 3.968 1 P 0 
L 1.411 3.968 1.411 3.924 1 P 0 
L 1.411 3.924 1.501 3.924 1 P 0 
L 1.501 3.924 1.501 3.968 1 P 0 
L 1.27343327 4.03391624 1.27113307 4.03546683 1 P 0 ;0,1=589,2=0.000000
L 1.27113307 4.03546683 1.2684503 4.0365 1 P 0 ;0,1=589,2=0.000000
L 1.2684503 4.0365 1.26538356 4.0365 1 P 0 ;0,1=589,2=0.000000
L 1.26538356 4.0365 1.26193287 4.03494931 1 P 0 ;0,1=589,2=0.000000
L 1.26193287 4.03494931 1.2592501 4.03236654 1 P 0 ;0,1=589,2=0.000000
L 1.2592501 4.03236654 1.25733317 4.02926624 1 P 0 ;0,1=589,2=0.000000
L 1.25733317 4.02926624 1.25579951 4.0240998 1 P 0 ;0,1=589,2=0.000000
L 1.25579951 4.0240998 1.25541624 4.0194498 1 P 0 ;0,1=589,2=0.000000
L 1.25541624 4.0194498 1.25618337 4.0147999 1 P 0 ;0,1=589,2=0.000000
L 1.25618337 4.0147999 1.25733317 4.01169961 1 P 0 ;0,1=589,2=0.000000
L 1.25733317 4.01169961 1.25963337 4.00859931 1 P 0 ;0,1=589,2=0.000000
L 1.25963337 4.00859931 1.26231683 4.00653307 1 P 0 ;0,1=589,2=0.000000
L 1.26231683 4.00653307 1.26499961 4.0055 1 P 0 ;0,1=589,2=0.000000
L 1.26499961 4.0055 1.26768307 4.0055 1 P 0 ;0,1=589,2=0.000000
L 1.26768307 4.0055 1.27036654 4.00653307 1 P 0 ;0,1=589,2=0.000000
L 1.27036654 4.00653307 1.27266673 4.00808278 1 P 0 ;0,1=589,2=0.000000
L 1.27266673 4.00808278 1.27458366 4.01014892 1 P 0 ;0,1=589,2=0.000000
L 1.28871644 4.03133346 1.29101663 4.03443278 1 P 0 ;0,1=589,2=0.000000
L 1.29101663 4.03443278 1.2937001 4.03598337 1 P 0 ;0,1=589,2=0.000000
L 1.2937001 4.03598337 1.29676683 4.0365 1 P 0 ;0,1=589,2=0.000000
L 1.29676683 4.0365 1.3006 4.03546683 1 P 0 ;0,1=589,2=0.000000
L 1.3006 4.03546683 1.30328346 4.03288307 1 P 0 ;0,1=589,2=0.000000
L 1.30328346 4.03288307 1.30405 4.02978376 1 P 0 ;0,1=589,2=0.000000
L 1.30405 4.02978376 1.30366673 4.02668258 1 P 0 ;0,1=589,2=0.000000
L 1.30366673 4.02668258 1.30213307 4.0240998 1 P 0 ;0,1=589,2=0.000000
L 1.30213307 4.0240998 1.29446663 4.01893327 1 P 0 ;0,1=589,2=0.000000
L 1.29446663 4.01893327 1.29101663 4.01531644 1 P 0 ;0,1=589,2=0.000000
L 1.29101663 4.01531644 1.28871644 4.01014892 1 P 0 ;0,1=589,2=0.000000
L 1.28871644 4.01014892 1.2879499 4.0055 1 P 0 ;0,1=589,2=0.000000
L 1.2879499 4.0055 1.30405 4.0055 1 P 0 ;0,1=589,2=0.000000
L 1.32048287 4.00911585 1.32316634 4.00653307 1 P 0 ;0,1=589,2=0.000000
L 1.32316634 4.00653307 1.32623307 4.0055 1 P 0 ;0,1=589,2=0.000000
L 1.32623307 4.0055 1.3292998 4.00653307 1 P 0 ;0,1=589,2=0.000000
L 1.3292998 4.00653307 1.33198327 4.00963238 1 P 0 ;0,1=589,2=0.000000
L 1.33198327 4.00963238 1.3339002 4.01428327 1 P 0 ;0,1=589,2=0.000000
L 1.3339002 4.01428327 1.33466673 4.01893327 1 P 0 ;0,1=589,2=0.000000
L 1.33466673 4.01893327 1.33466673 4.02461634 1 P 0 ;0,1=589,2=0.000000
L 1.33466673 4.02461634 1.3339002 4.02926624 1 P 0 ;0,1=589,2=0.000000
L 1.3339002 4.02926624 1.33198327 4.0333997 1 P 0 ;0,1=589,2=0.000000
L 1.33198327 4.0333997 1.32968307 4.03546683 1 P 0 ;0,1=589,2=0.000000
L 1.32968307 4.03546683 1.32699961 4.0365 1 P 0 ;0,1=589,2=0.000000
L 1.32699961 4.0365 1.32393287 4.03546683 1 P 0 ;0,1=589,2=0.000000
L 1.32393287 4.03546683 1.32163337 4.0333997 1 P 0 ;0,1=589,2=0.000000
L 1.32163337 4.0333997 1.3200997 4.0303003 1 P 0 ;0,1=589,2=0.000000
L 1.3200997 4.0303003 1.31933317 4.02616594 1 P 0 ;0,1=589,2=0.000000
L 1.31933317 4.02616594 1.3200997 4.0225501 1 P 0 ;0,1=589,2=0.000000
L 1.3200997 4.0225501 1.32201663 4.01893327 1 P 0 ;0,1=589,2=0.000000
L 1.32201663 4.01893327 1.32431683 4.01686604 1 P 0 ;0,1=589,2=0.000000
L 1.32431683 4.01686604 1.32699961 4.01634951 1 P 0 ;0,1=589,2=0.000000
L 1.32699961 4.01634951 1.33006634 4.01738268 1 P 0 ;0,1=589,2=0.000000
L 1.33006634 4.01738268 1.33236654 4.01996634 1 P 0 ;0,1=589,2=0.000000
L 1.33236654 4.01996634 1.33466673 4.02461634 1 P 0 ;0,1=589,2=0.000000
L 1.501 4.013 1.411 4.013 1 P 0 
L 1.411 4.013 1.411 3.969 1 P 0 
L 1.411 3.969 1.501 3.969 1 P 0 
L 1.501 3.969 1.501 4.013 1 P 0 
L 1.27343327 4.07391624 1.27113307 4.07546683 1 P 0 ;0,1=590,2=0.000000
L 1.27113307 4.07546683 1.2684503 4.0765 1 P 0 ;0,1=590,2=0.000000
L 1.2684503 4.0765 1.26538356 4.0765 1 P 0 ;0,1=590,2=0.000000
L 1.26538356 4.0765 1.26193287 4.07494931 1 P 0 ;0,1=590,2=0.000000
L 1.26193287 4.07494931 1.2592501 4.07236654 1 P 0 ;0,1=590,2=0.000000
L 1.2592501 4.07236654 1.25733317 4.06926624 1 P 0 ;0,1=590,2=0.000000
L 1.25733317 4.06926624 1.25579951 4.0640998 1 P 0 ;0,1=590,2=0.000000
L 1.25579951 4.0640998 1.25541624 4.0594498 1 P 0 ;0,1=590,2=0.000000
L 1.25541624 4.0594498 1.25618337 4.0547999 1 P 0 ;0,1=590,2=0.000000
L 1.25618337 4.0547999 1.25733317 4.05169961 1 P 0 ;0,1=590,2=0.000000
L 1.25733317 4.05169961 1.25963337 4.04859931 1 P 0 ;0,1=590,2=0.000000
L 1.25963337 4.04859931 1.26231683 4.04653307 1 P 0 ;0,1=590,2=0.000000
L 1.26231683 4.04653307 1.26499961 4.0455 1 P 0 ;0,1=590,2=0.000000
L 1.26499961 4.0455 1.26768307 4.0455 1 P 0 ;0,1=590,2=0.000000
L 1.26768307 4.0455 1.27036654 4.04653307 1 P 0 ;0,1=590,2=0.000000
L 1.27036654 4.04653307 1.27266673 4.04808278 1 P 0 ;0,1=590,2=0.000000
L 1.27266673 4.04808278 1.27458366 4.05014892 1 P 0 ;0,1=590,2=0.000000
L 1.28756663 4.05169961 1.28986614 4.04808278 1 P 0 ;0,1=590,2=0.000000
L 1.28986614 4.04808278 1.29293287 4.04601654 1 P 0 ;0,1=590,2=0.000000
L 1.29293287 4.04601654 1.29638356 4.0455 1 P 0 ;0,1=590,2=0.000000
L 1.29638356 4.0455 1.2994503 4.04601654 1 P 0 ;0,1=590,2=0.000000
L 1.2994503 4.04601654 1.30251703 4.04859931 1 P 0 ;0,1=590,2=0.000000
L 1.30251703 4.04859931 1.30443327 4.05169961 1 P 0 ;0,1=590,2=0.000000
L 1.30443327 4.05169961 1.30481654 4.0547999 1 P 0 ;0,1=590,2=0.000000
L 1.30481654 4.0547999 1.30405 4.05841575 1 P 0 ;0,1=590,2=0.000000
L 1.30405 4.05841575 1.30136654 4.06099951 1 P 0 ;0,1=590,2=0.000000
L 1.30136654 4.06099951 1.29868307 4.06203356 1 P 0 ;0,1=590,2=0.000000
L 1.29868307 4.06203356 1.29523307 4.06203356 1 P 0 ;0,1=590,2=0.000000
L 1.29868307 4.06203356 1.30098327 4.06358317 1 P 0 ;0,1=590,2=0.000000
L 1.30098327 4.06358317 1.3029002 4.06616594 1 P 0 ;0,1=590,2=0.000000
L 1.3029002 4.06616594 1.30366673 4.06926624 1 P 0 ;0,1=590,2=0.000000
L 1.30366673 4.06926624 1.3029002 4.07236654 1 P 0 ;0,1=590,2=0.000000
L 1.3029002 4.07236654 1.30098327 4.07494931 1 P 0 ;0,1=590,2=0.000000
L 1.30098327 4.07494931 1.29753327 4.0765 1 P 0 ;0,1=590,2=0.000000
L 1.29753327 4.0765 1.29408337 4.07598337 1 P 0 ;0,1=590,2=0.000000
L 1.29408337 4.07598337 1.29063337 4.07391624 1 P 0 ;0,1=590,2=0.000000
L 1.32699961 4.0455 1.32699961 4.0765 1 P 0 ;0,1=590,2=0.000000
L 1.32699961 4.0765 1.3223999 4.0703003 1 P 0 ;0,1=590,2=0.000000
L 1.3223999 4.0455 1.33159931 4.0455 1 P 0 ;0,1=590,2=0.000000
L 1.467 3.77 1.423 3.77 1 P 0 
L 1.423 3.77 1.423 3.68 1 P 0 
L 1.423 3.68 1.467 3.68 1 P 0 
L 1.467 3.68 1.467 3.77 1 P 0 
L 1.50243327 3.59291624 1.50013307 3.59446683 1 P 0 ;0,1=591,2=0.000000
L 1.50013307 3.59446683 1.4974503 3.5955 1 P 0 ;0,1=591,2=0.000000
L 1.4974503 3.5955 1.49438356 3.5955 1 P 0 ;0,1=591,2=0.000000
L 1.49438356 3.5955 1.49093287 3.59394931 1 P 0 ;0,1=591,2=0.000000
L 1.49093287 3.59394931 1.4882501 3.59136654 1 P 0 ;0,1=591,2=0.000000
L 1.4882501 3.59136654 1.48633317 3.58826624 1 P 0 ;0,1=591,2=0.000000
L 1.48633317 3.58826624 1.48479951 3.5830998 1 P 0 ;0,1=591,2=0.000000
L 1.48479951 3.5830998 1.48441624 3.5784498 1 P 0 ;0,1=591,2=0.000000
L 1.48441624 3.5784498 1.48518337 3.5737999 1 P 0 ;0,1=591,2=0.000000
L 1.48518337 3.5737999 1.48633317 3.57069961 1 P 0 ;0,1=591,2=0.000000
L 1.48633317 3.57069961 1.48863337 3.56759931 1 P 0 ;0,1=591,2=0.000000
L 1.48863337 3.56759931 1.49131683 3.56553307 1 P 0 ;0,1=591,2=0.000000
L 1.49131683 3.56553307 1.49399961 3.5645 1 P 0 ;0,1=591,2=0.000000
L 1.49399961 3.5645 1.49668307 3.5645 1 P 0 ;0,1=591,2=0.000000
L 1.49668307 3.5645 1.49936654 3.56553307 1 P 0 ;0,1=591,2=0.000000
L 1.49936654 3.56553307 1.50166673 3.56708278 1 P 0 ;0,1=591,2=0.000000
L 1.50166673 3.56708278 1.50358366 3.56914892 1 P 0 ;0,1=591,2=0.000000
L 1.52423307 3.5645 1.52499961 3.57121614 1 P 0 ;0,1=591,2=0.000000
L 1.52499961 3.57121614 1.5261501 3.57689921 1 P 0 ;0,1=591,2=0.000000
L 1.5261501 3.57689921 1.52768307 3.58206663 1 P 0 ;0,1=591,2=0.000000
L 1.52768307 3.58206663 1.5296 3.5877497 1 P 0 ;0,1=591,2=0.000000
L 1.5296 3.5877497 1.53266673 3.5955 1 P 0 ;0,1=591,2=0.000000
L 1.53266673 3.5955 1.51733317 3.5955 1 P 0 ;0,1=591,2=0.000000
L 1.5606 3.5645 1.5606 3.5955 1 P 0 ;0,1=591,2=0.000000
L 1.5606 3.5955 1.54641624 3.57328327 1 P 0 ;0,1=591,2=0.000000
L 1.54641624 3.57328327 1.56558366 3.57328327 1 P 0 ;0,1=591,2=0.000000
L 1.57 0.5972 1.57 0.6872 1 P 0 
L 1.57 0.6872 1.526 0.6872 1 P 0 
L 1.526 0.6872 1.526 0.5972 1 P 0 
L 1.526 0.5972 1.57 0.5972 1 P 0 
L 1.54208376 0.49743327 1.54053317 0.49513307 1 P 0 ;0,1=592,2=270.000000
L 1.54053317 0.49513307 1.5395 0.4924503 1 P 0 ;0,1=592,2=270.000000
L 1.5395 0.4924503 1.5395 0.48938356 1 P 0 ;0,1=592,2=270.000000
L 1.5395 0.48938356 1.54105069 0.48593287 1 P 0 ;0,1=592,2=270.000000
L 1.54105069 0.48593287 1.54363346 0.4832501 1 P 0 ;0,1=592,2=270.000000
L 1.54363346 0.4832501 1.54673376 0.48133317 1 P 0 ;0,1=592,2=270.000000
L 1.54673376 0.48133317 1.5519002 0.47979951 1 P 0 ;0,1=592,2=270.000000
L 1.5519002 0.47979951 1.5565502 0.47941624 1 P 0 ;0,1=592,2=270.000000
L 1.5565502 0.47941624 1.5612001 0.48018337 1 P 0 ;0,1=592,2=270.000000
L 1.5612001 0.48018337 1.56430039 0.48133317 1 P 0 ;0,1=592,2=270.000000
L 1.56430039 0.48133317 1.56740069 0.48363337 1 P 0 ;0,1=592,2=270.000000
L 1.56740069 0.48363337 1.56946693 0.48631683 1 P 0 ;0,1=592,2=270.000000
L 1.56946693 0.48631683 1.5705 0.48899961 1 P 0 ;0,1=592,2=270.000000
L 1.5705 0.48899961 1.5705 0.49168307 1 P 0 ;0,1=592,2=270.000000
L 1.5705 0.49168307 1.56946693 0.49436654 1 P 0 ;0,1=592,2=270.000000
L 1.56946693 0.49436654 1.56791722 0.49666673 1 P 0 ;0,1=592,2=270.000000
L 1.56791722 0.49666673 1.56585108 0.49858366 1 P 0 ;0,1=592,2=270.000000
L 1.5705 0.51999961 1.5395 0.51999961 1 P 0 ;0,1=592,2=270.000000
L 1.5395 0.51999961 1.5456997 0.5153999 1 P 0 ;0,1=592,2=270.000000
L 1.5705 0.5153999 1.5705 0.52459931 1 P 0 ;0,1=592,2=270.000000
L 1.5705 0.55023307 1.56378386 0.55099961 1 P 0 ;0,1=592,2=270.000000
L 1.56378386 0.55099961 1.55810079 0.5521501 1 P 0 ;0,1=592,2=270.000000
L 1.55810079 0.5521501 1.55293337 0.55368307 1 P 0 ;0,1=592,2=270.000000
L 1.55293337 0.55368307 1.5472503 0.5556 1 P 0 ;0,1=592,2=270.000000
L 1.5472503 0.5556 1.5395 0.55866673 1 P 0 ;0,1=592,2=270.000000
L 1.5395 0.55866673 1.5395 0.54333317 1 P 0 ;0,1=592,2=270.000000
L 2.198 3.911 2.154 3.911 1 P 0 
L 2.154 3.911 2.154 3.821 1 P 0 
L 2.154 3.821 2.198 3.821 1 P 0 
L 2.198 3.821 2.198 3.911 1 P 0 
L 2.30308376 3.84843327 2.30153317 3.84613307 1 P 0 ;0,1=593,2=270.000000
L 2.30153317 3.84613307 2.3005 3.8434503 1 P 0 ;0,1=593,2=270.000000
L 2.3005 3.8434503 2.3005 3.84038356 1 P 0 ;0,1=593,2=270.000000
L 2.3005 3.84038356 2.30205069 3.83693287 1 P 0 ;0,1=593,2=270.000000
L 2.30205069 3.83693287 2.30463346 3.8342501 1 P 0 ;0,1=593,2=270.000000
L 2.30463346 3.8342501 2.30773376 3.83233317 1 P 0 ;0,1=593,2=270.000000
L 2.30773376 3.83233317 2.3129002 3.83079951 1 P 0 ;0,1=593,2=270.000000
L 2.3129002 3.83079951 2.3175502 3.83041624 1 P 0 ;0,1=593,2=270.000000
L 2.3175502 3.83041624 2.3222001 3.83118337 1 P 0 ;0,1=593,2=270.000000
L 2.3222001 3.83118337 2.32530039 3.83233317 1 P 0 ;0,1=593,2=270.000000
L 2.32530039 3.83233317 2.32840069 3.83463337 1 P 0 ;0,1=593,2=270.000000
L 2.32840069 3.83463337 2.33046693 3.83731683 1 P 0 ;0,1=593,2=270.000000
L 2.33046693 3.83731683 2.3315 3.83999961 1 P 0 ;0,1=593,2=270.000000
L 2.3315 3.83999961 2.3315 3.84268307 1 P 0 ;0,1=593,2=270.000000
L 2.3315 3.84268307 2.33046693 3.84536654 1 P 0 ;0,1=593,2=270.000000
L 2.33046693 3.84536654 2.32891722 3.84766673 1 P 0 ;0,1=593,2=270.000000
L 2.32891722 3.84766673 2.32685108 3.84958366 1 P 0 ;0,1=593,2=270.000000
L 2.3315 3.87099961 2.3005 3.87099961 1 P 0 ;0,1=593,2=270.000000
L 2.3005 3.87099961 2.3066997 3.8663999 1 P 0 ;0,1=593,2=270.000000
L 2.3315 3.8663999 2.3315 3.87559931 1 P 0 ;0,1=593,2=270.000000
L 2.30566654 3.89471644 2.30256722 3.89701663 1 P 0 ;0,1=593,2=270.000000
L 2.30256722 3.89701663 2.30101663 3.8997001 1 P 0 ;0,1=593,2=270.000000
L 2.30101663 3.8997001 2.3005 3.90276683 1 P 0 ;0,1=593,2=270.000000
L 2.3005 3.90276683 2.30153317 3.9066 1 P 0 ;0,1=593,2=270.000000
L 2.30153317 3.9066 2.30411693 3.90928346 1 P 0 ;0,1=593,2=270.000000
L 2.30411693 3.90928346 2.30721624 3.91005 1 P 0 ;0,1=593,2=270.000000
L 2.30721624 3.91005 2.31031742 3.90966673 1 P 0 ;0,1=593,2=270.000000
L 2.31031742 3.90966673 2.3129002 3.90813307 1 P 0 ;0,1=593,2=270.000000
L 2.3129002 3.90813307 2.31806673 3.90046663 1 P 0 ;0,1=593,2=270.000000
L 2.31806673 3.90046663 2.32168356 3.89701663 1 P 0 ;0,1=593,2=270.000000
L 2.32168356 3.89701663 2.32685108 3.89471644 1 P 0 ;0,1=593,2=270.000000
L 2.32685108 3.89471644 2.3315 3.8939499 1 P 0 ;0,1=593,2=270.000000
L 2.3315 3.8939499 2.3315 3.91005 1 P 0 ;0,1=593,2=270.000000
L 2.24 2.907 2.24 2.997 1 P 0 
L 2.24 2.997 2.196 2.997 1 P 0 
L 2.196 2.997 2.196 2.907 1 P 0 
L 2.196 2.907 2.24 2.907 1 P 0 
L 2.36708376 2.89193327 2.36553317 2.88963307 1 P 0 ;0,1=594,2=270.000000
L 2.36553317 2.88963307 2.3645 2.8869503 1 P 0 ;0,1=594,2=270.000000
L 2.3645 2.8869503 2.3645 2.88388356 1 P 0 ;0,1=594,2=270.000000
L 2.3645 2.88388356 2.36605069 2.88043287 1 P 0 ;0,1=594,2=270.000000
L 2.36605069 2.88043287 2.36863346 2.8777501 1 P 0 ;0,1=594,2=270.000000
L 2.36863346 2.8777501 2.37173376 2.87583317 1 P 0 ;0,1=594,2=270.000000
L 2.37173376 2.87583317 2.3769002 2.87429951 1 P 0 ;0,1=594,2=270.000000
L 2.3769002 2.87429951 2.3815502 2.87391624 1 P 0 ;0,1=594,2=270.000000
L 2.3815502 2.87391624 2.3862001 2.87468337 1 P 0 ;0,1=594,2=270.000000
L 2.3862001 2.87468337 2.38930039 2.87583317 1 P 0 ;0,1=594,2=270.000000
L 2.38930039 2.87583317 2.39240069 2.87813337 1 P 0 ;0,1=594,2=270.000000
L 2.39240069 2.87813337 2.39446693 2.88081683 1 P 0 ;0,1=594,2=270.000000
L 2.39446693 2.88081683 2.3955 2.88349961 1 P 0 ;0,1=594,2=270.000000
L 2.3955 2.88349961 2.3955 2.88618307 1 P 0 ;0,1=594,2=270.000000
L 2.3955 2.88618307 2.39446693 2.88886654 1 P 0 ;0,1=594,2=270.000000
L 2.39446693 2.88886654 2.39291722 2.89116673 1 P 0 ;0,1=594,2=270.000000
L 2.39291722 2.89116673 2.39085108 2.89308366 1 P 0 ;0,1=594,2=270.000000
L 2.38930039 2.90606663 2.39291722 2.90836614 1 P 0 ;0,1=594,2=270.000000
L 2.39291722 2.90836614 2.39498346 2.91143287 1 P 0 ;0,1=594,2=270.000000
L 2.39498346 2.91143287 2.3955 2.91488356 1 P 0 ;0,1=594,2=270.000000
L 2.3955 2.91488356 2.39498346 2.9179503 1 P 0 ;0,1=594,2=270.000000
L 2.39498346 2.9179503 2.39240069 2.92101703 1 P 0 ;0,1=594,2=270.000000
L 2.39240069 2.92101703 2.38930039 2.92293327 1 P 0 ;0,1=594,2=270.000000
L 2.38930039 2.92293327 2.3862001 2.92331654 1 P 0 ;0,1=594,2=270.000000
L 2.3862001 2.92331654 2.38258425 2.92255 1 P 0 ;0,1=594,2=270.000000
L 2.38258425 2.92255 2.38000049 2.91986654 1 P 0 ;0,1=594,2=270.000000
L 2.38000049 2.91986654 2.37896644 2.91718307 1 P 0 ;0,1=594,2=270.000000
L 2.37896644 2.91718307 2.37896644 2.91373307 1 P 0 ;0,1=594,2=270.000000
L 2.37896644 2.91718307 2.37741683 2.91948327 1 P 0 ;0,1=594,2=270.000000
L 2.37741683 2.91948327 2.37483406 2.9214002 1 P 0 ;0,1=594,2=270.000000
L 2.37483406 2.9214002 2.37173376 2.92216673 1 P 0 ;0,1=594,2=270.000000
L 2.37173376 2.92216673 2.36863346 2.9214002 1 P 0 ;0,1=594,2=270.000000
L 2.36863346 2.9214002 2.36605069 2.91948327 1 P 0 ;0,1=594,2=270.000000
L 2.36605069 2.91948327 2.3645 2.91603327 1 P 0 ;0,1=594,2=270.000000
L 2.3645 2.91603327 2.36501663 2.91258337 1 P 0 ;0,1=594,2=270.000000
L 2.36501663 2.91258337 2.36708376 2.90913337 1 P 0 ;0,1=594,2=270.000000
L 2.3645 2.94549961 2.36553317 2.94243287 1 P 0 ;0,1=594,2=270.000000
L 2.36553317 2.94243287 2.36811693 2.94013337 1 P 0 ;0,1=594,2=270.000000
L 2.36811693 2.94013337 2.37121624 2.9385997 1 P 0 ;0,1=594,2=270.000000
L 2.37121624 2.9385997 2.37535059 2.9374499 1 P 0 ;0,1=594,2=270.000000
L 2.37535059 2.9374499 2.38000049 2.93706663 1 P 0 ;0,1=594,2=270.000000
L 2.38000049 2.93706663 2.38465049 2.9374499 1 P 0 ;0,1=594,2=270.000000
L 2.38465049 2.9374499 2.38878386 2.9385997 1 P 0 ;0,1=594,2=270.000000
L 2.38878386 2.9385997 2.39188415 2.94013337 1 P 0 ;0,1=594,2=270.000000
L 2.39188415 2.94013337 2.39446693 2.94243287 1 P 0 ;0,1=594,2=270.000000
L 2.39446693 2.94243287 2.3955 2.94549961 1 P 0 ;0,1=594,2=270.000000
L 2.3955 2.94549961 2.39446693 2.94856634 1 P 0 ;0,1=594,2=270.000000
L 2.39446693 2.94856634 2.39188415 2.95086654 1 P 0 ;0,1=594,2=270.000000
L 2.39188415 2.95086654 2.38878386 2.9524002 1 P 0 ;0,1=594,2=270.000000
L 2.38878386 2.9524002 2.38465049 2.95355 1 P 0 ;0,1=594,2=270.000000
L 2.38465049 2.95355 2.38000049 2.95393327 1 P 0 ;0,1=594,2=270.000000
L 2.38000049 2.95393327 2.37535059 2.95355 1 P 0 ;0,1=594,2=270.000000
L 2.37535059 2.95355 2.37121624 2.9524002 1 P 0 ;0,1=594,2=270.000000
L 2.37121624 2.9524002 2.36811693 2.95086654 1 P 0 ;0,1=594,2=270.000000
L 2.36811693 2.95086654 2.36553317 2.94856634 1 P 0 ;0,1=594,2=270.000000
L 2.36553317 2.94856634 2.3645 2.94549961 1 P 0 ;0,1=594,2=270.000000
L 2.38258425 2.96921644 2.37896644 2.9718999 1 P 0 ;0,1=594,2=270.000000
L 2.37896644 2.9718999 2.3769002 2.9742001 1 P 0 ;0,1=594,2=270.000000
L 2.3769002 2.9742001 2.37586713 2.97726683 1 P 0 ;0,1=594,2=270.000000
L 2.37586713 2.97726683 2.3769002 2.9799503 1 P 0 ;0,1=594,2=270.000000
L 2.3769002 2.9799503 2.37896644 2.98186654 1 P 0 ;0,1=594,2=270.000000
L 2.37896644 2.98186654 2.38206673 2.9834002 1 P 0 ;0,1=594,2=270.000000
L 2.38206673 2.9834002 2.38568356 2.98378346 1 P 0 ;0,1=594,2=270.000000
L 2.38568356 2.98378346 2.38878386 2.9834002 1 P 0 ;0,1=594,2=270.000000
L 2.38878386 2.9834002 2.39188415 2.98186654 1 P 0 ;0,1=594,2=270.000000
L 2.39188415 2.98186654 2.39446693 2.97956634 1 P 0 ;0,1=594,2=270.000000
L 2.39446693 2.97956634 2.3955 2.97688356 1 P 0 ;0,1=594,2=270.000000
L 2.3955 2.97688356 2.39446693 2.97381683 1 P 0 ;0,1=594,2=270.000000
L 2.39446693 2.97381683 2.39136762 2.97113337 1 P 0 ;0,1=594,2=270.000000
L 2.39136762 2.97113337 2.38671673 2.9695997 1 P 0 ;0,1=594,2=270.000000
L 2.38671673 2.9695997 2.3815502 2.96921644 1 P 0 ;0,1=594,2=270.000000
L 2.3815502 2.96921644 2.37483406 2.96998287 1 P 0 ;0,1=594,2=270.000000
L 2.37483406 2.96998287 2.37121624 2.97113337 1 P 0 ;0,1=594,2=270.000000
L 2.37121624 2.97113337 2.3676003 2.97304961 1 P 0 ;0,1=594,2=270.000000
L 2.3676003 2.97304961 2.36501663 2.97573307 1 P 0 ;0,1=594,2=270.000000
L 2.36501663 2.97573307 2.3645 2.97841654 1 P 0 ;0,1=594,2=270.000000
L 2.3645 2.97841654 2.36553317 2.9811 1 P 0 ;0,1=594,2=270.000000
L 2.36553317 2.9811 2.36811693 2.98301703 1 P 0 ;0,1=594,2=270.000000
L 5.432 1.77 5.432 1.86 1 P 0 
L 5.432 1.86 5.388 1.86 1 P 0 
L 5.388 1.86 5.388 1.77 1 P 0 
L 5.388 1.77 5.432 1.77 1 P 0 
L 5.39208376 1.90693327 5.39053317 1.90463307 1 P 0 ;0,1=595,2=270.000000
L 5.39053317 1.90463307 5.3895 1.9019503 1 P 0 ;0,1=595,2=270.000000
L 5.3895 1.9019503 5.3895 1.89888356 1 P 0 ;0,1=595,2=270.000000
L 5.3895 1.89888356 5.39105069 1.89543287 1 P 0 ;0,1=595,2=270.000000
L 5.39105069 1.89543287 5.39363346 1.8927501 1 P 0 ;0,1=595,2=270.000000
L 5.39363346 1.8927501 5.39673376 1.89083317 1 P 0 ;0,1=595,2=270.000000
L 5.39673376 1.89083317 5.4019002 1.88929951 1 P 0 ;0,1=595,2=270.000000
L 5.4019002 1.88929951 5.4065502 1.88891624 1 P 0 ;0,1=595,2=270.000000
L 5.4065502 1.88891624 5.4112001 1.88968337 1 P 0 ;0,1=595,2=270.000000
L 5.4112001 1.88968337 5.41430039 1.89083317 1 P 0 ;0,1=595,2=270.000000
L 5.41430039 1.89083317 5.41740069 1.89313337 1 P 0 ;0,1=595,2=270.000000
L 5.41740069 1.89313337 5.41946693 1.89581683 1 P 0 ;0,1=595,2=270.000000
L 5.41946693 1.89581683 5.4205 1.89849961 1 P 0 ;0,1=595,2=270.000000
L 5.4205 1.89849961 5.4205 1.90118307 1 P 0 ;0,1=595,2=270.000000
L 5.4205 1.90118307 5.41946693 1.90386654 1 P 0 ;0,1=595,2=270.000000
L 5.41946693 1.90386654 5.41791722 1.90616673 1 P 0 ;0,1=595,2=270.000000
L 5.41791722 1.90616673 5.41585108 1.90808366 1 P 0 ;0,1=595,2=270.000000
L 5.39466654 1.92221644 5.39156722 1.92451663 1 P 0 ;0,1=595,2=270.000000
L 5.39156722 1.92451663 5.39001663 1.9272001 1 P 0 ;0,1=595,2=270.000000
L 5.39001663 1.9272001 5.3895 1.93026683 1 P 0 ;0,1=595,2=270.000000
L 5.3895 1.93026683 5.39053317 1.9341 1 P 0 ;0,1=595,2=270.000000
L 5.39053317 1.9341 5.39311693 1.93678346 1 P 0 ;0,1=595,2=270.000000
L 5.39311693 1.93678346 5.39621624 1.93755 1 P 0 ;0,1=595,2=270.000000
L 5.39621624 1.93755 5.39931742 1.93716673 1 P 0 ;0,1=595,2=270.000000
L 5.39931742 1.93716673 5.4019002 1.93563307 1 P 0 ;0,1=595,2=270.000000
L 5.4019002 1.93563307 5.40706673 1.92796663 1 P 0 ;0,1=595,2=270.000000
L 5.40706673 1.92796663 5.41068356 1.92451663 1 P 0 ;0,1=595,2=270.000000
L 5.41068356 1.92451663 5.41585108 1.92221644 1 P 0 ;0,1=595,2=270.000000
L 5.41585108 1.92221644 5.4205 1.9214499 1 P 0 ;0,1=595,2=270.000000
L 5.4205 1.9214499 5.4205 1.93755 1 P 0 ;0,1=595,2=270.000000
L 5.40758425 1.95321644 5.40396644 1.9558999 1 P 0 ;0,1=595,2=270.000000
L 5.40396644 1.9558999 5.4019002 1.9582001 1 P 0 ;0,1=595,2=270.000000
L 5.4019002 1.9582001 5.40086713 1.96126683 1 P 0 ;0,1=595,2=270.000000
L 5.40086713 1.96126683 5.4019002 1.9639503 1 P 0 ;0,1=595,2=270.000000
L 5.4019002 1.9639503 5.40396644 1.96586654 1 P 0 ;0,1=595,2=270.000000
L 5.40396644 1.96586654 5.40706673 1.9674002 1 P 0 ;0,1=595,2=270.000000
L 5.40706673 1.9674002 5.41068356 1.96778346 1 P 0 ;0,1=595,2=270.000000
L 5.41068356 1.96778346 5.41378386 1.9674002 1 P 0 ;0,1=595,2=270.000000
L 5.41378386 1.9674002 5.41688415 1.96586654 1 P 0 ;0,1=595,2=270.000000
L 5.41688415 1.96586654 5.41946693 1.96356634 1 P 0 ;0,1=595,2=270.000000
L 5.41946693 1.96356634 5.4205 1.96088356 1 P 0 ;0,1=595,2=270.000000
L 5.4205 1.96088356 5.41946693 1.95781683 1 P 0 ;0,1=595,2=270.000000
L 5.41946693 1.95781683 5.41636762 1.95513337 1 P 0 ;0,1=595,2=270.000000
L 5.41636762 1.95513337 5.41171673 1.9535997 1 P 0 ;0,1=595,2=270.000000
L 5.41171673 1.9535997 5.4065502 1.95321644 1 P 0 ;0,1=595,2=270.000000
L 5.4065502 1.95321644 5.39983406 1.95398287 1 P 0 ;0,1=595,2=270.000000
L 5.39983406 1.95398287 5.39621624 1.95513337 1 P 0 ;0,1=595,2=270.000000
L 5.39621624 1.95513337 5.3926003 1.95704961 1 P 0 ;0,1=595,2=270.000000
L 5.3926003 1.95704961 5.39001663 1.95973307 1 P 0 ;0,1=595,2=270.000000
L 5.39001663 1.95973307 5.3895 1.96241654 1 P 0 ;0,1=595,2=270.000000
L 5.3895 1.96241654 5.39053317 1.9651 1 P 0 ;0,1=595,2=270.000000
L 5.39053317 1.9651 5.39311693 1.96701703 1 P 0 ;0,1=595,2=270.000000
L 5.4205 1.99149961 5.41998346 1.99418307 1 P 0 ;0,1=595,2=270.000000
L 5.41998346 1.99418307 5.41843386 1.9972498 1 P 0 ;0,1=595,2=270.000000
L 5.41843386 1.9972498 5.41585108 1.99916673 1 P 0 ;0,1=595,2=270.000000
L 5.41585108 1.99916673 5.41223327 1.99993327 1 P 0 ;0,1=595,2=270.000000
L 5.41223327 1.99993327 5.40861732 1.99916673 1 P 0 ;0,1=595,2=270.000000
L 5.40861732 1.99916673 5.40551713 1.99686654 1 P 0 ;0,1=595,2=270.000000
L 5.40551713 1.99686654 5.40396644 1.99341654 1 P 0 ;0,1=595,2=270.000000
L 5.40396644 1.99341654 5.40396644 1.98958337 1 P 0 ;0,1=595,2=270.000000
L 5.40396644 1.98958337 5.40293337 1.98728317 1 P 0 ;0,1=595,2=270.000000
L 5.40293337 1.98728317 5.40035059 1.98536614 1 P 0 ;0,1=595,2=270.000000
L 5.40035059 1.98536614 5.39673376 1.9845997 1 P 0 ;0,1=595,2=270.000000
L 5.39673376 1.9845997 5.39311693 1.9857501 1 P 0 ;0,1=595,2=270.000000
L 5.39311693 1.9857501 5.39053317 1.98843287 1 P 0 ;0,1=595,2=270.000000
L 5.39053317 1.98843287 5.3895 1.99149961 1 P 0 ;0,1=595,2=270.000000
L 5.3895 1.99149961 5.39053317 1.99456634 1 P 0 ;0,1=595,2=270.000000
L 5.39053317 1.99456634 5.39311693 1.9972498 1 P 0 ;0,1=595,2=270.000000
L 5.39311693 1.9972498 5.39673376 1.9984002 1 P 0 ;0,1=595,2=270.000000
L 5.39673376 1.9984002 5.40035059 1.99763307 1 P 0 ;0,1=595,2=270.000000
L 5.40035059 1.99763307 5.40293337 1.99571673 1 P 0 ;0,1=595,2=270.000000
L 5.40293337 1.99571673 5.40396644 1.99341654 1 P 0 ;0,1=595,2=270.000000
L 5.40396644 1.99341654 5.40396644 1.98958337 1 P 0 ;0,1=595,2=270.000000
L 5.40396644 1.98958337 5.40551713 1.98613337 1 P 0 ;0,1=595,2=270.000000
L 5.40551713 1.98613337 5.40861732 1.98383317 1 P 0 ;0,1=595,2=270.000000
L 5.40861732 1.98383317 5.41223327 1.98306663 1 P 0 ;0,1=595,2=270.000000
L 5.41223327 1.98306663 5.41585108 1.98383317 1 P 0 ;0,1=595,2=270.000000
L 5.41585108 1.98383317 5.41843386 1.9857501 1 P 0 ;0,1=595,2=270.000000
L 5.41843386 1.9857501 5.41998346 1.98881683 1 P 0 ;0,1=595,2=270.000000
L 5.41998346 1.98881683 5.4205 1.99149961 1 P 0 ;0,1=595,2=270.000000
L 5.315 0.898 5.315 0.942 1 P 0 
L 5.315 0.942 5.225 0.942 1 P 0 
L 5.225 0.898 5.315 0.898 1 P 0 
L 5.225 0.942 5.225 0.898 1 P 0 
L 5.22243327 1.12291624 5.22013307 1.12446683 1 P 0 ;0,1=596,2=0.000000
L 5.22013307 1.12446683 5.2174503 1.1255 1 P 0 ;0,1=596,2=0.000000
L 5.2174503 1.1255 5.21438356 1.1255 1 P 0 ;0,1=596,2=0.000000
L 5.21438356 1.1255 5.21093287 1.12394931 1 P 0 ;0,1=596,2=0.000000
L 5.21093287 1.12394931 5.2082501 1.12136654 1 P 0 ;0,1=596,2=0.000000
L 5.2082501 1.12136654 5.20633317 1.11826624 1 P 0 ;0,1=596,2=0.000000
L 5.20633317 1.11826624 5.20479951 1.1130998 1 P 0 ;0,1=596,2=0.000000
L 5.20479951 1.1130998 5.20441624 1.1084498 1 P 0 ;0,1=596,2=0.000000
L 5.20441624 1.1084498 5.20518337 1.1037999 1 P 0 ;0,1=596,2=0.000000
L 5.20518337 1.1037999 5.20633317 1.10069961 1 P 0 ;0,1=596,2=0.000000
L 5.20633317 1.10069961 5.20863337 1.09759931 1 P 0 ;0,1=596,2=0.000000
L 5.20863337 1.09759931 5.21131683 1.09553307 1 P 0 ;0,1=596,2=0.000000
L 5.21131683 1.09553307 5.21399961 1.0945 1 P 0 ;0,1=596,2=0.000000
L 5.21399961 1.0945 5.21668307 1.0945 1 P 0 ;0,1=596,2=0.000000
L 5.21668307 1.0945 5.21936654 1.09553307 1 P 0 ;0,1=596,2=0.000000
L 5.21936654 1.09553307 5.22166673 1.09708278 1 P 0 ;0,1=596,2=0.000000
L 5.22166673 1.09708278 5.22358366 1.09914892 1 P 0 ;0,1=596,2=0.000000
L 5.23848287 1.09811585 5.24116634 1.09553307 1 P 0 ;0,1=596,2=0.000000
L 5.24116634 1.09553307 5.24423307 1.0945 1 P 0 ;0,1=596,2=0.000000
L 5.24423307 1.0945 5.2472998 1.09553307 1 P 0 ;0,1=596,2=0.000000
L 5.2472998 1.09553307 5.24998327 1.09863238 1 P 0 ;0,1=596,2=0.000000
L 5.24998327 1.09863238 5.2519002 1.10328327 1 P 0 ;0,1=596,2=0.000000
L 5.2519002 1.10328327 5.25266673 1.10793327 1 P 0 ;0,1=596,2=0.000000
L 5.25266673 1.10793327 5.25266673 1.11361634 1 P 0 ;0,1=596,2=0.000000
L 5.25266673 1.11361634 5.2519002 1.11826624 1 P 0 ;0,1=596,2=0.000000
L 5.2519002 1.11826624 5.24998327 1.1223997 1 P 0 ;0,1=596,2=0.000000
L 5.24998327 1.1223997 5.24768307 1.12446683 1 P 0 ;0,1=596,2=0.000000
L 5.24768307 1.12446683 5.24499961 1.1255 1 P 0 ;0,1=596,2=0.000000
L 5.24499961 1.1255 5.24193287 1.12446683 1 P 0 ;0,1=596,2=0.000000
L 5.24193287 1.12446683 5.23963337 1.1223997 1 P 0 ;0,1=596,2=0.000000
L 5.23963337 1.1223997 5.2380997 1.1193003 1 P 0 ;0,1=596,2=0.000000
L 5.2380997 1.1193003 5.23733317 1.11516594 1 P 0 ;0,1=596,2=0.000000
L 5.23733317 1.11516594 5.2380997 1.1115501 1 P 0 ;0,1=596,2=0.000000
L 5.2380997 1.1115501 5.24001663 1.10793327 1 P 0 ;0,1=596,2=0.000000
L 5.24001663 1.10793327 5.24231683 1.10586604 1 P 0 ;0,1=596,2=0.000000
L 5.24231683 1.10586604 5.24499961 1.10534951 1 P 0 ;0,1=596,2=0.000000
L 5.24499961 1.10534951 5.24806634 1.10638268 1 P 0 ;0,1=596,2=0.000000
L 5.24806634 1.10638268 5.25036654 1.10896634 1 P 0 ;0,1=596,2=0.000000
L 5.25036654 1.10896634 5.25266673 1.11361634 1 P 0 ;0,1=596,2=0.000000
L 5.26871644 1.12033346 5.27101663 1.12343278 1 P 0 ;0,1=596,2=0.000000
L 5.27101663 1.12343278 5.2737001 1.12498337 1 P 0 ;0,1=596,2=0.000000
L 5.2737001 1.12498337 5.27676683 1.1255 1 P 0 ;0,1=596,2=0.000000
L 5.27676683 1.1255 5.2806 1.12446683 1 P 0 ;0,1=596,2=0.000000
L 5.2806 1.12446683 5.28328346 1.12188307 1 P 0 ;0,1=596,2=0.000000
L 5.28328346 1.12188307 5.28405 1.11878376 1 P 0 ;0,1=596,2=0.000000
L 5.28405 1.11878376 5.28366673 1.11568258 1 P 0 ;0,1=596,2=0.000000
L 5.28366673 1.11568258 5.28213307 1.1130998 1 P 0 ;0,1=596,2=0.000000
L 5.28213307 1.1130998 5.27446663 1.10793327 1 P 0 ;0,1=596,2=0.000000
L 5.27446663 1.10793327 5.27101663 1.10431644 1 P 0 ;0,1=596,2=0.000000
L 5.27101663 1.10431644 5.26871644 1.09914892 1 P 0 ;0,1=596,2=0.000000
L 5.26871644 1.09914892 5.2679499 1.0945 1 P 0 ;0,1=596,2=0.000000
L 5.2679499 1.0945 5.28405 1.0945 1 P 0 ;0,1=596,2=0.000000
L 3.225 2.546 3.135 2.546 1 P 0 
L 3.135 2.546 3.135 2.502 1 P 0 
L 3.135 2.502 3.225 2.502 1 P 0 
L 3.225 2.502 3.225 2.546 1 P 0 
L 2.73693327 3.29791624 2.73463307 3.29946683 1 P 0 ;0,1=597,2=0.000000
L 2.73463307 3.29946683 2.7319503 3.3005 1 P 0 ;0,1=597,2=0.000000
L 2.7319503 3.3005 2.72888356 3.3005 1 P 0 ;0,1=597,2=0.000000
L 2.72888356 3.3005 2.72543287 3.29894931 1 P 0 ;0,1=597,2=0.000000
L 2.72543287 3.29894931 2.7227501 3.29636654 1 P 0 ;0,1=597,2=0.000000
L 2.7227501 3.29636654 2.72083317 3.29326624 1 P 0 ;0,1=597,2=0.000000
L 2.72083317 3.29326624 2.71929951 3.2880998 1 P 0 ;0,1=597,2=0.000000
L 2.71929951 3.2880998 2.71891624 3.2834498 1 P 0 ;0,1=597,2=0.000000
L 2.71891624 3.2834498 2.71968337 3.2787999 1 P 0 ;0,1=597,2=0.000000
L 2.71968337 3.2787999 2.72083317 3.27569961 1 P 0 ;0,1=597,2=0.000000
L 2.72083317 3.27569961 2.72313337 3.27259931 1 P 0 ;0,1=597,2=0.000000
L 2.72313337 3.27259931 2.72581683 3.27053307 1 P 0 ;0,1=597,2=0.000000
L 2.72581683 3.27053307 2.72849961 3.2695 1 P 0 ;0,1=597,2=0.000000
L 2.72849961 3.2695 2.73118307 3.2695 1 P 0 ;0,1=597,2=0.000000
L 2.73118307 3.2695 2.73386654 3.27053307 1 P 0 ;0,1=597,2=0.000000
L 2.73386654 3.27053307 2.73616673 3.27208278 1 P 0 ;0,1=597,2=0.000000
L 2.73616673 3.27208278 2.73808366 3.27414892 1 P 0 ;0,1=597,2=0.000000
L 2.75221644 3.29533346 2.75451663 3.29843278 1 P 0 ;0,1=597,2=0.000000
L 2.75451663 3.29843278 2.7572001 3.29998337 1 P 0 ;0,1=597,2=0.000000
L 2.7572001 3.29998337 2.76026683 3.3005 1 P 0 ;0,1=597,2=0.000000
L 2.76026683 3.3005 2.7641 3.29946683 1 P 0 ;0,1=597,2=0.000000
L 2.7641 3.29946683 2.76678346 3.29688307 1 P 0 ;0,1=597,2=0.000000
L 2.76678346 3.29688307 2.76755 3.29378376 1 P 0 ;0,1=597,2=0.000000
L 2.76755 3.29378376 2.76716673 3.29068258 1 P 0 ;0,1=597,2=0.000000
L 2.76716673 3.29068258 2.76563307 3.2880998 1 P 0 ;0,1=597,2=0.000000
L 2.76563307 3.2880998 2.75796663 3.28293327 1 P 0 ;0,1=597,2=0.000000
L 2.75796663 3.28293327 2.75451663 3.27931644 1 P 0 ;0,1=597,2=0.000000
L 2.75451663 3.27931644 2.75221644 3.27414892 1 P 0 ;0,1=597,2=0.000000
L 2.75221644 3.27414892 2.7514499 3.2695 1 P 0 ;0,1=597,2=0.000000
L 2.7514499 3.2695 2.76755 3.2695 1 P 0 ;0,1=597,2=0.000000
L 2.79049961 3.2695 2.79318307 3.27001654 1 P 0 ;0,1=597,2=0.000000
L 2.79318307 3.27001654 2.7962498 3.27156614 1 P 0 ;0,1=597,2=0.000000
L 2.7962498 3.27156614 2.79816673 3.27414892 1 P 0 ;0,1=597,2=0.000000
L 2.79816673 3.27414892 2.79893327 3.27776673 1 P 0 ;0,1=597,2=0.000000
L 2.79893327 3.27776673 2.79816673 3.28138268 1 P 0 ;0,1=597,2=0.000000
L 2.79816673 3.28138268 2.79586654 3.28448287 1 P 0 ;0,1=597,2=0.000000
L 2.79586654 3.28448287 2.79241654 3.28603356 1 P 0 ;0,1=597,2=0.000000
L 2.79241654 3.28603356 2.78858337 3.28603356 1 P 0 ;0,1=597,2=0.000000
L 2.78858337 3.28603356 2.78628317 3.28706663 1 P 0 ;0,1=597,2=0.000000
L 2.78628317 3.28706663 2.78436614 3.28964941 1 P 0 ;0,1=597,2=0.000000
L 2.78436614 3.28964941 2.7835997 3.29326624 1 P 0 ;0,1=597,2=0.000000
L 2.7835997 3.29326624 2.7847501 3.29688307 1 P 0 ;0,1=597,2=0.000000
L 2.7847501 3.29688307 2.78743287 3.29946683 1 P 0 ;0,1=597,2=0.000000
L 2.78743287 3.29946683 2.79049961 3.3005 1 P 0 ;0,1=597,2=0.000000
L 2.79049961 3.3005 2.79356634 3.29946683 1 P 0 ;0,1=597,2=0.000000
L 2.79356634 3.29946683 2.7962498 3.29688307 1 P 0 ;0,1=597,2=0.000000
L 2.7962498 3.29688307 2.7974002 3.29326624 1 P 0 ;0,1=597,2=0.000000
L 2.7974002 3.29326624 2.79663307 3.28964941 1 P 0 ;0,1=597,2=0.000000
L 2.79663307 3.28964941 2.79471673 3.28706663 1 P 0 ;0,1=597,2=0.000000
L 2.79471673 3.28706663 2.79241654 3.28603356 1 P 0 ;0,1=597,2=0.000000
L 2.79241654 3.28603356 2.78858337 3.28603356 1 P 0 ;0,1=597,2=0.000000
L 2.78858337 3.28603356 2.78513337 3.28448287 1 P 0 ;0,1=597,2=0.000000
L 2.78513337 3.28448287 2.78283317 3.28138268 1 P 0 ;0,1=597,2=0.000000
L 2.78283317 3.28138268 2.78206663 3.27776673 1 P 0 ;0,1=597,2=0.000000
L 2.78206663 3.27776673 2.78283317 3.27414892 1 P 0 ;0,1=597,2=0.000000
L 2.78283317 3.27414892 2.7847501 3.27156614 1 P 0 ;0,1=597,2=0.000000
L 2.7847501 3.27156614 2.78781683 3.27001654 1 P 0 ;0,1=597,2=0.000000
L 2.78781683 3.27001654 2.79049961 3.2695 1 P 0 ;0,1=597,2=0.000000
L 2.81306663 3.27414892 2.81536614 3.27156614 1 P 0 ;0,1=597,2=0.000000
L 2.81536614 3.27156614 2.81804961 3.27001654 1 P 0 ;0,1=597,2=0.000000
L 2.81804961 3.27001654 2.82149961 3.2695 1 P 0 ;0,1=597,2=0.000000
L 2.82149961 3.2695 2.8249503 3.27053307 1 P 0 ;0,1=597,2=0.000000
L 2.8249503 3.27053307 2.82763307 3.27259931 1 P 0 ;0,1=597,2=0.000000
L 2.82763307 3.27259931 2.82955 3.27621614 1 P 0 ;0,1=597,2=0.000000
L 2.82955 3.27621614 2.82993327 3.28034951 1 P 0 ;0,1=597,2=0.000000
L 2.82993327 3.28034951 2.82916673 3.28448287 1 P 0 ;0,1=597,2=0.000000
L 2.82916673 3.28448287 2.8272498 3.28706663 1 P 0 ;0,1=597,2=0.000000
L 2.8272498 3.28706663 2.82456634 3.28913287 1 P 0 ;0,1=597,2=0.000000
L 2.82456634 3.28913287 2.82188356 3.28964941 1 P 0 ;0,1=597,2=0.000000
L 2.82188356 3.28964941 2.8192001 3.28913287 1 P 0 ;0,1=597,2=0.000000
L 2.8192001 3.28913287 2.8157501 3.28706663 1 P 0 ;0,1=597,2=0.000000
L 2.8157501 3.28706663 2.8168999 3.3005 1 P 0 ;0,1=597,2=0.000000
L 2.8168999 3.3005 2.8272498 3.3005 1 P 0 ;0,1=597,2=0.000000
L 5.08 2.452 5.08 2.496 1 P 0 
L 4.99 2.452 5.08 2.452 1 P 0 
L 5.08 2.496 4.99 2.496 1 P 0 
L 4.99 2.496 4.99 2.452 1 P 0 
L 5.04193327 2.29791624 5.03963307 2.29946683 1 P 0 ;0,1=598,2=0.000000
L 5.03963307 2.29946683 5.0369503 2.3005 1 P 0 ;0,1=598,2=0.000000
L 5.0369503 2.3005 5.03388356 2.3005 1 P 0 ;0,1=598,2=0.000000
L 5.03388356 2.3005 5.03043287 2.29894931 1 P 0 ;0,1=598,2=0.000000
L 5.03043287 2.29894931 5.0277501 2.29636654 1 P 0 ;0,1=598,2=0.000000
L 5.0277501 2.29636654 5.02583317 2.29326624 1 P 0 ;0,1=598,2=0.000000
L 5.02583317 2.29326624 5.02429951 2.2880998 1 P 0 ;0,1=598,2=0.000000
L 5.02429951 2.2880998 5.02391624 2.2834498 1 P 0 ;0,1=598,2=0.000000
L 5.02391624 2.2834498 5.02468337 2.2787999 1 P 0 ;0,1=598,2=0.000000
L 5.02468337 2.2787999 5.02583317 2.27569961 1 P 0 ;0,1=598,2=0.000000
L 5.02583317 2.27569961 5.02813337 2.27259931 1 P 0 ;0,1=598,2=0.000000
L 5.02813337 2.27259931 5.03081683 2.27053307 1 P 0 ;0,1=598,2=0.000000
L 5.03081683 2.27053307 5.03349961 2.2695 1 P 0 ;0,1=598,2=0.000000
L 5.03349961 2.2695 5.03618307 2.2695 1 P 0 ;0,1=598,2=0.000000
L 5.03618307 2.2695 5.03886654 2.27053307 1 P 0 ;0,1=598,2=0.000000
L 5.03886654 2.27053307 5.04116673 2.27208278 1 P 0 ;0,1=598,2=0.000000
L 5.04116673 2.27208278 5.04308366 2.27414892 1 P 0 ;0,1=598,2=0.000000
L 5.06449961 2.2695 5.06449961 2.3005 1 P 0 ;0,1=598,2=0.000000
L 5.06449961 2.3005 5.0598999 2.2943003 1 P 0 ;0,1=598,2=0.000000
L 5.0598999 2.2695 5.06909931 2.2695 1 P 0 ;0,1=598,2=0.000000
L 5.09549961 2.2695 5.09818307 2.27001654 1 P 0 ;0,1=598,2=0.000000
L 5.09818307 2.27001654 5.1012498 2.27156614 1 P 0 ;0,1=598,2=0.000000
L 5.1012498 2.27156614 5.10316673 2.27414892 1 P 0 ;0,1=598,2=0.000000
L 5.10316673 2.27414892 5.10393327 2.27776673 1 P 0 ;0,1=598,2=0.000000
L 5.10393327 2.27776673 5.10316673 2.28138268 1 P 0 ;0,1=598,2=0.000000
L 5.10316673 2.28138268 5.10086654 2.28448287 1 P 0 ;0,1=598,2=0.000000
L 5.10086654 2.28448287 5.09741654 2.28603356 1 P 0 ;0,1=598,2=0.000000
L 5.09741654 2.28603356 5.09358337 2.28603356 1 P 0 ;0,1=598,2=0.000000
L 5.09358337 2.28603356 5.09128317 2.28706663 1 P 0 ;0,1=598,2=0.000000
L 5.09128317 2.28706663 5.08936614 2.28964941 1 P 0 ;0,1=598,2=0.000000
L 5.08936614 2.28964941 5.0885997 2.29326624 1 P 0 ;0,1=598,2=0.000000
L 5.0885997 2.29326624 5.0897501 2.29688307 1 P 0 ;0,1=598,2=0.000000
L 5.0897501 2.29688307 5.09243287 2.29946683 1 P 0 ;0,1=598,2=0.000000
L 5.09243287 2.29946683 5.09549961 2.3005 1 P 0 ;0,1=598,2=0.000000
L 5.09549961 2.3005 5.09856634 2.29946683 1 P 0 ;0,1=598,2=0.000000
L 5.09856634 2.29946683 5.1012498 2.29688307 1 P 0 ;0,1=598,2=0.000000
L 5.1012498 2.29688307 5.1024002 2.29326624 1 P 0 ;0,1=598,2=0.000000
L 5.1024002 2.29326624 5.10163307 2.28964941 1 P 0 ;0,1=598,2=0.000000
L 5.10163307 2.28964941 5.09971673 2.28706663 1 P 0 ;0,1=598,2=0.000000
L 5.09971673 2.28706663 5.09741654 2.28603356 1 P 0 ;0,1=598,2=0.000000
L 5.09741654 2.28603356 5.09358337 2.28603356 1 P 0 ;0,1=598,2=0.000000
L 5.09358337 2.28603356 5.09013337 2.28448287 1 P 0 ;0,1=598,2=0.000000
L 5.09013337 2.28448287 5.08783317 2.28138268 1 P 0 ;0,1=598,2=0.000000
L 5.08783317 2.28138268 5.08706663 2.27776673 1 P 0 ;0,1=598,2=0.000000
L 5.08706663 2.27776673 5.08783317 2.27414892 1 P 0 ;0,1=598,2=0.000000
L 5.08783317 2.27414892 5.0897501 2.27156614 1 P 0 ;0,1=598,2=0.000000
L 5.0897501 2.27156614 5.09281683 2.27001654 1 P 0 ;0,1=598,2=0.000000
L 5.09281683 2.27001654 5.09549961 2.2695 1 P 0 ;0,1=598,2=0.000000
L 5.11806663 2.27569961 5.12036614 2.27208278 1 P 0 ;0,1=598,2=0.000000
L 5.12036614 2.27208278 5.12343287 2.27001654 1 P 0 ;0,1=598,2=0.000000
L 5.12343287 2.27001654 5.12688356 2.2695 1 P 0 ;0,1=598,2=0.000000
L 5.12688356 2.2695 5.1299503 2.27001654 1 P 0 ;0,1=598,2=0.000000
L 5.1299503 2.27001654 5.13301703 2.27259931 1 P 0 ;0,1=598,2=0.000000
L 5.13301703 2.27259931 5.13493327 2.27569961 1 P 0 ;0,1=598,2=0.000000
L 5.13493327 2.27569961 5.13531654 2.2787999 1 P 0 ;0,1=598,2=0.000000
L 5.13531654 2.2787999 5.13455 2.28241575 1 P 0 ;0,1=598,2=0.000000
L 5.13455 2.28241575 5.13186654 2.28499951 1 P 0 ;0,1=598,2=0.000000
L 5.13186654 2.28499951 5.12918307 2.28603356 1 P 0 ;0,1=598,2=0.000000
L 5.12918307 2.28603356 5.12573307 2.28603356 1 P 0 ;0,1=598,2=0.000000
L 5.12918307 2.28603356 5.13148327 2.28758317 1 P 0 ;0,1=598,2=0.000000
L 5.13148327 2.28758317 5.1334002 2.29016594 1 P 0 ;0,1=598,2=0.000000
L 5.1334002 2.29016594 5.13416673 2.29326624 1 P 0 ;0,1=598,2=0.000000
L 5.13416673 2.29326624 5.1334002 2.29636654 1 P 0 ;0,1=598,2=0.000000
L 5.1334002 2.29636654 5.13148327 2.29894931 1 P 0 ;0,1=598,2=0.000000
L 5.13148327 2.29894931 5.12803327 2.3005 1 P 0 ;0,1=598,2=0.000000
L 5.12803327 2.3005 5.12458337 2.29998337 1 P 0 ;0,1=598,2=0.000000
L 5.12458337 2.29998337 5.12113337 2.29791624 1 P 0 ;0,1=598,2=0.000000
L 5.794 0.634 5.794 0.724 1 P 0 
L 5.75 0.724 5.75 0.634 1 P 0 
L 5.75 0.634 5.794 0.634 1 P 0 
L 5.794 0.724 5.75 0.724 1 P 0 
L 5.83693327 0.62291624 5.83463307 0.62446683 1 P 0 ;0,1=599,2=0.000000
L 5.83463307 0.62446683 5.8319503 0.6255 1 P 0 ;0,1=599,2=0.000000
L 5.8319503 0.6255 5.82888356 0.6255 1 P 0 ;0,1=599,2=0.000000
L 5.82888356 0.6255 5.82543287 0.62394931 1 P 0 ;0,1=599,2=0.000000
L 5.82543287 0.62394931 5.8227501 0.62136654 1 P 0 ;0,1=599,2=0.000000
L 5.8227501 0.62136654 5.82083317 0.61826624 1 P 0 ;0,1=599,2=0.000000
L 5.82083317 0.61826624 5.81929951 0.6130998 1 P 0 ;0,1=599,2=0.000000
L 5.81929951 0.6130998 5.81891624 0.6084498 1 P 0 ;0,1=599,2=0.000000
L 5.81891624 0.6084498 5.81968337 0.6037999 1 P 0 ;0,1=599,2=0.000000
L 5.81968337 0.6037999 5.82083317 0.60069961 1 P 0 ;0,1=599,2=0.000000
L 5.82083317 0.60069961 5.82313337 0.59759931 1 P 0 ;0,1=599,2=0.000000
L 5.82313337 0.59759931 5.82581683 0.59553307 1 P 0 ;0,1=599,2=0.000000
L 5.82581683 0.59553307 5.82849961 0.5945 1 P 0 ;0,1=599,2=0.000000
L 5.82849961 0.5945 5.83118307 0.5945 1 P 0 ;0,1=599,2=0.000000
L 5.83118307 0.5945 5.83386654 0.59553307 1 P 0 ;0,1=599,2=0.000000
L 5.83386654 0.59553307 5.83616673 0.59708278 1 P 0 ;0,1=599,2=0.000000
L 5.83616673 0.59708278 5.83808366 0.59914892 1 P 0 ;0,1=599,2=0.000000
L 5.85221644 0.62033346 5.85451663 0.62343278 1 P 0 ;0,1=599,2=0.000000
L 5.85451663 0.62343278 5.8572001 0.62498337 1 P 0 ;0,1=599,2=0.000000
L 5.8572001 0.62498337 5.86026683 0.6255 1 P 0 ;0,1=599,2=0.000000
L 5.86026683 0.6255 5.8641 0.62446683 1 P 0 ;0,1=599,2=0.000000
L 5.8641 0.62446683 5.86678346 0.62188307 1 P 0 ;0,1=599,2=0.000000
L 5.86678346 0.62188307 5.86755 0.61878376 1 P 0 ;0,1=599,2=0.000000
L 5.86755 0.61878376 5.86716673 0.61568258 1 P 0 ;0,1=599,2=0.000000
L 5.86716673 0.61568258 5.86563307 0.6130998 1 P 0 ;0,1=599,2=0.000000
L 5.86563307 0.6130998 5.85796663 0.60793327 1 P 0 ;0,1=599,2=0.000000
L 5.85796663 0.60793327 5.85451663 0.60431644 1 P 0 ;0,1=599,2=0.000000
L 5.85451663 0.60431644 5.85221644 0.59914892 1 P 0 ;0,1=599,2=0.000000
L 5.85221644 0.59914892 5.8514499 0.5945 1 P 0 ;0,1=599,2=0.000000
L 5.8514499 0.5945 5.86755 0.5945 1 P 0 ;0,1=599,2=0.000000
L 5.88321644 0.62033346 5.88551663 0.62343278 1 P 0 ;0,1=599,2=0.000000
L 5.88551663 0.62343278 5.8882001 0.62498337 1 P 0 ;0,1=599,2=0.000000
L 5.8882001 0.62498337 5.89126683 0.6255 1 P 0 ;0,1=599,2=0.000000
L 5.89126683 0.6255 5.8951 0.62446683 1 P 0 ;0,1=599,2=0.000000
L 5.8951 0.62446683 5.89778346 0.62188307 1 P 0 ;0,1=599,2=0.000000
L 5.89778346 0.62188307 5.89855 0.61878376 1 P 0 ;0,1=599,2=0.000000
L 5.89855 0.61878376 5.89816673 0.61568258 1 P 0 ;0,1=599,2=0.000000
L 5.89816673 0.61568258 5.89663307 0.6130998 1 P 0 ;0,1=599,2=0.000000
L 5.89663307 0.6130998 5.88896663 0.60793327 1 P 0 ;0,1=599,2=0.000000
L 5.88896663 0.60793327 5.88551663 0.60431644 1 P 0 ;0,1=599,2=0.000000
L 5.88551663 0.60431644 5.88321644 0.59914892 1 P 0 ;0,1=599,2=0.000000
L 5.88321644 0.59914892 5.8824499 0.5945 1 P 0 ;0,1=599,2=0.000000
L 5.8824499 0.5945 5.89855 0.5945 1 P 0 ;0,1=599,2=0.000000
L 5.92073307 0.5945 5.92149961 0.60121614 1 P 0 ;0,1=599,2=0.000000
L 5.92149961 0.60121614 5.9226501 0.60689921 1 P 0 ;0,1=599,2=0.000000
L 5.9226501 0.60689921 5.92418307 0.61206663 1 P 0 ;0,1=599,2=0.000000
L 5.92418307 0.61206663 5.9261 0.6177497 1 P 0 ;0,1=599,2=0.000000
L 5.9261 0.6177497 5.92916673 0.6255 1 P 0 ;0,1=599,2=0.000000
L 5.92916673 0.6255 5.91383317 0.6255 1 P 0 ;0,1=599,2=0.000000
L 4.436 1.007 4.436 1.097 1 P 0 
L 4.436 1.097 4.392 1.097 1 P 0 
L 4.392 1.097 4.392 1.007 1 P 0 
L 4.392 1.007 4.436 1.007 1 P 0 
L 4.38708376 0.68193327 4.38553317 0.67963307 1 P 0 ;0,1=600,2=270.000000
L 4.38553317 0.67963307 4.3845 0.6769503 1 P 0 ;0,1=600,2=270.000000
L 4.3845 0.6769503 4.3845 0.67388356 1 P 0 ;0,1=600,2=270.000000
L 4.3845 0.67388356 4.38605069 0.67043287 1 P 0 ;0,1=600,2=270.000000
L 4.38605069 0.67043287 4.38863346 0.6677501 1 P 0 ;0,1=600,2=270.000000
L 4.38863346 0.6677501 4.39173376 0.66583317 1 P 0 ;0,1=600,2=270.000000
L 4.39173376 0.66583317 4.3969002 0.66429951 1 P 0 ;0,1=600,2=270.000000
L 4.3969002 0.66429951 4.4015502 0.66391624 1 P 0 ;0,1=600,2=270.000000
L 4.4015502 0.66391624 4.4062001 0.66468337 1 P 0 ;0,1=600,2=270.000000
L 4.4062001 0.66468337 4.40930039 0.66583317 1 P 0 ;0,1=600,2=270.000000
L 4.40930039 0.66583317 4.41240069 0.66813337 1 P 0 ;0,1=600,2=270.000000
L 4.41240069 0.66813337 4.41446693 0.67081683 1 P 0 ;0,1=600,2=270.000000
L 4.41446693 0.67081683 4.4155 0.67349961 1 P 0 ;0,1=600,2=270.000000
L 4.4155 0.67349961 4.4155 0.67618307 1 P 0 ;0,1=600,2=270.000000
L 4.4155 0.67618307 4.41446693 0.67886654 1 P 0 ;0,1=600,2=270.000000
L 4.41446693 0.67886654 4.41291722 0.68116673 1 P 0 ;0,1=600,2=270.000000
L 4.41291722 0.68116673 4.41085108 0.68308366 1 P 0 ;0,1=600,2=270.000000
L 4.38966654 0.69721644 4.38656722 0.69951663 1 P 0 ;0,1=600,2=270.000000
L 4.38656722 0.69951663 4.38501663 0.7022001 1 P 0 ;0,1=600,2=270.000000
L 4.38501663 0.7022001 4.3845 0.70526683 1 P 0 ;0,1=600,2=270.000000
L 4.3845 0.70526683 4.38553317 0.7091 1 P 0 ;0,1=600,2=270.000000
L 4.38553317 0.7091 4.38811693 0.71178346 1 P 0 ;0,1=600,2=270.000000
L 4.38811693 0.71178346 4.39121624 0.71255 1 P 0 ;0,1=600,2=270.000000
L 4.39121624 0.71255 4.39431742 0.71216673 1 P 0 ;0,1=600,2=270.000000
L 4.39431742 0.71216673 4.3969002 0.71063307 1 P 0 ;0,1=600,2=270.000000
L 4.3969002 0.71063307 4.40206673 0.70296663 1 P 0 ;0,1=600,2=270.000000
L 4.40206673 0.70296663 4.40568356 0.69951663 1 P 0 ;0,1=600,2=270.000000
L 4.40568356 0.69951663 4.41085108 0.69721644 1 P 0 ;0,1=600,2=270.000000
L 4.41085108 0.69721644 4.4155 0.6964499 1 P 0 ;0,1=600,2=270.000000
L 4.4155 0.6964499 4.4155 0.71255 1 P 0 ;0,1=600,2=270.000000
L 4.41085108 0.72706663 4.41343386 0.72936614 1 P 0 ;0,1=600,2=270.000000
L 4.41343386 0.72936614 4.41498346 0.73204961 1 P 0 ;0,1=600,2=270.000000
L 4.41498346 0.73204961 4.4155 0.73549961 1 P 0 ;0,1=600,2=270.000000
L 4.4155 0.73549961 4.41446693 0.7389503 1 P 0 ;0,1=600,2=270.000000
L 4.41446693 0.7389503 4.41240069 0.74163307 1 P 0 ;0,1=600,2=270.000000
L 4.41240069 0.74163307 4.40878386 0.74355 1 P 0 ;0,1=600,2=270.000000
L 4.40878386 0.74355 4.40465049 0.74393327 1 P 0 ;0,1=600,2=270.000000
L 4.40465049 0.74393327 4.40051713 0.74316673 1 P 0 ;0,1=600,2=270.000000
L 4.40051713 0.74316673 4.39793337 0.7412498 1 P 0 ;0,1=600,2=270.000000
L 4.39793337 0.7412498 4.39586713 0.73856634 1 P 0 ;0,1=600,2=270.000000
L 4.39586713 0.73856634 4.39535059 0.73588356 1 P 0 ;0,1=600,2=270.000000
L 4.39535059 0.73588356 4.39586713 0.7332001 1 P 0 ;0,1=600,2=270.000000
L 4.39586713 0.7332001 4.39793337 0.7297501 1 P 0 ;0,1=600,2=270.000000
L 4.39793337 0.7297501 4.3845 0.7308999 1 P 0 ;0,1=600,2=270.000000
L 4.3845 0.7308999 4.3845 0.7412498 1 P 0 ;0,1=600,2=270.000000
L 4.4155 0.76649961 4.3845 0.76649961 1 P 0 ;0,1=600,2=270.000000
L 4.3845 0.76649961 4.3906997 0.7618999 1 P 0 ;0,1=600,2=270.000000
L 4.4155 0.7618999 4.4155 0.77109931 1 P 0 ;0,1=600,2=270.000000
L 4.391 1.007 4.391 1.097 1 P 0 
L 4.391 1.097 4.347 1.097 1 P 0 
L 4.347 1.097 4.347 1.007 1 P 0 
L 4.347 1.007 4.391 1.007 1 P 0 
L 4.34208376 0.67693327 4.34053317 0.67463307 1 P 0 ;0,1=601,2=270.000000
L 4.34053317 0.67463307 4.3395 0.6719503 1 P 0 ;0,1=601,2=270.000000
L 4.3395 0.6719503 4.3395 0.66888356 1 P 0 ;0,1=601,2=270.000000
L 4.3395 0.66888356 4.34105069 0.66543287 1 P 0 ;0,1=601,2=270.000000
L 4.34105069 0.66543287 4.34363346 0.6627501 1 P 0 ;0,1=601,2=270.000000
L 4.34363346 0.6627501 4.34673376 0.66083317 1 P 0 ;0,1=601,2=270.000000
L 4.34673376 0.66083317 4.3519002 0.65929951 1 P 0 ;0,1=601,2=270.000000
L 4.3519002 0.65929951 4.3565502 0.65891624 1 P 0 ;0,1=601,2=270.000000
L 4.3565502 0.65891624 4.3612001 0.65968337 1 P 0 ;0,1=601,2=270.000000
L 4.3612001 0.65968337 4.36430039 0.66083317 1 P 0 ;0,1=601,2=270.000000
L 4.36430039 0.66083317 4.36740069 0.66313337 1 P 0 ;0,1=601,2=270.000000
L 4.36740069 0.66313337 4.36946693 0.66581683 1 P 0 ;0,1=601,2=270.000000
L 4.36946693 0.66581683 4.3705 0.66849961 1 P 0 ;0,1=601,2=270.000000
L 4.3705 0.66849961 4.3705 0.67118307 1 P 0 ;0,1=601,2=270.000000
L 4.3705 0.67118307 4.36946693 0.67386654 1 P 0 ;0,1=601,2=270.000000
L 4.36946693 0.67386654 4.36791722 0.67616673 1 P 0 ;0,1=601,2=270.000000
L 4.36791722 0.67616673 4.36585108 0.67808366 1 P 0 ;0,1=601,2=270.000000
L 4.34466654 0.69221644 4.34156722 0.69451663 1 P 0 ;0,1=601,2=270.000000
L 4.34156722 0.69451663 4.34001663 0.6972001 1 P 0 ;0,1=601,2=270.000000
L 4.34001663 0.6972001 4.3395 0.70026683 1 P 0 ;0,1=601,2=270.000000
L 4.3395 0.70026683 4.34053317 0.7041 1 P 0 ;0,1=601,2=270.000000
L 4.34053317 0.7041 4.34311693 0.70678346 1 P 0 ;0,1=601,2=270.000000
L 4.34311693 0.70678346 4.34621624 0.70755 1 P 0 ;0,1=601,2=270.000000
L 4.34621624 0.70755 4.34931742 0.70716673 1 P 0 ;0,1=601,2=270.000000
L 4.34931742 0.70716673 4.3519002 0.70563307 1 P 0 ;0,1=601,2=270.000000
L 4.3519002 0.70563307 4.35706673 0.69796663 1 P 0 ;0,1=601,2=270.000000
L 4.35706673 0.69796663 4.36068356 0.69451663 1 P 0 ;0,1=601,2=270.000000
L 4.36068356 0.69451663 4.36585108 0.69221644 1 P 0 ;0,1=601,2=270.000000
L 4.36585108 0.69221644 4.3705 0.6914499 1 P 0 ;0,1=601,2=270.000000
L 4.3705 0.6914499 4.3705 0.70755 1 P 0 ;0,1=601,2=270.000000
L 4.36585108 0.72206663 4.36843386 0.72436614 1 P 0 ;0,1=601,2=270.000000
L 4.36843386 0.72436614 4.36998346 0.72704961 1 P 0 ;0,1=601,2=270.000000
L 4.36998346 0.72704961 4.3705 0.73049961 1 P 0 ;0,1=601,2=270.000000
L 4.3705 0.73049961 4.36946693 0.7339503 1 P 0 ;0,1=601,2=270.000000
L 4.36946693 0.7339503 4.36740069 0.73663307 1 P 0 ;0,1=601,2=270.000000
L 4.36740069 0.73663307 4.36378386 0.73855 1 P 0 ;0,1=601,2=270.000000
L 4.36378386 0.73855 4.35965049 0.73893327 1 P 0 ;0,1=601,2=270.000000
L 4.35965049 0.73893327 4.35551713 0.73816673 1 P 0 ;0,1=601,2=270.000000
L 4.35551713 0.73816673 4.35293337 0.7362498 1 P 0 ;0,1=601,2=270.000000
L 4.35293337 0.7362498 4.35086713 0.73356634 1 P 0 ;0,1=601,2=270.000000
L 4.35086713 0.73356634 4.35035059 0.73088356 1 P 0 ;0,1=601,2=270.000000
L 4.35035059 0.73088356 4.35086713 0.7282001 1 P 0 ;0,1=601,2=270.000000
L 4.35086713 0.7282001 4.35293337 0.7247501 1 P 0 ;0,1=601,2=270.000000
L 4.35293337 0.7247501 4.3395 0.7258999 1 P 0 ;0,1=601,2=270.000000
L 4.3395 0.7258999 4.3395 0.7362498 1 P 0 ;0,1=601,2=270.000000
L 4.34466654 0.75421644 4.34156722 0.75651663 1 P 0 ;0,1=601,2=270.000000
L 4.34156722 0.75651663 4.34001663 0.7592001 1 P 0 ;0,1=601,2=270.000000
L 4.34001663 0.7592001 4.3395 0.76226683 1 P 0 ;0,1=601,2=270.000000
L 4.3395 0.76226683 4.34053317 0.7661 1 P 0 ;0,1=601,2=270.000000
L 4.34053317 0.7661 4.34311693 0.76878346 1 P 0 ;0,1=601,2=270.000000
L 4.34311693 0.76878346 4.34621624 0.76955 1 P 0 ;0,1=601,2=270.000000
L 4.34621624 0.76955 4.34931742 0.76916673 1 P 0 ;0,1=601,2=270.000000
L 4.34931742 0.76916673 4.3519002 0.76763307 1 P 0 ;0,1=601,2=270.000000
L 4.3519002 0.76763307 4.35706673 0.75996663 1 P 0 ;0,1=601,2=270.000000
L 4.35706673 0.75996663 4.36068356 0.75651663 1 P 0 ;0,1=601,2=270.000000
L 4.36068356 0.75651663 4.36585108 0.75421644 1 P 0 ;0,1=601,2=270.000000
L 4.36585108 0.75421644 4.3705 0.7534499 1 P 0 ;0,1=601,2=270.000000
L 4.3705 0.7534499 4.3705 0.76955 1 P 0 ;0,1=601,2=270.000000
L 5.593 0.77 5.593 0.814 1 P 0 
L 5.503 0.77 5.593 0.77 1 P 0 
L 5.593 0.814 5.503 0.814 1 P 0 
L 5.503 0.814 5.503 0.77 1 P 0 
L 5.35693327 0.85791624 5.35463307 0.85946683 1 P 0 ;0,1=602,2=0.000000
L 5.35463307 0.85946683 5.3519503 0.8605 1 P 0 ;0,1=602,2=0.000000
L 5.3519503 0.8605 5.34888356 0.8605 1 P 0 ;0,1=602,2=0.000000
L 5.34888356 0.8605 5.34543287 0.85894931 1 P 0 ;0,1=602,2=0.000000
L 5.34543287 0.85894931 5.3427501 0.85636654 1 P 0 ;0,1=602,2=0.000000
L 5.3427501 0.85636654 5.34083317 0.85326624 1 P 0 ;0,1=602,2=0.000000
L 5.34083317 0.85326624 5.33929951 0.8480998 1 P 0 ;0,1=602,2=0.000000
L 5.33929951 0.8480998 5.33891624 0.8434498 1 P 0 ;0,1=602,2=0.000000
L 5.33891624 0.8434498 5.33968337 0.8387999 1 P 0 ;0,1=602,2=0.000000
L 5.33968337 0.8387999 5.34083317 0.83569961 1 P 0 ;0,1=602,2=0.000000
L 5.34083317 0.83569961 5.34313337 0.83259931 1 P 0 ;0,1=602,2=0.000000
L 5.34313337 0.83259931 5.34581683 0.83053307 1 P 0 ;0,1=602,2=0.000000
L 5.34581683 0.83053307 5.34849961 0.8295 1 P 0 ;0,1=602,2=0.000000
L 5.34849961 0.8295 5.35118307 0.8295 1 P 0 ;0,1=602,2=0.000000
L 5.35118307 0.8295 5.35386654 0.83053307 1 P 0 ;0,1=602,2=0.000000
L 5.35386654 0.83053307 5.35616673 0.83208278 1 P 0 ;0,1=602,2=0.000000
L 5.35616673 0.83208278 5.35808366 0.83414892 1 P 0 ;0,1=602,2=0.000000
L 5.37221644 0.85533346 5.37451663 0.85843278 1 P 0 ;0,1=602,2=0.000000
L 5.37451663 0.85843278 5.3772001 0.85998337 1 P 0 ;0,1=602,2=0.000000
L 5.3772001 0.85998337 5.38026683 0.8605 1 P 0 ;0,1=602,2=0.000000
L 5.38026683 0.8605 5.3841 0.85946683 1 P 0 ;0,1=602,2=0.000000
L 5.3841 0.85946683 5.38678346 0.85688307 1 P 0 ;0,1=602,2=0.000000
L 5.38678346 0.85688307 5.38755 0.85378376 1 P 0 ;0,1=602,2=0.000000
L 5.38755 0.85378376 5.38716673 0.85068258 1 P 0 ;0,1=602,2=0.000000
L 5.38716673 0.85068258 5.38563307 0.8480998 1 P 0 ;0,1=602,2=0.000000
L 5.38563307 0.8480998 5.37796663 0.84293327 1 P 0 ;0,1=602,2=0.000000
L 5.37796663 0.84293327 5.37451663 0.83931644 1 P 0 ;0,1=602,2=0.000000
L 5.37451663 0.83931644 5.37221644 0.83414892 1 P 0 ;0,1=602,2=0.000000
L 5.37221644 0.83414892 5.3714499 0.8295 1 P 0 ;0,1=602,2=0.000000
L 5.3714499 0.8295 5.38755 0.8295 1 P 0 ;0,1=602,2=0.000000
L 5.4151 0.8295 5.4151 0.8605 1 P 0 ;0,1=602,2=0.000000
L 5.4151 0.8605 5.40091624 0.83828327 1 P 0 ;0,1=602,2=0.000000
L 5.40091624 0.83828327 5.42008366 0.83828327 1 P 0 ;0,1=602,2=0.000000
L 5.43421644 0.85533346 5.43651663 0.85843278 1 P 0 ;0,1=602,2=0.000000
L 5.43651663 0.85843278 5.4392001 0.85998337 1 P 0 ;0,1=602,2=0.000000
L 5.4392001 0.85998337 5.44226683 0.8605 1 P 0 ;0,1=602,2=0.000000
L 5.44226683 0.8605 5.4461 0.85946683 1 P 0 ;0,1=602,2=0.000000
L 5.4461 0.85946683 5.44878346 0.85688307 1 P 0 ;0,1=602,2=0.000000
L 5.44878346 0.85688307 5.44955 0.85378376 1 P 0 ;0,1=602,2=0.000000
L 5.44955 0.85378376 5.44916673 0.85068258 1 P 0 ;0,1=602,2=0.000000
L 5.44916673 0.85068258 5.44763307 0.8480998 1 P 0 ;0,1=602,2=0.000000
L 5.44763307 0.8480998 5.43996663 0.84293327 1 P 0 ;0,1=602,2=0.000000
L 5.43996663 0.84293327 5.43651663 0.83931644 1 P 0 ;0,1=602,2=0.000000
L 5.43651663 0.83931644 5.43421644 0.83414892 1 P 0 ;0,1=602,2=0.000000
L 5.43421644 0.83414892 5.4334499 0.8295 1 P 0 ;0,1=602,2=0.000000
L 5.4334499 0.8295 5.44955 0.8295 1 P 0 ;0,1=602,2=0.000000
L 5.715 0.814 5.625 0.814 1 P 0 
L 5.625 0.814 5.625 0.77 1 P 0 
L 5.625 0.77 5.715 0.77 1 P 0 
L 5.715 0.77 5.715 0.814 1 P 0 
L 5.75193327 0.86291624 5.74963307 0.86446683 1 P 0 ;0,1=603,2=0.000000
L 5.74963307 0.86446683 5.7469503 0.8655 1 P 0 ;0,1=603,2=0.000000
L 5.7469503 0.8655 5.74388356 0.8655 1 P 0 ;0,1=603,2=0.000000
L 5.74388356 0.8655 5.74043287 0.86394931 1 P 0 ;0,1=603,2=0.000000
L 5.74043287 0.86394931 5.7377501 0.86136654 1 P 0 ;0,1=603,2=0.000000
L 5.7377501 0.86136654 5.73583317 0.85826624 1 P 0 ;0,1=603,2=0.000000
L 5.73583317 0.85826624 5.73429951 0.8530998 1 P 0 ;0,1=603,2=0.000000
L 5.73429951 0.8530998 5.73391624 0.8484498 1 P 0 ;0,1=603,2=0.000000
L 5.73391624 0.8484498 5.73468337 0.8437999 1 P 0 ;0,1=603,2=0.000000
L 5.73468337 0.8437999 5.73583317 0.84069961 1 P 0 ;0,1=603,2=0.000000
L 5.73583317 0.84069961 5.73813337 0.83759931 1 P 0 ;0,1=603,2=0.000000
L 5.73813337 0.83759931 5.74081683 0.83553307 1 P 0 ;0,1=603,2=0.000000
L 5.74081683 0.83553307 5.74349961 0.8345 1 P 0 ;0,1=603,2=0.000000
L 5.74349961 0.8345 5.74618307 0.8345 1 P 0 ;0,1=603,2=0.000000
L 5.74618307 0.8345 5.74886654 0.83553307 1 P 0 ;0,1=603,2=0.000000
L 5.74886654 0.83553307 5.75116673 0.83708278 1 P 0 ;0,1=603,2=0.000000
L 5.75116673 0.83708278 5.75308366 0.83914892 1 P 0 ;0,1=603,2=0.000000
L 5.76721644 0.86033346 5.76951663 0.86343278 1 P 0 ;0,1=603,2=0.000000
L 5.76951663 0.86343278 5.7722001 0.86498337 1 P 0 ;0,1=603,2=0.000000
L 5.7722001 0.86498337 5.77526683 0.8655 1 P 0 ;0,1=603,2=0.000000
L 5.77526683 0.8655 5.7791 0.86446683 1 P 0 ;0,1=603,2=0.000000
L 5.7791 0.86446683 5.78178346 0.86188307 1 P 0 ;0,1=603,2=0.000000
L 5.78178346 0.86188307 5.78255 0.85878376 1 P 0 ;0,1=603,2=0.000000
L 5.78255 0.85878376 5.78216673 0.85568258 1 P 0 ;0,1=603,2=0.000000
L 5.78216673 0.85568258 5.78063307 0.8530998 1 P 0 ;0,1=603,2=0.000000
L 5.78063307 0.8530998 5.77296663 0.84793327 1 P 0 ;0,1=603,2=0.000000
L 5.77296663 0.84793327 5.76951663 0.84431644 1 P 0 ;0,1=603,2=0.000000
L 5.76951663 0.84431644 5.76721644 0.83914892 1 P 0 ;0,1=603,2=0.000000
L 5.76721644 0.83914892 5.7664499 0.8345 1 P 0 ;0,1=603,2=0.000000
L 5.7664499 0.8345 5.78255 0.8345 1 P 0 ;0,1=603,2=0.000000
L 5.79706663 0.84069961 5.79936614 0.83708278 1 P 0 ;0,1=603,2=0.000000
L 5.79936614 0.83708278 5.80243287 0.83501654 1 P 0 ;0,1=603,2=0.000000
L 5.80243287 0.83501654 5.80588356 0.8345 1 P 0 ;0,1=603,2=0.000000
L 5.80588356 0.8345 5.8089503 0.83501654 1 P 0 ;0,1=603,2=0.000000
L 5.8089503 0.83501654 5.81201703 0.83759931 1 P 0 ;0,1=603,2=0.000000
L 5.81201703 0.83759931 5.81393327 0.84069961 1 P 0 ;0,1=603,2=0.000000
L 5.81393327 0.84069961 5.81431654 0.8437999 1 P 0 ;0,1=603,2=0.000000
L 5.81431654 0.8437999 5.81355 0.84741575 1 P 0 ;0,1=603,2=0.000000
L 5.81355 0.84741575 5.81086654 0.84999951 1 P 0 ;0,1=603,2=0.000000
L 5.81086654 0.84999951 5.80818307 0.85103356 1 P 0 ;0,1=603,2=0.000000
L 5.80818307 0.85103356 5.80473307 0.85103356 1 P 0 ;0,1=603,2=0.000000
L 5.80818307 0.85103356 5.81048327 0.85258317 1 P 0 ;0,1=603,2=0.000000
L 5.81048327 0.85258317 5.8124002 0.85516594 1 P 0 ;0,1=603,2=0.000000
L 5.8124002 0.85516594 5.81316673 0.85826624 1 P 0 ;0,1=603,2=0.000000
L 5.81316673 0.85826624 5.8124002 0.86136654 1 P 0 ;0,1=603,2=0.000000
L 5.8124002 0.86136654 5.81048327 0.86394931 1 P 0 ;0,1=603,2=0.000000
L 5.81048327 0.86394931 5.80703327 0.8655 1 P 0 ;0,1=603,2=0.000000
L 5.80703327 0.8655 5.80358337 0.86498337 1 P 0 ;0,1=603,2=0.000000
L 5.80358337 0.86498337 5.80013337 0.86291624 1 P 0 ;0,1=603,2=0.000000
L 5.83649961 0.8655 5.83343287 0.86446683 1 P 0 ;0,1=603,2=0.000000
L 5.83343287 0.86446683 5.83113337 0.86188307 1 P 0 ;0,1=603,2=0.000000
L 5.83113337 0.86188307 5.8295997 0.85878376 1 P 0 ;0,1=603,2=0.000000
L 5.8295997 0.85878376 5.8284499 0.85464941 1 P 0 ;0,1=603,2=0.000000
L 5.8284499 0.85464941 5.82806663 0.84999951 1 P 0 ;0,1=603,2=0.000000
L 5.82806663 0.84999951 5.8284499 0.84534951 1 P 0 ;0,1=603,2=0.000000
L 5.8284499 0.84534951 5.8295997 0.84121614 1 P 0 ;0,1=603,2=0.000000
L 5.8295997 0.84121614 5.83113337 0.83811585 1 P 0 ;0,1=603,2=0.000000
L 5.83113337 0.83811585 5.83343287 0.83553307 1 P 0 ;0,1=603,2=0.000000
L 5.83343287 0.83553307 5.83649961 0.8345 1 P 0 ;0,1=603,2=0.000000
L 5.83649961 0.8345 5.83956634 0.83553307 1 P 0 ;0,1=603,2=0.000000
L 5.83956634 0.83553307 5.84186654 0.83811585 1 P 0 ;0,1=603,2=0.000000
L 5.84186654 0.83811585 5.8434002 0.84121614 1 P 0 ;0,1=603,2=0.000000
L 5.8434002 0.84121614 5.84455 0.84534951 1 P 0 ;0,1=603,2=0.000000
L 5.84455 0.84534951 5.84493327 0.84999951 1 P 0 ;0,1=603,2=0.000000
L 5.84493327 0.84999951 5.84455 0.85464941 1 P 0 ;0,1=603,2=0.000000
L 5.84455 0.85464941 5.8434002 0.85878376 1 P 0 ;0,1=603,2=0.000000
L 5.8434002 0.85878376 5.84186654 0.86188307 1 P 0 ;0,1=603,2=0.000000
L 5.84186654 0.86188307 5.83956634 0.86446683 1 P 0 ;0,1=603,2=0.000000
L 5.83956634 0.86446683 5.83649961 0.8655 1 P 0 ;0,1=603,2=0.000000
L 5.662 1.01 5.618 1.01 1 P 0 
L 5.618 1.01 5.618 0.92 1 P 0 
L 5.618 0.92 5.662 0.92 1 P 0 
L 5.662 0.92 5.662 1.01 1 P 0 
L 5.62208376 1.06193327 5.62053317 1.05963307 1 P 0 ;0,1=604,2=270.000000
L 5.62053317 1.05963307 5.6195 1.0569503 1 P 0 ;0,1=604,2=270.000000
L 5.6195 1.0569503 5.6195 1.05388356 1 P 0 ;0,1=604,2=270.000000
L 5.6195 1.05388356 5.62105069 1.05043287 1 P 0 ;0,1=604,2=270.000000
L 5.62105069 1.05043287 5.62363346 1.0477501 1 P 0 ;0,1=604,2=270.000000
L 5.62363346 1.0477501 5.62673376 1.04583317 1 P 0 ;0,1=604,2=270.000000
L 5.62673376 1.04583317 5.6319002 1.04429951 1 P 0 ;0,1=604,2=270.000000
L 5.6319002 1.04429951 5.6365502 1.04391624 1 P 0 ;0,1=604,2=270.000000
L 5.6365502 1.04391624 5.6412001 1.04468337 1 P 0 ;0,1=604,2=270.000000
L 5.6412001 1.04468337 5.64430039 1.04583317 1 P 0 ;0,1=604,2=270.000000
L 5.64430039 1.04583317 5.64740069 1.04813337 1 P 0 ;0,1=604,2=270.000000
L 5.64740069 1.04813337 5.64946693 1.05081683 1 P 0 ;0,1=604,2=270.000000
L 5.64946693 1.05081683 5.6505 1.05349961 1 P 0 ;0,1=604,2=270.000000
L 5.6505 1.05349961 5.6505 1.05618307 1 P 0 ;0,1=604,2=270.000000
L 5.6505 1.05618307 5.64946693 1.05886654 1 P 0 ;0,1=604,2=270.000000
L 5.64946693 1.05886654 5.64791722 1.06116673 1 P 0 ;0,1=604,2=270.000000
L 5.64791722 1.06116673 5.64585108 1.06308366 1 P 0 ;0,1=604,2=270.000000
L 5.62466654 1.07721644 5.62156722 1.07951663 1 P 0 ;0,1=604,2=270.000000
L 5.62156722 1.07951663 5.62001663 1.0822001 1 P 0 ;0,1=604,2=270.000000
L 5.62001663 1.0822001 5.6195 1.08526683 1 P 0 ;0,1=604,2=270.000000
L 5.6195 1.08526683 5.62053317 1.0891 1 P 0 ;0,1=604,2=270.000000
L 5.62053317 1.0891 5.62311693 1.09178346 1 P 0 ;0,1=604,2=270.000000
L 5.62311693 1.09178346 5.62621624 1.09255 1 P 0 ;0,1=604,2=270.000000
L 5.62621624 1.09255 5.62931742 1.09216673 1 P 0 ;0,1=604,2=270.000000
L 5.62931742 1.09216673 5.6319002 1.09063307 1 P 0 ;0,1=604,2=270.000000
L 5.6319002 1.09063307 5.63706673 1.08296663 1 P 0 ;0,1=604,2=270.000000
L 5.63706673 1.08296663 5.64068356 1.07951663 1 P 0 ;0,1=604,2=270.000000
L 5.64068356 1.07951663 5.64585108 1.07721644 1 P 0 ;0,1=604,2=270.000000
L 5.64585108 1.07721644 5.6505 1.0764499 1 P 0 ;0,1=604,2=270.000000
L 5.6505 1.0764499 5.6505 1.09255 1 P 0 ;0,1=604,2=270.000000
L 5.62466654 1.10821644 5.62156722 1.11051663 1 P 0 ;0,1=604,2=270.000000
L 5.62156722 1.11051663 5.62001663 1.1132001 1 P 0 ;0,1=604,2=270.000000
L 5.62001663 1.1132001 5.6195 1.11626683 1 P 0 ;0,1=604,2=270.000000
L 5.6195 1.11626683 5.62053317 1.1201 1 P 0 ;0,1=604,2=270.000000
L 5.62053317 1.1201 5.62311693 1.12278346 1 P 0 ;0,1=604,2=270.000000
L 5.62311693 1.12278346 5.62621624 1.12355 1 P 0 ;0,1=604,2=270.000000
L 5.62621624 1.12355 5.62931742 1.12316673 1 P 0 ;0,1=604,2=270.000000
L 5.62931742 1.12316673 5.6319002 1.12163307 1 P 0 ;0,1=604,2=270.000000
L 5.6319002 1.12163307 5.63706673 1.11396663 1 P 0 ;0,1=604,2=270.000000
L 5.63706673 1.11396663 5.64068356 1.11051663 1 P 0 ;0,1=604,2=270.000000
L 5.64068356 1.11051663 5.64585108 1.10821644 1 P 0 ;0,1=604,2=270.000000
L 5.64585108 1.10821644 5.6505 1.1074499 1 P 0 ;0,1=604,2=270.000000
L 5.6505 1.1074499 5.6505 1.12355 1 P 0 ;0,1=604,2=270.000000
L 5.63758425 1.13921644 5.63396644 1.1418999 1 P 0 ;0,1=604,2=270.000000
L 5.63396644 1.1418999 5.6319002 1.1442001 1 P 0 ;0,1=604,2=270.000000
L 5.6319002 1.1442001 5.63086713 1.14726683 1 P 0 ;0,1=604,2=270.000000
L 5.63086713 1.14726683 5.6319002 1.1499503 1 P 0 ;0,1=604,2=270.000000
L 5.6319002 1.1499503 5.63396644 1.15186654 1 P 0 ;0,1=604,2=270.000000
L 5.63396644 1.15186654 5.63706673 1.1534002 1 P 0 ;0,1=604,2=270.000000
L 5.63706673 1.1534002 5.64068356 1.15378346 1 P 0 ;0,1=604,2=270.000000
L 5.64068356 1.15378346 5.64378386 1.1534002 1 P 0 ;0,1=604,2=270.000000
L 5.64378386 1.1534002 5.64688415 1.15186654 1 P 0 ;0,1=604,2=270.000000
L 5.64688415 1.15186654 5.64946693 1.14956634 1 P 0 ;0,1=604,2=270.000000
L 5.64946693 1.14956634 5.6505 1.14688356 1 P 0 ;0,1=604,2=270.000000
L 5.6505 1.14688356 5.64946693 1.14381683 1 P 0 ;0,1=604,2=270.000000
L 5.64946693 1.14381683 5.64636762 1.14113337 1 P 0 ;0,1=604,2=270.000000
L 5.64636762 1.14113337 5.64171673 1.1395997 1 P 0 ;0,1=604,2=270.000000
L 5.64171673 1.1395997 5.6365502 1.13921644 1 P 0 ;0,1=604,2=270.000000
L 5.6365502 1.13921644 5.62983406 1.13998287 1 P 0 ;0,1=604,2=270.000000
L 5.62983406 1.13998287 5.62621624 1.14113337 1 P 0 ;0,1=604,2=270.000000
L 5.62621624 1.14113337 5.6226003 1.14304961 1 P 0 ;0,1=604,2=270.000000
L 5.6226003 1.14304961 5.62001663 1.14573307 1 P 0 ;0,1=604,2=270.000000
L 5.62001663 1.14573307 5.6195 1.14841654 1 P 0 ;0,1=604,2=270.000000
L 5.6195 1.14841654 5.62053317 1.1511 1 P 0 ;0,1=604,2=270.000000
L 5.62053317 1.1511 5.62311693 1.15301703 1 P 0 ;0,1=604,2=270.000000
L 3.277 3.73 3.233 3.73 1 P 0 
L 3.277 3.64 3.277 3.73 1 P 0 
L 3.233 3.73 3.233 3.64 1 P 0 
L 3.233 3.64 3.277 3.64 1 P 0 
L 3.10708376 3.51243327 3.10553317 3.51013307 1 P 0 ;0,1=605,2=270.000000
L 3.10553317 3.51013307 3.1045 3.5074503 1 P 0 ;0,1=605,2=270.000000
L 3.1045 3.5074503 3.1045 3.50438356 1 P 0 ;0,1=605,2=270.000000
L 3.1045 3.50438356 3.10605069 3.50093287 1 P 0 ;0,1=605,2=270.000000
L 3.10605069 3.50093287 3.10863346 3.4982501 1 P 0 ;0,1=605,2=270.000000
L 3.10863346 3.4982501 3.11173376 3.49633317 1 P 0 ;0,1=605,2=270.000000
L 3.11173376 3.49633317 3.1169002 3.49479951 1 P 0 ;0,1=605,2=270.000000
L 3.1169002 3.49479951 3.1215502 3.49441624 1 P 0 ;0,1=605,2=270.000000
L 3.1215502 3.49441624 3.1262001 3.49518337 1 P 0 ;0,1=605,2=270.000000
L 3.1262001 3.49518337 3.12930039 3.49633317 1 P 0 ;0,1=605,2=270.000000
L 3.12930039 3.49633317 3.13240069 3.49863337 1 P 0 ;0,1=605,2=270.000000
L 3.13240069 3.49863337 3.13446693 3.50131683 1 P 0 ;0,1=605,2=270.000000
L 3.13446693 3.50131683 3.1355 3.50399961 1 P 0 ;0,1=605,2=270.000000
L 3.1355 3.50399961 3.1355 3.50668307 1 P 0 ;0,1=605,2=270.000000
L 3.1355 3.50668307 3.13446693 3.50936654 1 P 0 ;0,1=605,2=270.000000
L 3.13446693 3.50936654 3.13291722 3.51166673 1 P 0 ;0,1=605,2=270.000000
L 3.13291722 3.51166673 3.13085108 3.51358366 1 P 0 ;0,1=605,2=270.000000
L 3.1355 3.53499961 3.1045 3.53499961 1 P 0 ;0,1=605,2=270.000000
L 3.1045 3.53499961 3.1106997 3.5303999 1 P 0 ;0,1=605,2=270.000000
L 3.1355 3.5303999 3.1355 3.53959931 1 P 0 ;0,1=605,2=270.000000
L 3.1355 3.56599961 3.13498346 3.56868307 1 P 0 ;0,1=605,2=270.000000
L 3.13498346 3.56868307 3.13343386 3.5717498 1 P 0 ;0,1=605,2=270.000000
L 3.13343386 3.5717498 3.13085108 3.57366673 1 P 0 ;0,1=605,2=270.000000
L 3.13085108 3.57366673 3.12723327 3.57443327 1 P 0 ;0,1=605,2=270.000000
L 3.12723327 3.57443327 3.12361732 3.57366673 1 P 0 ;0,1=605,2=270.000000
L 3.12361732 3.57366673 3.12051713 3.57136654 1 P 0 ;0,1=605,2=270.000000
L 3.12051713 3.57136654 3.11896644 3.56791654 1 P 0 ;0,1=605,2=270.000000
L 3.11896644 3.56791654 3.11896644 3.56408337 1 P 0 ;0,1=605,2=270.000000
L 3.11896644 3.56408337 3.11793337 3.56178317 1 P 0 ;0,1=605,2=270.000000
L 3.11793337 3.56178317 3.11535059 3.55986614 1 P 0 ;0,1=605,2=270.000000
L 3.11535059 3.55986614 3.11173376 3.5590997 1 P 0 ;0,1=605,2=270.000000
L 3.11173376 3.5590997 3.10811693 3.5602501 1 P 0 ;0,1=605,2=270.000000
L 3.10811693 3.5602501 3.10553317 3.56293287 1 P 0 ;0,1=605,2=270.000000
L 3.10553317 3.56293287 3.1045 3.56599961 1 P 0 ;0,1=605,2=270.000000
L 3.1045 3.56599961 3.10553317 3.56906634 1 P 0 ;0,1=605,2=270.000000
L 3.10553317 3.56906634 3.10811693 3.5717498 1 P 0 ;0,1=605,2=270.000000
L 3.10811693 3.5717498 3.11173376 3.5729002 1 P 0 ;0,1=605,2=270.000000
L 3.11173376 3.5729002 3.11535059 3.57213307 1 P 0 ;0,1=605,2=270.000000
L 3.11535059 3.57213307 3.11793337 3.57021673 1 P 0 ;0,1=605,2=270.000000
L 3.11793337 3.57021673 3.11896644 3.56791654 1 P 0 ;0,1=605,2=270.000000
L 3.11896644 3.56791654 3.11896644 3.56408337 1 P 0 ;0,1=605,2=270.000000
L 3.11896644 3.56408337 3.12051713 3.56063337 1 P 0 ;0,1=605,2=270.000000
L 3.12051713 3.56063337 3.12361732 3.55833317 1 P 0 ;0,1=605,2=270.000000
L 3.12361732 3.55833317 3.12723327 3.55756663 1 P 0 ;0,1=605,2=270.000000
L 3.12723327 3.55756663 3.13085108 3.55833317 1 P 0 ;0,1=605,2=270.000000
L 3.13085108 3.55833317 3.13343386 3.5602501 1 P 0 ;0,1=605,2=270.000000
L 3.13343386 3.5602501 3.13498346 3.56331683 1 P 0 ;0,1=605,2=270.000000
L 3.13498346 3.56331683 3.1355 3.56599961 1 P 0 ;0,1=605,2=270.000000
L 3.373 3.865 3.373 3.909 1 P 0 
L 3.373 3.909 3.283 3.909 1 P 0 
L 3.283 3.909 3.283 3.865 1 P 0 
L 3.283 3.865 3.373 3.865 1 P 0 
L 3.12243327 3.65791624 3.12013307 3.65946683 1 P 0 ;0,1=606,2=0.000000
L 3.12013307 3.65946683 3.1174503 3.6605 1 P 0 ;0,1=606,2=0.000000
L 3.1174503 3.6605 3.11438356 3.6605 1 P 0 ;0,1=606,2=0.000000
L 3.11438356 3.6605 3.11093287 3.65894931 1 P 0 ;0,1=606,2=0.000000
L 3.11093287 3.65894931 3.1082501 3.65636654 1 P 0 ;0,1=606,2=0.000000
L 3.1082501 3.65636654 3.10633317 3.65326624 1 P 0 ;0,1=606,2=0.000000
L 3.10633317 3.65326624 3.10479951 3.6480998 1 P 0 ;0,1=606,2=0.000000
L 3.10479951 3.6480998 3.10441624 3.6434498 1 P 0 ;0,1=606,2=0.000000
L 3.10441624 3.6434498 3.10518337 3.6387999 1 P 0 ;0,1=606,2=0.000000
L 3.10518337 3.6387999 3.10633317 3.63569961 1 P 0 ;0,1=606,2=0.000000
L 3.10633317 3.63569961 3.10863337 3.63259931 1 P 0 ;0,1=606,2=0.000000
L 3.10863337 3.63259931 3.11131683 3.63053307 1 P 0 ;0,1=606,2=0.000000
L 3.11131683 3.63053307 3.11399961 3.6295 1 P 0 ;0,1=606,2=0.000000
L 3.11399961 3.6295 3.11668307 3.6295 1 P 0 ;0,1=606,2=0.000000
L 3.11668307 3.6295 3.11936654 3.63053307 1 P 0 ;0,1=606,2=0.000000
L 3.11936654 3.63053307 3.12166673 3.63208278 1 P 0 ;0,1=606,2=0.000000
L 3.12166673 3.63208278 3.12358366 3.63414892 1 P 0 ;0,1=606,2=0.000000
L 3.13656663 3.63414892 3.13886614 3.63156614 1 P 0 ;0,1=606,2=0.000000
L 3.13886614 3.63156614 3.14154961 3.63001654 1 P 0 ;0,1=606,2=0.000000
L 3.14154961 3.63001654 3.14499961 3.6295 1 P 0 ;0,1=606,2=0.000000
L 3.14499961 3.6295 3.1484503 3.63053307 1 P 0 ;0,1=606,2=0.000000
L 3.1484503 3.63053307 3.15113307 3.63259931 1 P 0 ;0,1=606,2=0.000000
L 3.15113307 3.63259931 3.15305 3.63621614 1 P 0 ;0,1=606,2=0.000000
L 3.15305 3.63621614 3.15343327 3.64034951 1 P 0 ;0,1=606,2=0.000000
L 3.15343327 3.64034951 3.15266673 3.64448287 1 P 0 ;0,1=606,2=0.000000
L 3.15266673 3.64448287 3.1507498 3.64706663 1 P 0 ;0,1=606,2=0.000000
L 3.1507498 3.64706663 3.14806634 3.64913287 1 P 0 ;0,1=606,2=0.000000
L 3.14806634 3.64913287 3.14538356 3.64964941 1 P 0 ;0,1=606,2=0.000000
L 3.14538356 3.64964941 3.1427001 3.64913287 1 P 0 ;0,1=606,2=0.000000
L 3.1427001 3.64913287 3.1392501 3.64706663 1 P 0 ;0,1=606,2=0.000000
L 3.1392501 3.64706663 3.1403999 3.6605 1 P 0 ;0,1=606,2=0.000000
L 3.1403999 3.6605 3.1507498 3.6605 1 P 0 ;0,1=606,2=0.000000
L 3.16871644 3.65533346 3.17101663 3.65843278 1 P 0 ;0,1=606,2=0.000000
L 3.17101663 3.65843278 3.1737001 3.65998337 1 P 0 ;0,1=606,2=0.000000
L 3.1737001 3.65998337 3.17676683 3.6605 1 P 0 ;0,1=606,2=0.000000
L 3.17676683 3.6605 3.1806 3.65946683 1 P 0 ;0,1=606,2=0.000000
L 3.1806 3.65946683 3.18328346 3.65688307 1 P 0 ;0,1=606,2=0.000000
L 3.18328346 3.65688307 3.18405 3.65378376 1 P 0 ;0,1=606,2=0.000000
L 3.18405 3.65378376 3.18366673 3.65068258 1 P 0 ;0,1=606,2=0.000000
L 3.18366673 3.65068258 3.18213307 3.6480998 1 P 0 ;0,1=606,2=0.000000
L 3.18213307 3.6480998 3.17446663 3.64293327 1 P 0 ;0,1=606,2=0.000000
L 3.17446663 3.64293327 3.17101663 3.63931644 1 P 0 ;0,1=606,2=0.000000
L 3.17101663 3.63931644 3.16871644 3.63414892 1 P 0 ;0,1=606,2=0.000000
L 3.16871644 3.63414892 3.1679499 3.6295 1 P 0 ;0,1=606,2=0.000000
L 3.1679499 3.6295 3.18405 3.6295 1 P 0 ;0,1=606,2=0.000000
L 4.59 2.923 4.59 2.967 1 P 0 
L 4.5 2.923 4.59 2.923 1 P 0 
L 4.59 2.967 4.5 2.967 1 P 0 
L 4.5 2.967 4.5 2.923 1 P 0 
L 4.63693327 2.94291624 4.63463307 2.94446683 1 P 0 ;0,1=607,2=0.000000
L 4.63463307 2.94446683 4.6319503 2.9455 1 P 0 ;0,1=607,2=0.000000
L 4.6319503 2.9455 4.62888356 2.9455 1 P 0 ;0,1=607,2=0.000000
L 4.62888356 2.9455 4.62543287 2.94394931 1 P 0 ;0,1=607,2=0.000000
L 4.62543287 2.94394931 4.6227501 2.94136654 1 P 0 ;0,1=607,2=0.000000
L 4.6227501 2.94136654 4.62083317 2.93826624 1 P 0 ;0,1=607,2=0.000000
L 4.62083317 2.93826624 4.61929951 2.9330998 1 P 0 ;0,1=607,2=0.000000
L 4.61929951 2.9330998 4.61891624 2.9284498 1 P 0 ;0,1=607,2=0.000000
L 4.61891624 2.9284498 4.61968337 2.9237999 1 P 0 ;0,1=607,2=0.000000
L 4.61968337 2.9237999 4.62083317 2.92069961 1 P 0 ;0,1=607,2=0.000000
L 4.62083317 2.92069961 4.62313337 2.91759931 1 P 0 ;0,1=607,2=0.000000
L 4.62313337 2.91759931 4.62581683 2.91553307 1 P 0 ;0,1=607,2=0.000000
L 4.62581683 2.91553307 4.62849961 2.9145 1 P 0 ;0,1=607,2=0.000000
L 4.62849961 2.9145 4.63118307 2.9145 1 P 0 ;0,1=607,2=0.000000
L 4.63118307 2.9145 4.63386654 2.91553307 1 P 0 ;0,1=607,2=0.000000
L 4.63386654 2.91553307 4.63616673 2.91708278 1 P 0 ;0,1=607,2=0.000000
L 4.63616673 2.91708278 4.63808366 2.91914892 1 P 0 ;0,1=607,2=0.000000
L 4.65221644 2.94033346 4.65451663 2.94343278 1 P 0 ;0,1=607,2=0.000000
L 4.65451663 2.94343278 4.6572001 2.94498337 1 P 0 ;0,1=607,2=0.000000
L 4.6572001 2.94498337 4.66026683 2.9455 1 P 0 ;0,1=607,2=0.000000
L 4.66026683 2.9455 4.6641 2.94446683 1 P 0 ;0,1=607,2=0.000000
L 4.6641 2.94446683 4.66678346 2.94188307 1 P 0 ;0,1=607,2=0.000000
L 4.66678346 2.94188307 4.66755 2.93878376 1 P 0 ;0,1=607,2=0.000000
L 4.66755 2.93878376 4.66716673 2.93568258 1 P 0 ;0,1=607,2=0.000000
L 4.66716673 2.93568258 4.66563307 2.9330998 1 P 0 ;0,1=607,2=0.000000
L 4.66563307 2.9330998 4.65796663 2.92793327 1 P 0 ;0,1=607,2=0.000000
L 4.65796663 2.92793327 4.65451663 2.92431644 1 P 0 ;0,1=607,2=0.000000
L 4.65451663 2.92431644 4.65221644 2.91914892 1 P 0 ;0,1=607,2=0.000000
L 4.65221644 2.91914892 4.6514499 2.9145 1 P 0 ;0,1=607,2=0.000000
L 4.6514499 2.9145 4.66755 2.9145 1 P 0 ;0,1=607,2=0.000000
L 4.68206663 2.92069961 4.68436614 2.91708278 1 P 0 ;0,1=607,2=0.000000
L 4.68436614 2.91708278 4.68743287 2.91501654 1 P 0 ;0,1=607,2=0.000000
L 4.68743287 2.91501654 4.69088356 2.9145 1 P 0 ;0,1=607,2=0.000000
L 4.69088356 2.9145 4.6939503 2.91501654 1 P 0 ;0,1=607,2=0.000000
L 4.6939503 2.91501654 4.69701703 2.91759931 1 P 0 ;0,1=607,2=0.000000
L 4.69701703 2.91759931 4.69893327 2.92069961 1 P 0 ;0,1=607,2=0.000000
L 4.69893327 2.92069961 4.69931654 2.9237999 1 P 0 ;0,1=607,2=0.000000
L 4.69931654 2.9237999 4.69855 2.92741575 1 P 0 ;0,1=607,2=0.000000
L 4.69855 2.92741575 4.69586654 2.92999951 1 P 0 ;0,1=607,2=0.000000
L 4.69586654 2.92999951 4.69318307 2.93103356 1 P 0 ;0,1=607,2=0.000000
L 4.69318307 2.93103356 4.68973307 2.93103356 1 P 0 ;0,1=607,2=0.000000
L 4.69318307 2.93103356 4.69548327 2.93258317 1 P 0 ;0,1=607,2=0.000000
L 4.69548327 2.93258317 4.6974002 2.93516594 1 P 0 ;0,1=607,2=0.000000
L 4.6974002 2.93516594 4.69816673 2.93826624 1 P 0 ;0,1=607,2=0.000000
L 4.69816673 2.93826624 4.6974002 2.94136654 1 P 0 ;0,1=607,2=0.000000
L 4.6974002 2.94136654 4.69548327 2.94394931 1 P 0 ;0,1=607,2=0.000000
L 4.69548327 2.94394931 4.69203327 2.9455 1 P 0 ;0,1=607,2=0.000000
L 4.69203327 2.9455 4.68858337 2.94498337 1 P 0 ;0,1=607,2=0.000000
L 4.68858337 2.94498337 4.68513337 2.94291624 1 P 0 ;0,1=607,2=0.000000
L 4.71421644 2.92741575 4.7168999 2.93103356 1 P 0 ;0,1=607,2=0.000000
L 4.7168999 2.93103356 4.7192001 2.9330998 1 P 0 ;0,1=607,2=0.000000
L 4.7192001 2.9330998 4.72226683 2.93413287 1 P 0 ;0,1=607,2=0.000000
L 4.72226683 2.93413287 4.7249503 2.9330998 1 P 0 ;0,1=607,2=0.000000
L 4.7249503 2.9330998 4.72686654 2.93103356 1 P 0 ;0,1=607,2=0.000000
L 4.72686654 2.93103356 4.7284002 2.92793327 1 P 0 ;0,1=607,2=0.000000
L 4.7284002 2.92793327 4.72878346 2.92431644 1 P 0 ;0,1=607,2=0.000000
L 4.72878346 2.92431644 4.7284002 2.92121614 1 P 0 ;0,1=607,2=0.000000
L 4.7284002 2.92121614 4.72686654 2.91811585 1 P 0 ;0,1=607,2=0.000000
L 4.72686654 2.91811585 4.72456634 2.91553307 1 P 0 ;0,1=607,2=0.000000
L 4.72456634 2.91553307 4.72188356 2.9145 1 P 0 ;0,1=607,2=0.000000
L 4.72188356 2.9145 4.71881683 2.91553307 1 P 0 ;0,1=607,2=0.000000
L 4.71881683 2.91553307 4.71613337 2.91863238 1 P 0 ;0,1=607,2=0.000000
L 4.71613337 2.91863238 4.7145997 2.92328327 1 P 0 ;0,1=607,2=0.000000
L 4.7145997 2.92328327 4.71421644 2.9284498 1 P 0 ;0,1=607,2=0.000000
L 4.71421644 2.9284498 4.71498287 2.93516594 1 P 0 ;0,1=607,2=0.000000
L 4.71498287 2.93516594 4.71613337 2.93878376 1 P 0 ;0,1=607,2=0.000000
L 4.71613337 2.93878376 4.71804961 2.9423997 1 P 0 ;0,1=607,2=0.000000
L 4.71804961 2.9423997 4.72073307 2.94498337 1 P 0 ;0,1=607,2=0.000000
L 4.72073307 2.94498337 4.72341654 2.9455 1 P 0 ;0,1=607,2=0.000000
L 4.72341654 2.9455 4.7261 2.94446683 1 P 0 ;0,1=607,2=0.000000
L 4.7261 2.94446683 4.72801703 2.94188307 1 P 0 ;0,1=607,2=0.000000
L 4.59 2.873 4.59 2.917 1 P 0 
L 4.5 2.873 4.59 2.873 1 P 0 
L 4.59 2.917 4.5 2.917 1 P 0 
L 4.5 2.917 4.5 2.873 1 P 0 
L 4.63693327 2.89291624 4.63463307 2.89446683 1 P 0 ;0,1=608,2=0.000000
L 4.63463307 2.89446683 4.6319503 2.8955 1 P 0 ;0,1=608,2=0.000000
L 4.6319503 2.8955 4.62888356 2.8955 1 P 0 ;0,1=608,2=0.000000
L 4.62888356 2.8955 4.62543287 2.89394931 1 P 0 ;0,1=608,2=0.000000
L 4.62543287 2.89394931 4.6227501 2.89136654 1 P 0 ;0,1=608,2=0.000000
L 4.6227501 2.89136654 4.62083317 2.88826624 1 P 0 ;0,1=608,2=0.000000
L 4.62083317 2.88826624 4.61929951 2.8830998 1 P 0 ;0,1=608,2=0.000000
L 4.61929951 2.8830998 4.61891624 2.8784498 1 P 0 ;0,1=608,2=0.000000
L 4.61891624 2.8784498 4.61968337 2.8737999 1 P 0 ;0,1=608,2=0.000000
L 4.61968337 2.8737999 4.62083317 2.87069961 1 P 0 ;0,1=608,2=0.000000
L 4.62083317 2.87069961 4.62313337 2.86759931 1 P 0 ;0,1=608,2=0.000000
L 4.62313337 2.86759931 4.62581683 2.86553307 1 P 0 ;0,1=608,2=0.000000
L 4.62581683 2.86553307 4.62849961 2.8645 1 P 0 ;0,1=608,2=0.000000
L 4.62849961 2.8645 4.63118307 2.8645 1 P 0 ;0,1=608,2=0.000000
L 4.63118307 2.8645 4.63386654 2.86553307 1 P 0 ;0,1=608,2=0.000000
L 4.63386654 2.86553307 4.63616673 2.86708278 1 P 0 ;0,1=608,2=0.000000
L 4.63616673 2.86708278 4.63808366 2.86914892 1 P 0 ;0,1=608,2=0.000000
L 4.65221644 2.89033346 4.65451663 2.89343278 1 P 0 ;0,1=608,2=0.000000
L 4.65451663 2.89343278 4.6572001 2.89498337 1 P 0 ;0,1=608,2=0.000000
L 4.6572001 2.89498337 4.66026683 2.8955 1 P 0 ;0,1=608,2=0.000000
L 4.66026683 2.8955 4.6641 2.89446683 1 P 0 ;0,1=608,2=0.000000
L 4.6641 2.89446683 4.66678346 2.89188307 1 P 0 ;0,1=608,2=0.000000
L 4.66678346 2.89188307 4.66755 2.88878376 1 P 0 ;0,1=608,2=0.000000
L 4.66755 2.88878376 4.66716673 2.88568258 1 P 0 ;0,1=608,2=0.000000
L 4.66716673 2.88568258 4.66563307 2.8830998 1 P 0 ;0,1=608,2=0.000000
L 4.66563307 2.8830998 4.65796663 2.87793327 1 P 0 ;0,1=608,2=0.000000
L 4.65796663 2.87793327 4.65451663 2.87431644 1 P 0 ;0,1=608,2=0.000000
L 4.65451663 2.87431644 4.65221644 2.86914892 1 P 0 ;0,1=608,2=0.000000
L 4.65221644 2.86914892 4.6514499 2.8645 1 P 0 ;0,1=608,2=0.000000
L 4.6514499 2.8645 4.66755 2.8645 1 P 0 ;0,1=608,2=0.000000
L 4.68206663 2.87069961 4.68436614 2.86708278 1 P 0 ;0,1=608,2=0.000000
L 4.68436614 2.86708278 4.68743287 2.86501654 1 P 0 ;0,1=608,2=0.000000
L 4.68743287 2.86501654 4.69088356 2.8645 1 P 0 ;0,1=608,2=0.000000
L 4.69088356 2.8645 4.6939503 2.86501654 1 P 0 ;0,1=608,2=0.000000
L 4.6939503 2.86501654 4.69701703 2.86759931 1 P 0 ;0,1=608,2=0.000000
L 4.69701703 2.86759931 4.69893327 2.87069961 1 P 0 ;0,1=608,2=0.000000
L 4.69893327 2.87069961 4.69931654 2.8737999 1 P 0 ;0,1=608,2=0.000000
L 4.69931654 2.8737999 4.69855 2.87741575 1 P 0 ;0,1=608,2=0.000000
L 4.69855 2.87741575 4.69586654 2.87999951 1 P 0 ;0,1=608,2=0.000000
L 4.69586654 2.87999951 4.69318307 2.88103356 1 P 0 ;0,1=608,2=0.000000
L 4.69318307 2.88103356 4.68973307 2.88103356 1 P 0 ;0,1=608,2=0.000000
L 4.69318307 2.88103356 4.69548327 2.88258317 1 P 0 ;0,1=608,2=0.000000
L 4.69548327 2.88258317 4.6974002 2.88516594 1 P 0 ;0,1=608,2=0.000000
L 4.6974002 2.88516594 4.69816673 2.88826624 1 P 0 ;0,1=608,2=0.000000
L 4.69816673 2.88826624 4.6974002 2.89136654 1 P 0 ;0,1=608,2=0.000000
L 4.6974002 2.89136654 4.69548327 2.89394931 1 P 0 ;0,1=608,2=0.000000
L 4.69548327 2.89394931 4.69203327 2.8955 1 P 0 ;0,1=608,2=0.000000
L 4.69203327 2.8955 4.68858337 2.89498337 1 P 0 ;0,1=608,2=0.000000
L 4.68858337 2.89498337 4.68513337 2.89291624 1 P 0 ;0,1=608,2=0.000000
L 4.71306663 2.86914892 4.71536614 2.86656614 1 P 0 ;0,1=608,2=0.000000
L 4.71536614 2.86656614 4.71804961 2.86501654 1 P 0 ;0,1=608,2=0.000000
L 4.71804961 2.86501654 4.72149961 2.8645 1 P 0 ;0,1=608,2=0.000000
L 4.72149961 2.8645 4.7249503 2.86553307 1 P 0 ;0,1=608,2=0.000000
L 4.7249503 2.86553307 4.72763307 2.86759931 1 P 0 ;0,1=608,2=0.000000
L 4.72763307 2.86759931 4.72955 2.87121614 1 P 0 ;0,1=608,2=0.000000
L 4.72955 2.87121614 4.72993327 2.87534951 1 P 0 ;0,1=608,2=0.000000
L 4.72993327 2.87534951 4.72916673 2.87948287 1 P 0 ;0,1=608,2=0.000000
L 4.72916673 2.87948287 4.7272498 2.88206663 1 P 0 ;0,1=608,2=0.000000
L 4.7272498 2.88206663 4.72456634 2.88413287 1 P 0 ;0,1=608,2=0.000000
L 4.72456634 2.88413287 4.72188356 2.88464941 1 P 0 ;0,1=608,2=0.000000
L 4.72188356 2.88464941 4.7192001 2.88413287 1 P 0 ;0,1=608,2=0.000000
L 4.7192001 2.88413287 4.7157501 2.88206663 1 P 0 ;0,1=608,2=0.000000
L 4.7157501 2.88206663 4.7168999 2.8955 1 P 0 ;0,1=608,2=0.000000
L 4.7168999 2.8955 4.7272498 2.8955 1 P 0 ;0,1=608,2=0.000000
L 4.412 2.765 4.368 2.765 1 P 0 
L 4.368 2.765 4.368 2.675 1 P 0 
L 4.368 2.675 4.412 2.675 1 P 0 
L 4.412 2.675 4.412 2.765 1 P 0 
L 4.50708376 2.67193327 4.50553317 2.66963307 1 P 0 ;0,1=609,2=270.000000
L 4.50553317 2.66963307 4.5045 2.6669503 1 P 0 ;0,1=609,2=270.000000
L 4.5045 2.6669503 4.5045 2.66388356 1 P 0 ;0,1=609,2=270.000000
L 4.5045 2.66388356 4.50605069 2.66043287 1 P 0 ;0,1=609,2=270.000000
L 4.50605069 2.66043287 4.50863346 2.6577501 1 P 0 ;0,1=609,2=270.000000
L 4.50863346 2.6577501 4.51173376 2.65583317 1 P 0 ;0,1=609,2=270.000000
L 4.51173376 2.65583317 4.5169002 2.65429951 1 P 0 ;0,1=609,2=270.000000
L 4.5169002 2.65429951 4.5215502 2.65391624 1 P 0 ;0,1=609,2=270.000000
L 4.5215502 2.65391624 4.5262001 2.65468337 1 P 0 ;0,1=609,2=270.000000
L 4.5262001 2.65468337 4.52930039 2.65583317 1 P 0 ;0,1=609,2=270.000000
L 4.52930039 2.65583317 4.53240069 2.65813337 1 P 0 ;0,1=609,2=270.000000
L 4.53240069 2.65813337 4.53446693 2.66081683 1 P 0 ;0,1=609,2=270.000000
L 4.53446693 2.66081683 4.5355 2.66349961 1 P 0 ;0,1=609,2=270.000000
L 4.5355 2.66349961 4.5355 2.66618307 1 P 0 ;0,1=609,2=270.000000
L 4.5355 2.66618307 4.53446693 2.66886654 1 P 0 ;0,1=609,2=270.000000
L 4.53446693 2.66886654 4.53291722 2.67116673 1 P 0 ;0,1=609,2=270.000000
L 4.53291722 2.67116673 4.53085108 2.67308366 1 P 0 ;0,1=609,2=270.000000
L 4.50966654 2.68721644 4.50656722 2.68951663 1 P 0 ;0,1=609,2=270.000000
L 4.50656722 2.68951663 4.50501663 2.6922001 1 P 0 ;0,1=609,2=270.000000
L 4.50501663 2.6922001 4.5045 2.69526683 1 P 0 ;0,1=609,2=270.000000
L 4.5045 2.69526683 4.50553317 2.6991 1 P 0 ;0,1=609,2=270.000000
L 4.50553317 2.6991 4.50811693 2.70178346 1 P 0 ;0,1=609,2=270.000000
L 4.50811693 2.70178346 4.51121624 2.70255 1 P 0 ;0,1=609,2=270.000000
L 4.51121624 2.70255 4.51431742 2.70216673 1 P 0 ;0,1=609,2=270.000000
L 4.51431742 2.70216673 4.5169002 2.70063307 1 P 0 ;0,1=609,2=270.000000
L 4.5169002 2.70063307 4.52206673 2.69296663 1 P 0 ;0,1=609,2=270.000000
L 4.52206673 2.69296663 4.52568356 2.68951663 1 P 0 ;0,1=609,2=270.000000
L 4.52568356 2.68951663 4.53085108 2.68721644 1 P 0 ;0,1=609,2=270.000000
L 4.53085108 2.68721644 4.5355 2.6864499 1 P 0 ;0,1=609,2=270.000000
L 4.5355 2.6864499 4.5355 2.70255 1 P 0 ;0,1=609,2=270.000000
L 4.52930039 2.71706663 4.53291722 2.71936614 1 P 0 ;0,1=609,2=270.000000
L 4.53291722 2.71936614 4.53498346 2.72243287 1 P 0 ;0,1=609,2=270.000000
L 4.53498346 2.72243287 4.5355 2.72588356 1 P 0 ;0,1=609,2=270.000000
L 4.5355 2.72588356 4.53498346 2.7289503 1 P 0 ;0,1=609,2=270.000000
L 4.53498346 2.7289503 4.53240069 2.73201703 1 P 0 ;0,1=609,2=270.000000
L 4.53240069 2.73201703 4.52930039 2.73393327 1 P 0 ;0,1=609,2=270.000000
L 4.52930039 2.73393327 4.5262001 2.73431654 1 P 0 ;0,1=609,2=270.000000
L 4.5262001 2.73431654 4.52258425 2.73355 1 P 0 ;0,1=609,2=270.000000
L 4.52258425 2.73355 4.52000049 2.73086654 1 P 0 ;0,1=609,2=270.000000
L 4.52000049 2.73086654 4.51896644 2.72818307 1 P 0 ;0,1=609,2=270.000000
L 4.51896644 2.72818307 4.51896644 2.72473307 1 P 0 ;0,1=609,2=270.000000
L 4.51896644 2.72818307 4.51741683 2.73048327 1 P 0 ;0,1=609,2=270.000000
L 4.51741683 2.73048327 4.51483406 2.7324002 1 P 0 ;0,1=609,2=270.000000
L 4.51483406 2.7324002 4.51173376 2.73316673 1 P 0 ;0,1=609,2=270.000000
L 4.51173376 2.73316673 4.50863346 2.7324002 1 P 0 ;0,1=609,2=270.000000
L 4.50863346 2.7324002 4.50605069 2.73048327 1 P 0 ;0,1=609,2=270.000000
L 4.50605069 2.73048327 4.5045 2.72703327 1 P 0 ;0,1=609,2=270.000000
L 4.5045 2.72703327 4.50501663 2.72358337 1 P 0 ;0,1=609,2=270.000000
L 4.50501663 2.72358337 4.50708376 2.72013337 1 P 0 ;0,1=609,2=270.000000
L 4.52930039 2.74806663 4.53291722 2.75036614 1 P 0 ;0,1=609,2=270.000000
L 4.53291722 2.75036614 4.53498346 2.75343287 1 P 0 ;0,1=609,2=270.000000
L 4.53498346 2.75343287 4.5355 2.75688356 1 P 0 ;0,1=609,2=270.000000
L 4.5355 2.75688356 4.53498346 2.7599503 1 P 0 ;0,1=609,2=270.000000
L 4.53498346 2.7599503 4.53240069 2.76301703 1 P 0 ;0,1=609,2=270.000000
L 4.53240069 2.76301703 4.52930039 2.76493327 1 P 0 ;0,1=609,2=270.000000
L 4.52930039 2.76493327 4.5262001 2.76531654 1 P 0 ;0,1=609,2=270.000000
L 4.5262001 2.76531654 4.52258425 2.76455 1 P 0 ;0,1=609,2=270.000000
L 4.52258425 2.76455 4.52000049 2.76186654 1 P 0 ;0,1=609,2=270.000000
L 4.52000049 2.76186654 4.51896644 2.75918307 1 P 0 ;0,1=609,2=270.000000
L 4.51896644 2.75918307 4.51896644 2.75573307 1 P 0 ;0,1=609,2=270.000000
L 4.51896644 2.75918307 4.51741683 2.76148327 1 P 0 ;0,1=609,2=270.000000
L 4.51741683 2.76148327 4.51483406 2.7634002 1 P 0 ;0,1=609,2=270.000000
L 4.51483406 2.7634002 4.51173376 2.76416673 1 P 0 ;0,1=609,2=270.000000
L 4.51173376 2.76416673 4.50863346 2.7634002 1 P 0 ;0,1=609,2=270.000000
L 4.50863346 2.7634002 4.50605069 2.76148327 1 P 0 ;0,1=609,2=270.000000
L 4.50605069 2.76148327 4.5045 2.75803327 1 P 0 ;0,1=609,2=270.000000
L 4.5045 2.75803327 4.50501663 2.75458337 1 P 0 ;0,1=609,2=270.000000
L 4.50501663 2.75458337 4.50708376 2.75113337 1 P 0 ;0,1=609,2=270.000000
L 4.211 2.77 4.211 2.814 1 P 0 
L 4.211 2.814 4.121 2.814 1 P 0 
L 4.121 2.814 4.121 2.77 1 P 0 
L 4.121 2.77 4.211 2.77 1 P 0 
L 4.14293327 2.66491624 4.14063307 2.66646683 1 P 0 ;0,1=610,2=0.000000
L 4.14063307 2.66646683 4.1379503 2.6675 1 P 0 ;0,1=610,2=0.000000
L 4.1379503 2.6675 4.13488356 2.6675 1 P 0 ;0,1=610,2=0.000000
L 4.13488356 2.6675 4.13143287 2.66594931 1 P 0 ;0,1=610,2=0.000000
L 4.13143287 2.66594931 4.1287501 2.66336654 1 P 0 ;0,1=610,2=0.000000
L 4.1287501 2.66336654 4.12683317 2.66026624 1 P 0 ;0,1=610,2=0.000000
L 4.12683317 2.66026624 4.12529951 2.6550998 1 P 0 ;0,1=610,2=0.000000
L 4.12529951 2.6550998 4.12491624 2.6504498 1 P 0 ;0,1=610,2=0.000000
L 4.12491624 2.6504498 4.12568337 2.6457999 1 P 0 ;0,1=610,2=0.000000
L 4.12568337 2.6457999 4.12683317 2.64269961 1 P 0 ;0,1=610,2=0.000000
L 4.12683317 2.64269961 4.12913337 2.63959931 1 P 0 ;0,1=610,2=0.000000
L 4.12913337 2.63959931 4.13181683 2.63753307 1 P 0 ;0,1=610,2=0.000000
L 4.13181683 2.63753307 4.13449961 2.6365 1 P 0 ;0,1=610,2=0.000000
L 4.13449961 2.6365 4.13718307 2.6365 1 P 0 ;0,1=610,2=0.000000
L 4.13718307 2.6365 4.13986654 2.63753307 1 P 0 ;0,1=610,2=0.000000
L 4.13986654 2.63753307 4.14216673 2.63908278 1 P 0 ;0,1=610,2=0.000000
L 4.14216673 2.63908278 4.14408366 2.64114892 1 P 0 ;0,1=610,2=0.000000
L 4.15821644 2.66233346 4.16051663 2.66543278 1 P 0 ;0,1=610,2=0.000000
L 4.16051663 2.66543278 4.1632001 2.66698337 1 P 0 ;0,1=610,2=0.000000
L 4.1632001 2.66698337 4.16626683 2.6675 1 P 0 ;0,1=610,2=0.000000
L 4.16626683 2.6675 4.1701 2.66646683 1 P 0 ;0,1=610,2=0.000000
L 4.1701 2.66646683 4.17278346 2.66388307 1 P 0 ;0,1=610,2=0.000000
L 4.17278346 2.66388307 4.17355 2.66078376 1 P 0 ;0,1=610,2=0.000000
L 4.17355 2.66078376 4.17316673 2.65768258 1 P 0 ;0,1=610,2=0.000000
L 4.17316673 2.65768258 4.17163307 2.6550998 1 P 0 ;0,1=610,2=0.000000
L 4.17163307 2.6550998 4.16396663 2.64993327 1 P 0 ;0,1=610,2=0.000000
L 4.16396663 2.64993327 4.16051663 2.64631644 1 P 0 ;0,1=610,2=0.000000
L 4.16051663 2.64631644 4.15821644 2.64114892 1 P 0 ;0,1=610,2=0.000000
L 4.15821644 2.64114892 4.1574499 2.6365 1 P 0 ;0,1=610,2=0.000000
L 4.1574499 2.6365 4.17355 2.6365 1 P 0 ;0,1=610,2=0.000000
L 4.18806663 2.64269961 4.19036614 2.63908278 1 P 0 ;0,1=610,2=0.000000
L 4.19036614 2.63908278 4.19343287 2.63701654 1 P 0 ;0,1=610,2=0.000000
L 4.19343287 2.63701654 4.19688356 2.6365 1 P 0 ;0,1=610,2=0.000000
L 4.19688356 2.6365 4.1999503 2.63701654 1 P 0 ;0,1=610,2=0.000000
L 4.1999503 2.63701654 4.20301703 2.63959931 1 P 0 ;0,1=610,2=0.000000
L 4.20301703 2.63959931 4.20493327 2.64269961 1 P 0 ;0,1=610,2=0.000000
L 4.20493327 2.64269961 4.20531654 2.6457999 1 P 0 ;0,1=610,2=0.000000
L 4.20531654 2.6457999 4.20455 2.64941575 1 P 0 ;0,1=610,2=0.000000
L 4.20455 2.64941575 4.20186654 2.65199951 1 P 0 ;0,1=610,2=0.000000
L 4.20186654 2.65199951 4.19918307 2.65303356 1 P 0 ;0,1=610,2=0.000000
L 4.19918307 2.65303356 4.19573307 2.65303356 1 P 0 ;0,1=610,2=0.000000
L 4.19918307 2.65303356 4.20148327 2.65458317 1 P 0 ;0,1=610,2=0.000000
L 4.20148327 2.65458317 4.2034002 2.65716594 1 P 0 ;0,1=610,2=0.000000
L 4.2034002 2.65716594 4.20416673 2.66026624 1 P 0 ;0,1=610,2=0.000000
L 4.20416673 2.66026624 4.2034002 2.66336654 1 P 0 ;0,1=610,2=0.000000
L 4.2034002 2.66336654 4.20148327 2.66594931 1 P 0 ;0,1=610,2=0.000000
L 4.20148327 2.66594931 4.19803327 2.6675 1 P 0 ;0,1=610,2=0.000000
L 4.19803327 2.6675 4.19458337 2.66698337 1 P 0 ;0,1=610,2=0.000000
L 4.19458337 2.66698337 4.19113337 2.66491624 1 P 0 ;0,1=610,2=0.000000
L 4.22673307 2.6365 4.22749961 2.64321614 1 P 0 ;0,1=610,2=0.000000
L 4.22749961 2.64321614 4.2286501 2.64889921 1 P 0 ;0,1=610,2=0.000000
L 4.2286501 2.64889921 4.23018307 2.65406663 1 P 0 ;0,1=610,2=0.000000
L 4.23018307 2.65406663 4.2321 2.6597497 1 P 0 ;0,1=610,2=0.000000
L 4.2321 2.6597497 4.23516673 2.6675 1 P 0 ;0,1=610,2=0.000000
L 4.23516673 2.6675 4.21983317 2.6675 1 P 0 ;0,1=610,2=0.000000
L 4.983 2.752 4.939 2.752 1 P 0 
L 4.983 2.662 4.983 2.752 1 P 0 
L 4.939 2.752 4.939 2.662 1 P 0 
L 4.939 2.662 4.983 2.662 1 P 0 
L 4.92193327 2.88291624 4.91963307 2.88446683 1 P 0 ;0,1=611,2=0.000000
L 4.91963307 2.88446683 4.9169503 2.8855 1 P 0 ;0,1=611,2=0.000000
L 4.9169503 2.8855 4.91388356 2.8855 1 P 0 ;0,1=611,2=0.000000
L 4.91388356 2.8855 4.91043287 2.88394931 1 P 0 ;0,1=611,2=0.000000
L 4.91043287 2.88394931 4.9077501 2.88136654 1 P 0 ;0,1=611,2=0.000000
L 4.9077501 2.88136654 4.90583317 2.87826624 1 P 0 ;0,1=611,2=0.000000
L 4.90583317 2.87826624 4.90429951 2.8730998 1 P 0 ;0,1=611,2=0.000000
L 4.90429951 2.8730998 4.90391624 2.8684498 1 P 0 ;0,1=611,2=0.000000
L 4.90391624 2.8684498 4.90468337 2.8637999 1 P 0 ;0,1=611,2=0.000000
L 4.90468337 2.8637999 4.90583317 2.86069961 1 P 0 ;0,1=611,2=0.000000
L 4.90583317 2.86069961 4.90813337 2.85759931 1 P 0 ;0,1=611,2=0.000000
L 4.90813337 2.85759931 4.91081683 2.85553307 1 P 0 ;0,1=611,2=0.000000
L 4.91081683 2.85553307 4.91349961 2.8545 1 P 0 ;0,1=611,2=0.000000
L 4.91349961 2.8545 4.91618307 2.8545 1 P 0 ;0,1=611,2=0.000000
L 4.91618307 2.8545 4.91886654 2.85553307 1 P 0 ;0,1=611,2=0.000000
L 4.91886654 2.85553307 4.92116673 2.85708278 1 P 0 ;0,1=611,2=0.000000
L 4.92116673 2.85708278 4.92308366 2.85914892 1 P 0 ;0,1=611,2=0.000000
L 4.94449961 2.8545 4.94449961 2.8855 1 P 0 ;0,1=611,2=0.000000
L 4.94449961 2.8855 4.9398999 2.8793003 1 P 0 ;0,1=611,2=0.000000
L 4.9398999 2.8545 4.94909931 2.8545 1 P 0 ;0,1=611,2=0.000000
L 4.97549961 2.8545 4.97818307 2.85501654 1 P 0 ;0,1=611,2=0.000000
L 4.97818307 2.85501654 4.9812498 2.85656614 1 P 0 ;0,1=611,2=0.000000
L 4.9812498 2.85656614 4.98316673 2.85914892 1 P 0 ;0,1=611,2=0.000000
L 4.98316673 2.85914892 4.98393327 2.86276673 1 P 0 ;0,1=611,2=0.000000
L 4.98393327 2.86276673 4.98316673 2.86638268 1 P 0 ;0,1=611,2=0.000000
L 4.98316673 2.86638268 4.98086654 2.86948287 1 P 0 ;0,1=611,2=0.000000
L 4.98086654 2.86948287 4.97741654 2.87103356 1 P 0 ;0,1=611,2=0.000000
L 4.97741654 2.87103356 4.97358337 2.87103356 1 P 0 ;0,1=611,2=0.000000
L 4.97358337 2.87103356 4.97128317 2.87206663 1 P 0 ;0,1=611,2=0.000000
L 4.97128317 2.87206663 4.96936614 2.87464941 1 P 0 ;0,1=611,2=0.000000
L 4.96936614 2.87464941 4.9685997 2.87826624 1 P 0 ;0,1=611,2=0.000000
L 4.9685997 2.87826624 4.9697501 2.88188307 1 P 0 ;0,1=611,2=0.000000
L 4.9697501 2.88188307 4.97243287 2.88446683 1 P 0 ;0,1=611,2=0.000000
L 4.97243287 2.88446683 4.97549961 2.8855 1 P 0 ;0,1=611,2=0.000000
L 4.97549961 2.8855 4.97856634 2.88446683 1 P 0 ;0,1=611,2=0.000000
L 4.97856634 2.88446683 4.9812498 2.88188307 1 P 0 ;0,1=611,2=0.000000
L 4.9812498 2.88188307 4.9824002 2.87826624 1 P 0 ;0,1=611,2=0.000000
L 4.9824002 2.87826624 4.98163307 2.87464941 1 P 0 ;0,1=611,2=0.000000
L 4.98163307 2.87464941 4.97971673 2.87206663 1 P 0 ;0,1=611,2=0.000000
L 4.97971673 2.87206663 4.97741654 2.87103356 1 P 0 ;0,1=611,2=0.000000
L 4.97741654 2.87103356 4.97358337 2.87103356 1 P 0 ;0,1=611,2=0.000000
L 4.97358337 2.87103356 4.97013337 2.86948287 1 P 0 ;0,1=611,2=0.000000
L 4.97013337 2.86948287 4.96783317 2.86638268 1 P 0 ;0,1=611,2=0.000000
L 4.96783317 2.86638268 4.96706663 2.86276673 1 P 0 ;0,1=611,2=0.000000
L 4.96706663 2.86276673 4.96783317 2.85914892 1 P 0 ;0,1=611,2=0.000000
L 4.96783317 2.85914892 4.9697501 2.85656614 1 P 0 ;0,1=611,2=0.000000
L 4.9697501 2.85656614 4.97281683 2.85501654 1 P 0 ;0,1=611,2=0.000000
L 4.97281683 2.85501654 4.97549961 2.8545 1 P 0 ;0,1=611,2=0.000000
L 5.00573307 2.8545 5.00649961 2.86121614 1 P 0 ;0,1=611,2=0.000000
L 5.00649961 2.86121614 5.0076501 2.86689921 1 P 0 ;0,1=611,2=0.000000
L 5.0076501 2.86689921 5.00918307 2.87206663 1 P 0 ;0,1=611,2=0.000000
L 5.00918307 2.87206663 5.0111 2.8777497 1 P 0 ;0,1=611,2=0.000000
L 5.0111 2.8777497 5.01416673 2.8855 1 P 0 ;0,1=611,2=0.000000
L 5.01416673 2.8855 4.99883317 2.8855 1 P 0 ;0,1=611,2=0.000000
L 5.155 3.797 5.065 3.797 1 P 0 
L 5.065 3.797 5.065 3.753 1 P 0 
L 5.065 3.753 5.155 3.753 1 P 0 
L 5.155 3.753 5.155 3.797 1 P 0 
L 5.07693327 3.72291624 5.07463307 3.72446683 1 P 0 ;0,1=612,2=0.000000
L 5.07463307 3.72446683 5.0719503 3.7255 1 P 0 ;0,1=612,2=0.000000
L 5.0719503 3.7255 5.06888356 3.7255 1 P 0 ;0,1=612,2=0.000000
L 5.06888356 3.7255 5.06543287 3.72394931 1 P 0 ;0,1=612,2=0.000000
L 5.06543287 3.72394931 5.0627501 3.72136654 1 P 0 ;0,1=612,2=0.000000
L 5.0627501 3.72136654 5.06083317 3.71826624 1 P 0 ;0,1=612,2=0.000000
L 5.06083317 3.71826624 5.05929951 3.7130998 1 P 0 ;0,1=612,2=0.000000
L 5.05929951 3.7130998 5.05891624 3.7084498 1 P 0 ;0,1=612,2=0.000000
L 5.05891624 3.7084498 5.05968337 3.7037999 1 P 0 ;0,1=612,2=0.000000
L 5.05968337 3.7037999 5.06083317 3.70069961 1 P 0 ;0,1=612,2=0.000000
L 5.06083317 3.70069961 5.06313337 3.69759931 1 P 0 ;0,1=612,2=0.000000
L 5.06313337 3.69759931 5.06581683 3.69553307 1 P 0 ;0,1=612,2=0.000000
L 5.06581683 3.69553307 5.06849961 3.6945 1 P 0 ;0,1=612,2=0.000000
L 5.06849961 3.6945 5.07118307 3.6945 1 P 0 ;0,1=612,2=0.000000
L 5.07118307 3.6945 5.07386654 3.69553307 1 P 0 ;0,1=612,2=0.000000
L 5.07386654 3.69553307 5.07616673 3.69708278 1 P 0 ;0,1=612,2=0.000000
L 5.07616673 3.69708278 5.07808366 3.69914892 1 P 0 ;0,1=612,2=0.000000
L 5.09221644 3.72033346 5.09451663 3.72343278 1 P 0 ;0,1=612,2=0.000000
L 5.09451663 3.72343278 5.0972001 3.72498337 1 P 0 ;0,1=612,2=0.000000
L 5.0972001 3.72498337 5.10026683 3.7255 1 P 0 ;0,1=612,2=0.000000
L 5.10026683 3.7255 5.1041 3.72446683 1 P 0 ;0,1=612,2=0.000000
L 5.1041 3.72446683 5.10678346 3.72188307 1 P 0 ;0,1=612,2=0.000000
L 5.10678346 3.72188307 5.10755 3.71878376 1 P 0 ;0,1=612,2=0.000000
L 5.10755 3.71878376 5.10716673 3.71568258 1 P 0 ;0,1=612,2=0.000000
L 5.10716673 3.71568258 5.10563307 3.7130998 1 P 0 ;0,1=612,2=0.000000
L 5.10563307 3.7130998 5.09796663 3.70793327 1 P 0 ;0,1=612,2=0.000000
L 5.09796663 3.70793327 5.09451663 3.70431644 1 P 0 ;0,1=612,2=0.000000
L 5.09451663 3.70431644 5.09221644 3.69914892 1 P 0 ;0,1=612,2=0.000000
L 5.09221644 3.69914892 5.0914499 3.6945 1 P 0 ;0,1=612,2=0.000000
L 5.0914499 3.6945 5.10755 3.6945 1 P 0 ;0,1=612,2=0.000000
L 5.12973307 3.6945 5.13049961 3.70121614 1 P 0 ;0,1=612,2=0.000000
L 5.13049961 3.70121614 5.1316501 3.70689921 1 P 0 ;0,1=612,2=0.000000
L 5.1316501 3.70689921 5.13318307 3.71206663 1 P 0 ;0,1=612,2=0.000000
L 5.13318307 3.71206663 5.1351 3.7177497 1 P 0 ;0,1=612,2=0.000000
L 5.1351 3.7177497 5.13816673 3.7255 1 P 0 ;0,1=612,2=0.000000
L 5.13816673 3.7255 5.12283317 3.7255 1 P 0 ;0,1=612,2=0.000000
L 5.15421644 3.72033346 5.15651663 3.72343278 1 P 0 ;0,1=612,2=0.000000
L 5.15651663 3.72343278 5.1592001 3.72498337 1 P 0 ;0,1=612,2=0.000000
L 5.1592001 3.72498337 5.16226683 3.7255 1 P 0 ;0,1=612,2=0.000000
L 5.16226683 3.7255 5.1661 3.72446683 1 P 0 ;0,1=612,2=0.000000
L 5.1661 3.72446683 5.16878346 3.72188307 1 P 0 ;0,1=612,2=0.000000
L 5.16878346 3.72188307 5.16955 3.71878376 1 P 0 ;0,1=612,2=0.000000
L 5.16955 3.71878376 5.16916673 3.71568258 1 P 0 ;0,1=612,2=0.000000
L 5.16916673 3.71568258 5.16763307 3.7130998 1 P 0 ;0,1=612,2=0.000000
L 5.16763307 3.7130998 5.15996663 3.70793327 1 P 0 ;0,1=612,2=0.000000
L 5.15996663 3.70793327 5.15651663 3.70431644 1 P 0 ;0,1=612,2=0.000000
L 5.15651663 3.70431644 5.15421644 3.69914892 1 P 0 ;0,1=612,2=0.000000
L 5.15421644 3.69914892 5.1534499 3.6945 1 P 0 ;0,1=612,2=0.000000
L 5.1534499 3.6945 5.16955 3.6945 1 P 0 ;0,1=612,2=0.000000
L 4.42 3.943 4.42 3.987 1 P 0 
L 4.33 3.943 4.42 3.943 1 P 0 
L 4.42 3.987 4.33 3.987 1 P 0 
L 4.33 3.987 4.33 3.943 1 P 0 
L 4.46193327 4.10291624 4.45963307 4.10446683 1 P 0 ;0,1=613,2=0.000000
L 4.45963307 4.10446683 4.4569503 4.1055 1 P 0 ;0,1=613,2=0.000000
L 4.4569503 4.1055 4.45388356 4.1055 1 P 0 ;0,1=613,2=0.000000
L 4.45388356 4.1055 4.45043287 4.10394931 1 P 0 ;0,1=613,2=0.000000
L 4.45043287 4.10394931 4.4477501 4.10136654 1 P 0 ;0,1=613,2=0.000000
L 4.4477501 4.10136654 4.44583317 4.09826624 1 P 0 ;0,1=613,2=0.000000
L 4.44583317 4.09826624 4.44429951 4.0930998 1 P 0 ;0,1=613,2=0.000000
L 4.44429951 4.0930998 4.44391624 4.0884498 1 P 0 ;0,1=613,2=0.000000
L 4.44391624 4.0884498 4.44468337 4.0837999 1 P 0 ;0,1=613,2=0.000000
L 4.44468337 4.0837999 4.44583317 4.08069961 1 P 0 ;0,1=613,2=0.000000
L 4.44583317 4.08069961 4.44813337 4.07759931 1 P 0 ;0,1=613,2=0.000000
L 4.44813337 4.07759931 4.45081683 4.07553307 1 P 0 ;0,1=613,2=0.000000
L 4.45081683 4.07553307 4.45349961 4.0745 1 P 0 ;0,1=613,2=0.000000
L 4.45349961 4.0745 4.45618307 4.0745 1 P 0 ;0,1=613,2=0.000000
L 4.45618307 4.0745 4.45886654 4.07553307 1 P 0 ;0,1=613,2=0.000000
L 4.45886654 4.07553307 4.46116673 4.07708278 1 P 0 ;0,1=613,2=0.000000
L 4.46116673 4.07708278 4.46308366 4.07914892 1 P 0 ;0,1=613,2=0.000000
L 4.47606663 4.08069961 4.47836614 4.07708278 1 P 0 ;0,1=613,2=0.000000
L 4.47836614 4.07708278 4.48143287 4.07501654 1 P 0 ;0,1=613,2=0.000000
L 4.48143287 4.07501654 4.48488356 4.0745 1 P 0 ;0,1=613,2=0.000000
L 4.48488356 4.0745 4.4879503 4.07501654 1 P 0 ;0,1=613,2=0.000000
L 4.4879503 4.07501654 4.49101703 4.07759931 1 P 0 ;0,1=613,2=0.000000
L 4.49101703 4.07759931 4.49293327 4.08069961 1 P 0 ;0,1=613,2=0.000000
L 4.49293327 4.08069961 4.49331654 4.0837999 1 P 0 ;0,1=613,2=0.000000
L 4.49331654 4.0837999 4.49255 4.08741575 1 P 0 ;0,1=613,2=0.000000
L 4.49255 4.08741575 4.48986654 4.08999951 1 P 0 ;0,1=613,2=0.000000
L 4.48986654 4.08999951 4.48718307 4.09103356 1 P 0 ;0,1=613,2=0.000000
L 4.48718307 4.09103356 4.48373307 4.09103356 1 P 0 ;0,1=613,2=0.000000
L 4.48718307 4.09103356 4.48948327 4.09258317 1 P 0 ;0,1=613,2=0.000000
L 4.48948327 4.09258317 4.4914002 4.09516594 1 P 0 ;0,1=613,2=0.000000
L 4.4914002 4.09516594 4.49216673 4.09826624 1 P 0 ;0,1=613,2=0.000000
L 4.49216673 4.09826624 4.4914002 4.10136654 1 P 0 ;0,1=613,2=0.000000
L 4.4914002 4.10136654 4.48948327 4.10394931 1 P 0 ;0,1=613,2=0.000000
L 4.48948327 4.10394931 4.48603327 4.1055 1 P 0 ;0,1=613,2=0.000000
L 4.48603327 4.1055 4.48258337 4.10498337 1 P 0 ;0,1=613,2=0.000000
L 4.48258337 4.10498337 4.47913337 4.10291624 1 P 0 ;0,1=613,2=0.000000
L 4.51549961 4.0745 4.51549961 4.1055 1 P 0 ;0,1=613,2=0.000000
L 4.51549961 4.1055 4.5108999 4.0993003 1 P 0 ;0,1=613,2=0.000000
L 4.5108999 4.0745 4.52009931 4.0745 1 P 0 ;0,1=613,2=0.000000
L 4.5511 4.0745 4.5511 4.1055 1 P 0 ;0,1=613,2=0.000000
L 4.5511 4.1055 4.53691624 4.08328327 1 P 0 ;0,1=613,2=0.000000
L 4.53691624 4.08328327 4.55608366 4.08328327 1 P 0 ;0,1=613,2=0.000000
L 2.961 3.184 2.961 3.228 1 P 0 
L 2.961 3.228 2.871 3.228 1 P 0 
L 2.871 3.228 2.871 3.184 1 P 0 
L 2.871 3.184 2.961 3.184 1 P 0 
L 2.87243327 3.39791624 2.87013307 3.39946683 1 P 0 ;0,1=614,2=0.000000
L 2.87013307 3.39946683 2.8674503 3.4005 1 P 0 ;0,1=614,2=0.000000
L 2.8674503 3.4005 2.86438356 3.4005 1 P 0 ;0,1=614,2=0.000000
L 2.86438356 3.4005 2.86093287 3.39894931 1 P 0 ;0,1=614,2=0.000000
L 2.86093287 3.39894931 2.8582501 3.39636654 1 P 0 ;0,1=614,2=0.000000
L 2.8582501 3.39636654 2.85633317 3.39326624 1 P 0 ;0,1=614,2=0.000000
L 2.85633317 3.39326624 2.85479951 3.3880998 1 P 0 ;0,1=614,2=0.000000
L 2.85479951 3.3880998 2.85441624 3.3834498 1 P 0 ;0,1=614,2=0.000000
L 2.85441624 3.3834498 2.85518337 3.3787999 1 P 0 ;0,1=614,2=0.000000
L 2.85518337 3.3787999 2.85633317 3.37569961 1 P 0 ;0,1=614,2=0.000000
L 2.85633317 3.37569961 2.85863337 3.37259931 1 P 0 ;0,1=614,2=0.000000
L 2.85863337 3.37259931 2.86131683 3.37053307 1 P 0 ;0,1=614,2=0.000000
L 2.86131683 3.37053307 2.86399961 3.3695 1 P 0 ;0,1=614,2=0.000000
L 2.86399961 3.3695 2.86668307 3.3695 1 P 0 ;0,1=614,2=0.000000
L 2.86668307 3.3695 2.86936654 3.37053307 1 P 0 ;0,1=614,2=0.000000
L 2.86936654 3.37053307 2.87166673 3.37208278 1 P 0 ;0,1=614,2=0.000000
L 2.87166673 3.37208278 2.87358366 3.37414892 1 P 0 ;0,1=614,2=0.000000
L 2.88656663 3.37569961 2.88886614 3.37208278 1 P 0 ;0,1=614,2=0.000000
L 2.88886614 3.37208278 2.89193287 3.37001654 1 P 0 ;0,1=614,2=0.000000
L 2.89193287 3.37001654 2.89538356 3.3695 1 P 0 ;0,1=614,2=0.000000
L 2.89538356 3.3695 2.8984503 3.37001654 1 P 0 ;0,1=614,2=0.000000
L 2.8984503 3.37001654 2.90151703 3.37259931 1 P 0 ;0,1=614,2=0.000000
L 2.90151703 3.37259931 2.90343327 3.37569961 1 P 0 ;0,1=614,2=0.000000
L 2.90343327 3.37569961 2.90381654 3.3787999 1 P 0 ;0,1=614,2=0.000000
L 2.90381654 3.3787999 2.90305 3.38241575 1 P 0 ;0,1=614,2=0.000000
L 2.90305 3.38241575 2.90036654 3.38499951 1 P 0 ;0,1=614,2=0.000000
L 2.90036654 3.38499951 2.89768307 3.38603356 1 P 0 ;0,1=614,2=0.000000
L 2.89768307 3.38603356 2.89423307 3.38603356 1 P 0 ;0,1=614,2=0.000000
L 2.89768307 3.38603356 2.89998327 3.38758317 1 P 0 ;0,1=614,2=0.000000
L 2.89998327 3.38758317 2.9019002 3.39016594 1 P 0 ;0,1=614,2=0.000000
L 2.9019002 3.39016594 2.90266673 3.39326624 1 P 0 ;0,1=614,2=0.000000
L 2.90266673 3.39326624 2.9019002 3.39636654 1 P 0 ;0,1=614,2=0.000000
L 2.9019002 3.39636654 2.89998327 3.39894931 1 P 0 ;0,1=614,2=0.000000
L 2.89998327 3.39894931 2.89653327 3.4005 1 P 0 ;0,1=614,2=0.000000
L 2.89653327 3.4005 2.89308337 3.39998337 1 P 0 ;0,1=614,2=0.000000
L 2.89308337 3.39998337 2.88963337 3.39791624 1 P 0 ;0,1=614,2=0.000000
L 2.92599961 3.3695 2.92868307 3.37001654 1 P 0 ;0,1=614,2=0.000000
L 2.92868307 3.37001654 2.9317498 3.37156614 1 P 0 ;0,1=614,2=0.000000
L 2.9317498 3.37156614 2.93366673 3.37414892 1 P 0 ;0,1=614,2=0.000000
L 2.93366673 3.37414892 2.93443327 3.37776673 1 P 0 ;0,1=614,2=0.000000
L 2.93443327 3.37776673 2.93366673 3.38138268 1 P 0 ;0,1=614,2=0.000000
L 2.93366673 3.38138268 2.93136654 3.38448287 1 P 0 ;0,1=614,2=0.000000
L 2.93136654 3.38448287 2.92791654 3.38603356 1 P 0 ;0,1=614,2=0.000000
L 2.92791654 3.38603356 2.92408337 3.38603356 1 P 0 ;0,1=614,2=0.000000
L 2.92408337 3.38603356 2.92178317 3.38706663 1 P 0 ;0,1=614,2=0.000000
L 2.92178317 3.38706663 2.91986614 3.38964941 1 P 0 ;0,1=614,2=0.000000
L 2.91986614 3.38964941 2.9190997 3.39326624 1 P 0 ;0,1=614,2=0.000000
L 2.9190997 3.39326624 2.9202501 3.39688307 1 P 0 ;0,1=614,2=0.000000
L 2.9202501 3.39688307 2.92293287 3.39946683 1 P 0 ;0,1=614,2=0.000000
L 2.92293287 3.39946683 2.92599961 3.4005 1 P 0 ;0,1=614,2=0.000000
L 2.92599961 3.4005 2.92906634 3.39946683 1 P 0 ;0,1=614,2=0.000000
L 2.92906634 3.39946683 2.9317498 3.39688307 1 P 0 ;0,1=614,2=0.000000
L 2.9317498 3.39688307 2.9329002 3.39326624 1 P 0 ;0,1=614,2=0.000000
L 2.9329002 3.39326624 2.93213307 3.38964941 1 P 0 ;0,1=614,2=0.000000
L 2.93213307 3.38964941 2.93021673 3.38706663 1 P 0 ;0,1=614,2=0.000000
L 2.93021673 3.38706663 2.92791654 3.38603356 1 P 0 ;0,1=614,2=0.000000
L 2.92791654 3.38603356 2.92408337 3.38603356 1 P 0 ;0,1=614,2=0.000000
L 2.92408337 3.38603356 2.92063337 3.38448287 1 P 0 ;0,1=614,2=0.000000
L 2.92063337 3.38448287 2.91833317 3.38138268 1 P 0 ;0,1=614,2=0.000000
L 2.91833317 3.38138268 2.91756663 3.37776673 1 P 0 ;0,1=614,2=0.000000
L 2.91756663 3.37776673 2.91833317 3.37414892 1 P 0 ;0,1=614,2=0.000000
L 2.91833317 3.37414892 2.9202501 3.37156614 1 P 0 ;0,1=614,2=0.000000
L 2.9202501 3.37156614 2.92331683 3.37001654 1 P 0 ;0,1=614,2=0.000000
L 2.92331683 3.37001654 2.92599961 3.3695 1 P 0 ;0,1=614,2=0.000000
L 3.819 2.915 3.775 2.915 1 P 0 
L 3.819 2.825 3.819 2.915 1 P 0 
L 3.775 2.915 3.775 2.825 1 P 0 
L 3.775 2.825 3.819 2.825 1 P 0 
L 2.68708376 3.58193327 2.68553317 3.57963307 1 P 0 ;0,1=615,2=270.000000
L 2.68553317 3.57963307 2.6845 3.5769503 1 P 0 ;0,1=615,2=270.000000
L 2.6845 3.5769503 2.6845 3.57388356 1 P 0 ;0,1=615,2=270.000000
L 2.6845 3.57388356 2.68605069 3.57043287 1 P 0 ;0,1=615,2=270.000000
L 2.68605069 3.57043287 2.68863346 3.5677501 1 P 0 ;0,1=615,2=270.000000
L 2.68863346 3.5677501 2.69173376 3.56583317 1 P 0 ;0,1=615,2=270.000000
L 2.69173376 3.56583317 2.6969002 3.56429951 1 P 0 ;0,1=615,2=270.000000
L 2.6969002 3.56429951 2.7015502 3.56391624 1 P 0 ;0,1=615,2=270.000000
L 2.7015502 3.56391624 2.7062001 3.56468337 1 P 0 ;0,1=615,2=270.000000
L 2.7062001 3.56468337 2.70930039 3.56583317 1 P 0 ;0,1=615,2=270.000000
L 2.70930039 3.56583317 2.71240069 3.56813337 1 P 0 ;0,1=615,2=270.000000
L 2.71240069 3.56813337 2.71446693 3.57081683 1 P 0 ;0,1=615,2=270.000000
L 2.71446693 3.57081683 2.7155 3.57349961 1 P 0 ;0,1=615,2=270.000000
L 2.7155 3.57349961 2.7155 3.57618307 1 P 0 ;0,1=615,2=270.000000
L 2.7155 3.57618307 2.71446693 3.57886654 1 P 0 ;0,1=615,2=270.000000
L 2.71446693 3.57886654 2.71291722 3.58116673 1 P 0 ;0,1=615,2=270.000000
L 2.71291722 3.58116673 2.71085108 3.58308366 1 P 0 ;0,1=615,2=270.000000
L 2.7155 3.60449961 2.6845 3.60449961 1 P 0 ;0,1=615,2=270.000000
L 2.6845 3.60449961 2.6906997 3.5998999 1 P 0 ;0,1=615,2=270.000000
L 2.7155 3.5998999 2.7155 3.60909931 1 P 0 ;0,1=615,2=270.000000
L 2.71188415 3.62898287 2.71446693 3.63166634 1 P 0 ;0,1=615,2=270.000000
L 2.71446693 3.63166634 2.7155 3.63473307 1 P 0 ;0,1=615,2=270.000000
L 2.7155 3.63473307 2.71446693 3.6377998 1 P 0 ;0,1=615,2=270.000000
L 2.71446693 3.6377998 2.71136762 3.64048327 1 P 0 ;0,1=615,2=270.000000
L 2.71136762 3.64048327 2.70671673 3.6424002 1 P 0 ;0,1=615,2=270.000000
L 2.70671673 3.6424002 2.70206673 3.64316673 1 P 0 ;0,1=615,2=270.000000
L 2.70206673 3.64316673 2.69638366 3.64316673 1 P 0 ;0,1=615,2=270.000000
L 2.69638366 3.64316673 2.69173376 3.6424002 1 P 0 ;0,1=615,2=270.000000
L 2.69173376 3.6424002 2.6876003 3.64048327 1 P 0 ;0,1=615,2=270.000000
L 2.6876003 3.64048327 2.68553317 3.63818307 1 P 0 ;0,1=615,2=270.000000
L 2.68553317 3.63818307 2.6845 3.63549961 1 P 0 ;0,1=615,2=270.000000
L 2.6845 3.63549961 2.68553317 3.63243287 1 P 0 ;0,1=615,2=270.000000
L 2.68553317 3.63243287 2.6876003 3.63013337 1 P 0 ;0,1=615,2=270.000000
L 2.6876003 3.63013337 2.6906997 3.6285997 1 P 0 ;0,1=615,2=270.000000
L 2.6906997 3.6285997 2.69483406 3.62783317 1 P 0 ;0,1=615,2=270.000000
L 2.69483406 3.62783317 2.6984499 3.6285997 1 P 0 ;0,1=615,2=270.000000
L 2.6984499 3.6285997 2.70206673 3.63051663 1 P 0 ;0,1=615,2=270.000000
L 2.70206673 3.63051663 2.70413396 3.63281683 1 P 0 ;0,1=615,2=270.000000
L 2.70413396 3.63281683 2.70465049 3.63549961 1 P 0 ;0,1=615,2=270.000000
L 2.70465049 3.63549961 2.70361732 3.63856634 1 P 0 ;0,1=615,2=270.000000
L 2.70361732 3.63856634 2.70103366 3.64086654 1 P 0 ;0,1=615,2=270.000000
L 2.70103366 3.64086654 2.69638366 3.64316673 1 P 0 ;0,1=615,2=270.000000
L 2.70258425 3.65921644 2.69896644 3.6618999 1 P 0 ;0,1=615,2=270.000000
L 2.69896644 3.6618999 2.6969002 3.6642001 1 P 0 ;0,1=615,2=270.000000
L 2.6969002 3.6642001 2.69586713 3.66726683 1 P 0 ;0,1=615,2=270.000000
L 2.69586713 3.66726683 2.6969002 3.6699503 1 P 0 ;0,1=615,2=270.000000
L 2.6969002 3.6699503 2.69896644 3.67186654 1 P 0 ;0,1=615,2=270.000000
L 2.69896644 3.67186654 2.70206673 3.6734002 1 P 0 ;0,1=615,2=270.000000
L 2.70206673 3.6734002 2.70568356 3.67378346 1 P 0 ;0,1=615,2=270.000000
L 2.70568356 3.67378346 2.70878386 3.6734002 1 P 0 ;0,1=615,2=270.000000
L 2.70878386 3.6734002 2.71188415 3.67186654 1 P 0 ;0,1=615,2=270.000000
L 2.71188415 3.67186654 2.71446693 3.66956634 1 P 0 ;0,1=615,2=270.000000
L 2.71446693 3.66956634 2.7155 3.66688356 1 P 0 ;0,1=615,2=270.000000
L 2.7155 3.66688356 2.71446693 3.66381683 1 P 0 ;0,1=615,2=270.000000
L 2.71446693 3.66381683 2.71136762 3.66113337 1 P 0 ;0,1=615,2=270.000000
L 2.71136762 3.66113337 2.70671673 3.6595997 1 P 0 ;0,1=615,2=270.000000
L 2.70671673 3.6595997 2.7015502 3.65921644 1 P 0 ;0,1=615,2=270.000000
L 2.7015502 3.65921644 2.69483406 3.65998287 1 P 0 ;0,1=615,2=270.000000
L 2.69483406 3.65998287 2.69121624 3.66113337 1 P 0 ;0,1=615,2=270.000000
L 2.69121624 3.66113337 2.6876003 3.66304961 1 P 0 ;0,1=615,2=270.000000
L 2.6876003 3.66304961 2.68501663 3.66573307 1 P 0 ;0,1=615,2=270.000000
L 2.68501663 3.66573307 2.6845 3.66841654 1 P 0 ;0,1=615,2=270.000000
L 2.6845 3.66841654 2.68553317 3.6711 1 P 0 ;0,1=615,2=270.000000
L 2.68553317 3.6711 2.68811693 3.67301703 1 P 0 ;0,1=615,2=270.000000
L 3.819 3.035 3.775 3.035 1 P 0 
L 3.775 3.035 3.775 2.945 1 P 0 
L 3.775 2.945 3.819 2.945 1 P 0 
L 3.819 2.945 3.819 3.035 1 P 0 
L 2.68708376 3.70693327 2.68553317 3.70463307 1 P 0 ;0,1=616,2=270.000000
L 2.68553317 3.70463307 2.6845 3.7019503 1 P 0 ;0,1=616,2=270.000000
L 2.6845 3.7019503 2.6845 3.69888356 1 P 0 ;0,1=616,2=270.000000
L 2.6845 3.69888356 2.68605069 3.69543287 1 P 0 ;0,1=616,2=270.000000
L 2.68605069 3.69543287 2.68863346 3.6927501 1 P 0 ;0,1=616,2=270.000000
L 2.68863346 3.6927501 2.69173376 3.69083317 1 P 0 ;0,1=616,2=270.000000
L 2.69173376 3.69083317 2.6969002 3.68929951 1 P 0 ;0,1=616,2=270.000000
L 2.6969002 3.68929951 2.7015502 3.68891624 1 P 0 ;0,1=616,2=270.000000
L 2.7015502 3.68891624 2.7062001 3.68968337 1 P 0 ;0,1=616,2=270.000000
L 2.7062001 3.68968337 2.70930039 3.69083317 1 P 0 ;0,1=616,2=270.000000
L 2.70930039 3.69083317 2.71240069 3.69313337 1 P 0 ;0,1=616,2=270.000000
L 2.71240069 3.69313337 2.71446693 3.69581683 1 P 0 ;0,1=616,2=270.000000
L 2.71446693 3.69581683 2.7155 3.69849961 1 P 0 ;0,1=616,2=270.000000
L 2.7155 3.69849961 2.7155 3.70118307 1 P 0 ;0,1=616,2=270.000000
L 2.7155 3.70118307 2.71446693 3.70386654 1 P 0 ;0,1=616,2=270.000000
L 2.71446693 3.70386654 2.71291722 3.70616673 1 P 0 ;0,1=616,2=270.000000
L 2.71291722 3.70616673 2.71085108 3.70808366 1 P 0 ;0,1=616,2=270.000000
L 2.7155 3.72949961 2.6845 3.72949961 1 P 0 ;0,1=616,2=270.000000
L 2.6845 3.72949961 2.6906997 3.7248999 1 P 0 ;0,1=616,2=270.000000
L 2.7155 3.7248999 2.7155 3.73409931 1 P 0 ;0,1=616,2=270.000000
L 2.7155 3.76049961 2.71498346 3.76318307 1 P 0 ;0,1=616,2=270.000000
L 2.71498346 3.76318307 2.71343386 3.7662498 1 P 0 ;0,1=616,2=270.000000
L 2.71343386 3.7662498 2.71085108 3.76816673 1 P 0 ;0,1=616,2=270.000000
L 2.71085108 3.76816673 2.70723327 3.76893327 1 P 0 ;0,1=616,2=270.000000
L 2.70723327 3.76893327 2.70361732 3.76816673 1 P 0 ;0,1=616,2=270.000000
L 2.70361732 3.76816673 2.70051713 3.76586654 1 P 0 ;0,1=616,2=270.000000
L 2.70051713 3.76586654 2.69896644 3.76241654 1 P 0 ;0,1=616,2=270.000000
L 2.69896644 3.76241654 2.69896644 3.75858337 1 P 0 ;0,1=616,2=270.000000
L 2.69896644 3.75858337 2.69793337 3.75628317 1 P 0 ;0,1=616,2=270.000000
L 2.69793337 3.75628317 2.69535059 3.75436614 1 P 0 ;0,1=616,2=270.000000
L 2.69535059 3.75436614 2.69173376 3.7535997 1 P 0 ;0,1=616,2=270.000000
L 2.69173376 3.7535997 2.68811693 3.7547501 1 P 0 ;0,1=616,2=270.000000
L 2.68811693 3.7547501 2.68553317 3.75743287 1 P 0 ;0,1=616,2=270.000000
L 2.68553317 3.75743287 2.6845 3.76049961 1 P 0 ;0,1=616,2=270.000000
L 2.6845 3.76049961 2.68553317 3.76356634 1 P 0 ;0,1=616,2=270.000000
L 2.68553317 3.76356634 2.68811693 3.7662498 1 P 0 ;0,1=616,2=270.000000
L 2.68811693 3.7662498 2.69173376 3.7674002 1 P 0 ;0,1=616,2=270.000000
L 2.69173376 3.7674002 2.69535059 3.76663307 1 P 0 ;0,1=616,2=270.000000
L 2.69535059 3.76663307 2.69793337 3.76471673 1 P 0 ;0,1=616,2=270.000000
L 2.69793337 3.76471673 2.69896644 3.76241654 1 P 0 ;0,1=616,2=270.000000
L 2.69896644 3.76241654 2.69896644 3.75858337 1 P 0 ;0,1=616,2=270.000000
L 2.69896644 3.75858337 2.70051713 3.75513337 1 P 0 ;0,1=616,2=270.000000
L 2.70051713 3.75513337 2.70361732 3.75283317 1 P 0 ;0,1=616,2=270.000000
L 2.70361732 3.75283317 2.70723327 3.75206663 1 P 0 ;0,1=616,2=270.000000
L 2.70723327 3.75206663 2.71085108 3.75283317 1 P 0 ;0,1=616,2=270.000000
L 2.71085108 3.75283317 2.71343386 3.7547501 1 P 0 ;0,1=616,2=270.000000
L 2.71343386 3.7547501 2.71498346 3.75781683 1 P 0 ;0,1=616,2=270.000000
L 2.71498346 3.75781683 2.7155 3.76049961 1 P 0 ;0,1=616,2=270.000000
L 2.7155 3.79149961 2.71498346 3.79418307 1 P 0 ;0,1=616,2=270.000000
L 2.71498346 3.79418307 2.71343386 3.7972498 1 P 0 ;0,1=616,2=270.000000
L 2.71343386 3.7972498 2.71085108 3.79916673 1 P 0 ;0,1=616,2=270.000000
L 2.71085108 3.79916673 2.70723327 3.79993327 1 P 0 ;0,1=616,2=270.000000
L 2.70723327 3.79993327 2.70361732 3.79916673 1 P 0 ;0,1=616,2=270.000000
L 2.70361732 3.79916673 2.70051713 3.79686654 1 P 0 ;0,1=616,2=270.000000
L 2.70051713 3.79686654 2.69896644 3.79341654 1 P 0 ;0,1=616,2=270.000000
L 2.69896644 3.79341654 2.69896644 3.78958337 1 P 0 ;0,1=616,2=270.000000
L 2.69896644 3.78958337 2.69793337 3.78728317 1 P 0 ;0,1=616,2=270.000000
L 2.69793337 3.78728317 2.69535059 3.78536614 1 P 0 ;0,1=616,2=270.000000
L 2.69535059 3.78536614 2.69173376 3.7845997 1 P 0 ;0,1=616,2=270.000000
L 2.69173376 3.7845997 2.68811693 3.7857501 1 P 0 ;0,1=616,2=270.000000
L 2.68811693 3.7857501 2.68553317 3.78843287 1 P 0 ;0,1=616,2=270.000000
L 2.68553317 3.78843287 2.6845 3.79149961 1 P 0 ;0,1=616,2=270.000000
L 2.6845 3.79149961 2.68553317 3.79456634 1 P 0 ;0,1=616,2=270.000000
L 2.68553317 3.79456634 2.68811693 3.7972498 1 P 0 ;0,1=616,2=270.000000
L 2.68811693 3.7972498 2.69173376 3.7984002 1 P 0 ;0,1=616,2=270.000000
L 2.69173376 3.7984002 2.69535059 3.79763307 1 P 0 ;0,1=616,2=270.000000
L 2.69535059 3.79763307 2.69793337 3.79571673 1 P 0 ;0,1=616,2=270.000000
L 2.69793337 3.79571673 2.69896644 3.79341654 1 P 0 ;0,1=616,2=270.000000
L 2.69896644 3.79341654 2.69896644 3.78958337 1 P 0 ;0,1=616,2=270.000000
L 2.69896644 3.78958337 2.70051713 3.78613337 1 P 0 ;0,1=616,2=270.000000
L 2.70051713 3.78613337 2.70361732 3.78383317 1 P 0 ;0,1=616,2=270.000000
L 2.70361732 3.78383317 2.70723327 3.78306663 1 P 0 ;0,1=616,2=270.000000
L 2.70723327 3.78306663 2.71085108 3.78383317 1 P 0 ;0,1=616,2=270.000000
L 2.71085108 3.78383317 2.71343386 3.7857501 1 P 0 ;0,1=616,2=270.000000
L 2.71343386 3.7857501 2.71498346 3.78881683 1 P 0 ;0,1=616,2=270.000000
L 2.71498346 3.78881683 2.7155 3.79149961 1 P 0 ;0,1=616,2=270.000000
L 3.867 3.07 3.957 3.07 1 P 0 
L 3.957 3.07 3.957 3.114 1 P 0 
L 3.957 3.114 3.867 3.114 1 P 0 
L 3.867 3.114 3.867 3.07 1 P 0 
L 4.00708376 3.11193327 4.00553317 3.10963307 1 P 0 ;0,1=617,2=270.000000
L 4.00553317 3.10963307 4.0045 3.1069503 1 P 0 ;0,1=617,2=270.000000
L 4.0045 3.1069503 4.0045 3.10388356 1 P 0 ;0,1=617,2=270.000000
L 4.0045 3.10388356 4.00605069 3.10043287 1 P 0 ;0,1=617,2=270.000000
L 4.00605069 3.10043287 4.00863346 3.0977501 1 P 0 ;0,1=617,2=270.000000
L 4.00863346 3.0977501 4.01173376 3.09583317 1 P 0 ;0,1=617,2=270.000000
L 4.01173376 3.09583317 4.0169002 3.09429951 1 P 0 ;0,1=617,2=270.000000
L 4.0169002 3.09429951 4.0215502 3.09391624 1 P 0 ;0,1=617,2=270.000000
L 4.0215502 3.09391624 4.0262001 3.09468337 1 P 0 ;0,1=617,2=270.000000
L 4.0262001 3.09468337 4.02930039 3.09583317 1 P 0 ;0,1=617,2=270.000000
L 4.02930039 3.09583317 4.03240069 3.09813337 1 P 0 ;0,1=617,2=270.000000
L 4.03240069 3.09813337 4.03446693 3.10081683 1 P 0 ;0,1=617,2=270.000000
L 4.03446693 3.10081683 4.0355 3.10349961 1 P 0 ;0,1=617,2=270.000000
L 4.0355 3.10349961 4.0355 3.10618307 1 P 0 ;0,1=617,2=270.000000
L 4.0355 3.10618307 4.03446693 3.10886654 1 P 0 ;0,1=617,2=270.000000
L 4.03446693 3.10886654 4.03291722 3.11116673 1 P 0 ;0,1=617,2=270.000000
L 4.03291722 3.11116673 4.03085108 3.11308366 1 P 0 ;0,1=617,2=270.000000
L 4.0355 3.13449961 4.0045 3.13449961 1 P 0 ;0,1=617,2=270.000000
L 4.0045 3.13449961 4.0106997 3.1298999 1 P 0 ;0,1=617,2=270.000000
L 4.0355 3.1298999 4.0355 3.13909931 1 P 0 ;0,1=617,2=270.000000
L 4.0355 3.16549961 4.03498346 3.16818307 1 P 0 ;0,1=617,2=270.000000
L 4.03498346 3.16818307 4.03343386 3.1712498 1 P 0 ;0,1=617,2=270.000000
L 4.03343386 3.1712498 4.03085108 3.17316673 1 P 0 ;0,1=617,2=270.000000
L 4.03085108 3.17316673 4.02723327 3.17393327 1 P 0 ;0,1=617,2=270.000000
L 4.02723327 3.17393327 4.02361732 3.17316673 1 P 0 ;0,1=617,2=270.000000
L 4.02361732 3.17316673 4.02051713 3.17086654 1 P 0 ;0,1=617,2=270.000000
L 4.02051713 3.17086654 4.01896644 3.16741654 1 P 0 ;0,1=617,2=270.000000
L 4.01896644 3.16741654 4.01896644 3.16358337 1 P 0 ;0,1=617,2=270.000000
L 4.01896644 3.16358337 4.01793337 3.16128317 1 P 0 ;0,1=617,2=270.000000
L 4.01793337 3.16128317 4.01535059 3.15936614 1 P 0 ;0,1=617,2=270.000000
L 4.01535059 3.15936614 4.01173376 3.1585997 1 P 0 ;0,1=617,2=270.000000
L 4.01173376 3.1585997 4.00811693 3.1597501 1 P 0 ;0,1=617,2=270.000000
L 4.00811693 3.1597501 4.00553317 3.16243287 1 P 0 ;0,1=617,2=270.000000
L 4.00553317 3.16243287 4.0045 3.16549961 1 P 0 ;0,1=617,2=270.000000
L 4.0045 3.16549961 4.00553317 3.16856634 1 P 0 ;0,1=617,2=270.000000
L 4.00553317 3.16856634 4.00811693 3.1712498 1 P 0 ;0,1=617,2=270.000000
L 4.00811693 3.1712498 4.01173376 3.1724002 1 P 0 ;0,1=617,2=270.000000
L 4.01173376 3.1724002 4.01535059 3.17163307 1 P 0 ;0,1=617,2=270.000000
L 4.01535059 3.17163307 4.01793337 3.16971673 1 P 0 ;0,1=617,2=270.000000
L 4.01793337 3.16971673 4.01896644 3.16741654 1 P 0 ;0,1=617,2=270.000000
L 4.01896644 3.16741654 4.01896644 3.16358337 1 P 0 ;0,1=617,2=270.000000
L 4.01896644 3.16358337 4.02051713 3.16013337 1 P 0 ;0,1=617,2=270.000000
L 4.02051713 3.16013337 4.02361732 3.15783317 1 P 0 ;0,1=617,2=270.000000
L 4.02361732 3.15783317 4.02723327 3.15706663 1 P 0 ;0,1=617,2=270.000000
L 4.02723327 3.15706663 4.03085108 3.15783317 1 P 0 ;0,1=617,2=270.000000
L 4.03085108 3.15783317 4.03343386 3.1597501 1 P 0 ;0,1=617,2=270.000000
L 4.03343386 3.1597501 4.03498346 3.16281683 1 P 0 ;0,1=617,2=270.000000
L 4.03498346 3.16281683 4.0355 3.16549961 1 P 0 ;0,1=617,2=270.000000
L 4.0355 3.2011 4.0045 3.2011 1 P 0 ;0,1=617,2=270.000000
L 4.0045 3.2011 4.02671673 3.18691624 1 P 0 ;0,1=617,2=270.000000
L 4.02671673 3.18691624 4.02671673 3.20608366 1 P 0 ;0,1=617,2=270.000000
L 3.528 4.175 3.618 4.175 1 P 0 
L 3.618 4.175 3.618 4.219 1 P 0 
L 3.618 4.219 3.528 4.219 1 P 0 
L 3.528 4.219 3.528 4.175 1 P 0 
L 3.55243327 4.28291624 3.55013307 4.28446683 1 P 0 ;0,1=618,2=0.000000
L 3.55013307 4.28446683 3.5474503 4.2855 1 P 0 ;0,1=618,2=0.000000
L 3.5474503 4.2855 3.54438356 4.2855 1 P 0 ;0,1=618,2=0.000000
L 3.54438356 4.2855 3.54093287 4.28394931 1 P 0 ;0,1=618,2=0.000000
L 3.54093287 4.28394931 3.5382501 4.28136654 1 P 0 ;0,1=618,2=0.000000
L 3.5382501 4.28136654 3.53633317 4.27826624 1 P 0 ;0,1=618,2=0.000000
L 3.53633317 4.27826624 3.53479951 4.2730998 1 P 0 ;0,1=618,2=0.000000
L 3.53479951 4.2730998 3.53441624 4.2684498 1 P 0 ;0,1=618,2=0.000000
L 3.53441624 4.2684498 3.53518337 4.2637999 1 P 0 ;0,1=618,2=0.000000
L 3.53518337 4.2637999 3.53633317 4.26069961 1 P 0 ;0,1=618,2=0.000000
L 3.53633317 4.26069961 3.53863337 4.25759931 1 P 0 ;0,1=618,2=0.000000
L 3.53863337 4.25759931 3.54131683 4.25553307 1 P 0 ;0,1=618,2=0.000000
L 3.54131683 4.25553307 3.54399961 4.2545 1 P 0 ;0,1=618,2=0.000000
L 3.54399961 4.2545 3.54668307 4.2545 1 P 0 ;0,1=618,2=0.000000
L 3.54668307 4.2545 3.54936654 4.25553307 1 P 0 ;0,1=618,2=0.000000
L 3.54936654 4.25553307 3.55166673 4.25708278 1 P 0 ;0,1=618,2=0.000000
L 3.55166673 4.25708278 3.55358366 4.25914892 1 P 0 ;0,1=618,2=0.000000
L 3.57423307 4.2545 3.57499961 4.26121614 1 P 0 ;0,1=618,2=0.000000
L 3.57499961 4.26121614 3.5761501 4.26689921 1 P 0 ;0,1=618,2=0.000000
L 3.5761501 4.26689921 3.57768307 4.27206663 1 P 0 ;0,1=618,2=0.000000
L 3.57768307 4.27206663 3.5796 4.2777497 1 P 0 ;0,1=618,2=0.000000
L 3.5796 4.2777497 3.58266673 4.2855 1 P 0 ;0,1=618,2=0.000000
L 3.58266673 4.2855 3.56733317 4.2855 1 P 0 ;0,1=618,2=0.000000
L 3.59871644 4.26741575 3.6013999 4.27103356 1 P 0 ;0,1=618,2=0.000000
L 3.6013999 4.27103356 3.6037001 4.2730998 1 P 0 ;0,1=618,2=0.000000
L 3.6037001 4.2730998 3.60676683 4.27413287 1 P 0 ;0,1=618,2=0.000000
L 3.60676683 4.27413287 3.6094503 4.2730998 1 P 0 ;0,1=618,2=0.000000
L 3.6094503 4.2730998 3.61136654 4.27103356 1 P 0 ;0,1=618,2=0.000000
L 3.61136654 4.27103356 3.6129002 4.26793327 1 P 0 ;0,1=618,2=0.000000
L 3.6129002 4.26793327 3.61328346 4.26431644 1 P 0 ;0,1=618,2=0.000000
L 3.61328346 4.26431644 3.6129002 4.26121614 1 P 0 ;0,1=618,2=0.000000
L 3.6129002 4.26121614 3.61136654 4.25811585 1 P 0 ;0,1=618,2=0.000000
L 3.61136654 4.25811585 3.60906634 4.25553307 1 P 0 ;0,1=618,2=0.000000
L 3.60906634 4.25553307 3.60638356 4.2545 1 P 0 ;0,1=618,2=0.000000
L 3.60638356 4.2545 3.60331683 4.25553307 1 P 0 ;0,1=618,2=0.000000
L 3.60331683 4.25553307 3.60063337 4.25863238 1 P 0 ;0,1=618,2=0.000000
L 3.60063337 4.25863238 3.5990997 4.26328327 1 P 0 ;0,1=618,2=0.000000
L 3.5990997 4.26328327 3.59871644 4.2684498 1 P 0 ;0,1=618,2=0.000000
L 3.59871644 4.2684498 3.59948287 4.27516594 1 P 0 ;0,1=618,2=0.000000
L 3.59948287 4.27516594 3.60063337 4.27878376 1 P 0 ;0,1=618,2=0.000000
L 3.60063337 4.27878376 3.60254961 4.2823997 1 P 0 ;0,1=618,2=0.000000
L 3.60254961 4.2823997 3.60523307 4.28498337 1 P 0 ;0,1=618,2=0.000000
L 3.60523307 4.28498337 3.60791654 4.2855 1 P 0 ;0,1=618,2=0.000000
L 3.60791654 4.2855 3.6106 4.28446683 1 P 0 ;0,1=618,2=0.000000
L 3.6106 4.28446683 3.61251703 4.28188307 1 P 0 ;0,1=618,2=0.000000
L 3.498 3.965 3.588 3.965 1 P 0 
L 3.588 3.965 3.588 4.009 1 P 0 
L 3.588 4.009 3.498 4.009 1 P 0 
L 3.498 4.009 3.498 3.965 1 P 0 
L 3.64043327 3.99491624 3.63813307 3.99646683 1 P 0 ;0,1=619,2=0.000000
L 3.63813307 3.99646683 3.6354503 3.9975 1 P 0 ;0,1=619,2=0.000000
L 3.6354503 3.9975 3.63238356 3.9975 1 P 0 ;0,1=619,2=0.000000
L 3.63238356 3.9975 3.62893287 3.99594931 1 P 0 ;0,1=619,2=0.000000
L 3.62893287 3.99594931 3.6262501 3.99336654 1 P 0 ;0,1=619,2=0.000000
L 3.6262501 3.99336654 3.62433317 3.99026624 1 P 0 ;0,1=619,2=0.000000
L 3.62433317 3.99026624 3.62279951 3.9850998 1 P 0 ;0,1=619,2=0.000000
L 3.62279951 3.9850998 3.62241624 3.9804498 1 P 0 ;0,1=619,2=0.000000
L 3.62241624 3.9804498 3.62318337 3.9757999 1 P 0 ;0,1=619,2=0.000000
L 3.62318337 3.9757999 3.62433317 3.97269961 1 P 0 ;0,1=619,2=0.000000
L 3.62433317 3.97269961 3.62663337 3.96959931 1 P 0 ;0,1=619,2=0.000000
L 3.62663337 3.96959931 3.62931683 3.96753307 1 P 0 ;0,1=619,2=0.000000
L 3.62931683 3.96753307 3.63199961 3.9665 1 P 0 ;0,1=619,2=0.000000
L 3.63199961 3.9665 3.63468307 3.9665 1 P 0 ;0,1=619,2=0.000000
L 3.63468307 3.9665 3.63736654 3.96753307 1 P 0 ;0,1=619,2=0.000000
L 3.63736654 3.96753307 3.63966673 3.96908278 1 P 0 ;0,1=619,2=0.000000
L 3.63966673 3.96908278 3.64158366 3.97114892 1 P 0 ;0,1=619,2=0.000000
L 3.6676 3.9665 3.6676 3.9975 1 P 0 ;0,1=619,2=0.000000
L 3.6676 3.9975 3.65341624 3.97528327 1 P 0 ;0,1=619,2=0.000000
L 3.65341624 3.97528327 3.67258366 3.97528327 1 P 0 ;0,1=619,2=0.000000
L 3.68748287 3.97011585 3.69016634 3.96753307 1 P 0 ;0,1=619,2=0.000000
L 3.69016634 3.96753307 3.69323307 3.9665 1 P 0 ;0,1=619,2=0.000000
L 3.69323307 3.9665 3.6962998 3.96753307 1 P 0 ;0,1=619,2=0.000000
L 3.6962998 3.96753307 3.69898327 3.97063238 1 P 0 ;0,1=619,2=0.000000
L 3.69898327 3.97063238 3.7009002 3.97528327 1 P 0 ;0,1=619,2=0.000000
L 3.7009002 3.97528327 3.70166673 3.97993327 1 P 0 ;0,1=619,2=0.000000
L 3.70166673 3.97993327 3.70166673 3.98561634 1 P 0 ;0,1=619,2=0.000000
L 3.70166673 3.98561634 3.7009002 3.99026624 1 P 0 ;0,1=619,2=0.000000
L 3.7009002 3.99026624 3.69898327 3.9943997 1 P 0 ;0,1=619,2=0.000000
L 3.69898327 3.9943997 3.69668307 3.99646683 1 P 0 ;0,1=619,2=0.000000
L 3.69668307 3.99646683 3.69399961 3.9975 1 P 0 ;0,1=619,2=0.000000
L 3.69399961 3.9975 3.69093287 3.99646683 1 P 0 ;0,1=619,2=0.000000
L 3.69093287 3.99646683 3.68863337 3.9943997 1 P 0 ;0,1=619,2=0.000000
L 3.68863337 3.9943997 3.6870997 3.9913003 1 P 0 ;0,1=619,2=0.000000
L 3.6870997 3.9913003 3.68633317 3.98716594 1 P 0 ;0,1=619,2=0.000000
L 3.68633317 3.98716594 3.6870997 3.9835501 1 P 0 ;0,1=619,2=0.000000
L 3.6870997 3.9835501 3.68901663 3.97993327 1 P 0 ;0,1=619,2=0.000000
L 3.68901663 3.97993327 3.69131683 3.97786604 1 P 0 ;0,1=619,2=0.000000
L 3.69131683 3.97786604 3.69399961 3.97734951 1 P 0 ;0,1=619,2=0.000000
L 3.69399961 3.97734951 3.69706634 3.97838268 1 P 0 ;0,1=619,2=0.000000
L 3.69706634 3.97838268 3.69936654 3.98096634 1 P 0 ;0,1=619,2=0.000000
L 3.69936654 3.98096634 3.70166673 3.98561634 1 P 0 ;0,1=619,2=0.000000
L 3.498 4.01 3.588 4.01 1 P 0 
L 3.588 4.01 3.588 4.054 1 P 0 
L 3.588 4.054 3.498 4.054 1 P 0 
L 3.498 4.054 3.498 4.01 1 P 0 
L 3.64043327 4.03991624 3.63813307 4.04146683 1 P 0 ;0,1=620,2=0.000000
L 3.63813307 4.04146683 3.6354503 4.0425 1 P 0 ;0,1=620,2=0.000000
L 3.6354503 4.0425 3.63238356 4.0425 1 P 0 ;0,1=620,2=0.000000
L 3.63238356 4.0425 3.62893287 4.04094931 1 P 0 ;0,1=620,2=0.000000
L 3.62893287 4.04094931 3.6262501 4.03836654 1 P 0 ;0,1=620,2=0.000000
L 3.6262501 4.03836654 3.62433317 4.03526624 1 P 0 ;0,1=620,2=0.000000
L 3.62433317 4.03526624 3.62279951 4.0300998 1 P 0 ;0,1=620,2=0.000000
L 3.62279951 4.0300998 3.62241624 4.0254498 1 P 0 ;0,1=620,2=0.000000
L 3.62241624 4.0254498 3.62318337 4.0207999 1 P 0 ;0,1=620,2=0.000000
L 3.62318337 4.0207999 3.62433317 4.01769961 1 P 0 ;0,1=620,2=0.000000
L 3.62433317 4.01769961 3.62663337 4.01459931 1 P 0 ;0,1=620,2=0.000000
L 3.62663337 4.01459931 3.62931683 4.01253307 1 P 0 ;0,1=620,2=0.000000
L 3.62931683 4.01253307 3.63199961 4.0115 1 P 0 ;0,1=620,2=0.000000
L 3.63199961 4.0115 3.63468307 4.0115 1 P 0 ;0,1=620,2=0.000000
L 3.63468307 4.0115 3.63736654 4.01253307 1 P 0 ;0,1=620,2=0.000000
L 3.63736654 4.01253307 3.63966673 4.01408278 1 P 0 ;0,1=620,2=0.000000
L 3.63966673 4.01408278 3.64158366 4.01614892 1 P 0 ;0,1=620,2=0.000000
L 3.6676 4.0115 3.6676 4.0425 1 P 0 ;0,1=620,2=0.000000
L 3.6676 4.0425 3.65341624 4.02028327 1 P 0 ;0,1=620,2=0.000000
L 3.65341624 4.02028327 3.67258366 4.02028327 1 P 0 ;0,1=620,2=0.000000
L 3.68671644 4.02441575 3.6893999 4.02803356 1 P 0 ;0,1=620,2=0.000000
L 3.6893999 4.02803356 3.6917001 4.0300998 1 P 0 ;0,1=620,2=0.000000
L 3.6917001 4.0300998 3.69476683 4.03113287 1 P 0 ;0,1=620,2=0.000000
L 3.69476683 4.03113287 3.6974503 4.0300998 1 P 0 ;0,1=620,2=0.000000
L 3.6974503 4.0300998 3.69936654 4.02803356 1 P 0 ;0,1=620,2=0.000000
L 3.69936654 4.02803356 3.7009002 4.02493327 1 P 0 ;0,1=620,2=0.000000
L 3.7009002 4.02493327 3.70128346 4.02131644 1 P 0 ;0,1=620,2=0.000000
L 3.70128346 4.02131644 3.7009002 4.01821614 1 P 0 ;0,1=620,2=0.000000
L 3.7009002 4.01821614 3.69936654 4.01511585 1 P 0 ;0,1=620,2=0.000000
L 3.69936654 4.01511585 3.69706634 4.01253307 1 P 0 ;0,1=620,2=0.000000
L 3.69706634 4.01253307 3.69438356 4.0115 1 P 0 ;0,1=620,2=0.000000
L 3.69438356 4.0115 3.69131683 4.01253307 1 P 0 ;0,1=620,2=0.000000
L 3.69131683 4.01253307 3.68863337 4.01563238 1 P 0 ;0,1=620,2=0.000000
L 3.68863337 4.01563238 3.6870997 4.02028327 1 P 0 ;0,1=620,2=0.000000
L 3.6870997 4.02028327 3.68671644 4.0254498 1 P 0 ;0,1=620,2=0.000000
L 3.68671644 4.0254498 3.68748287 4.03216594 1 P 0 ;0,1=620,2=0.000000
L 3.68748287 4.03216594 3.68863337 4.03578376 1 P 0 ;0,1=620,2=0.000000
L 3.68863337 4.03578376 3.69054961 4.0393997 1 P 0 ;0,1=620,2=0.000000
L 3.69054961 4.0393997 3.69323307 4.04198337 1 P 0 ;0,1=620,2=0.000000
L 3.69323307 4.04198337 3.69591654 4.0425 1 P 0 ;0,1=620,2=0.000000
L 3.69591654 4.0425 3.6986 4.04146683 1 P 0 ;0,1=620,2=0.000000
L 3.6986 4.04146683 3.70051703 4.03888307 1 P 0 ;0,1=620,2=0.000000
L 3.684 2.952 3.684 3.042 1 P 0 
L 3.684 3.042 3.64 3.042 1 P 0 
L 3.64 3.042 3.64 2.952 1 P 0 
L 3.64 2.952 3.684 2.952 1 P 0 
L 2.58208376 3.70693327 2.58053317 3.70463307 1 P 0 ;0,1=621,2=270.000000
L 2.58053317 3.70463307 2.5795 3.7019503 1 P 0 ;0,1=621,2=270.000000
L 2.5795 3.7019503 2.5795 3.69888356 1 P 0 ;0,1=621,2=270.000000
L 2.5795 3.69888356 2.58105069 3.69543287 1 P 0 ;0,1=621,2=270.000000
L 2.58105069 3.69543287 2.58363346 3.6927501 1 P 0 ;0,1=621,2=270.000000
L 2.58363346 3.6927501 2.58673376 3.69083317 1 P 0 ;0,1=621,2=270.000000
L 2.58673376 3.69083317 2.5919002 3.68929951 1 P 0 ;0,1=621,2=270.000000
L 2.5919002 3.68929951 2.5965502 3.68891624 1 P 0 ;0,1=621,2=270.000000
L 2.5965502 3.68891624 2.6012001 3.68968337 1 P 0 ;0,1=621,2=270.000000
L 2.6012001 3.68968337 2.60430039 3.69083317 1 P 0 ;0,1=621,2=270.000000
L 2.60430039 3.69083317 2.60740069 3.69313337 1 P 0 ;0,1=621,2=270.000000
L 2.60740069 3.69313337 2.60946693 3.69581683 1 P 0 ;0,1=621,2=270.000000
L 2.60946693 3.69581683 2.6105 3.69849961 1 P 0 ;0,1=621,2=270.000000
L 2.6105 3.69849961 2.6105 3.70118307 1 P 0 ;0,1=621,2=270.000000
L 2.6105 3.70118307 2.60946693 3.70386654 1 P 0 ;0,1=621,2=270.000000
L 2.60946693 3.70386654 2.60791722 3.70616673 1 P 0 ;0,1=621,2=270.000000
L 2.60791722 3.70616673 2.60585108 3.70808366 1 P 0 ;0,1=621,2=270.000000
L 2.6105 3.72949961 2.5795 3.72949961 1 P 0 ;0,1=621,2=270.000000
L 2.5795 3.72949961 2.5856997 3.7248999 1 P 0 ;0,1=621,2=270.000000
L 2.6105 3.7248999 2.6105 3.73409931 1 P 0 ;0,1=621,2=270.000000
L 2.6105 3.76049961 2.60998346 3.76318307 1 P 0 ;0,1=621,2=270.000000
L 2.60998346 3.76318307 2.60843386 3.7662498 1 P 0 ;0,1=621,2=270.000000
L 2.60843386 3.7662498 2.60585108 3.76816673 1 P 0 ;0,1=621,2=270.000000
L 2.60585108 3.76816673 2.60223327 3.76893327 1 P 0 ;0,1=621,2=270.000000
L 2.60223327 3.76893327 2.59861732 3.76816673 1 P 0 ;0,1=621,2=270.000000
L 2.59861732 3.76816673 2.59551713 3.76586654 1 P 0 ;0,1=621,2=270.000000
L 2.59551713 3.76586654 2.59396644 3.76241654 1 P 0 ;0,1=621,2=270.000000
L 2.59396644 3.76241654 2.59396644 3.75858337 1 P 0 ;0,1=621,2=270.000000
L 2.59396644 3.75858337 2.59293337 3.75628317 1 P 0 ;0,1=621,2=270.000000
L 2.59293337 3.75628317 2.59035059 3.75436614 1 P 0 ;0,1=621,2=270.000000
L 2.59035059 3.75436614 2.58673376 3.7535997 1 P 0 ;0,1=621,2=270.000000
L 2.58673376 3.7535997 2.58311693 3.7547501 1 P 0 ;0,1=621,2=270.000000
L 2.58311693 3.7547501 2.58053317 3.75743287 1 P 0 ;0,1=621,2=270.000000
L 2.58053317 3.75743287 2.5795 3.76049961 1 P 0 ;0,1=621,2=270.000000
L 2.5795 3.76049961 2.58053317 3.76356634 1 P 0 ;0,1=621,2=270.000000
L 2.58053317 3.76356634 2.58311693 3.7662498 1 P 0 ;0,1=621,2=270.000000
L 2.58311693 3.7662498 2.58673376 3.7674002 1 P 0 ;0,1=621,2=270.000000
L 2.58673376 3.7674002 2.59035059 3.76663307 1 P 0 ;0,1=621,2=270.000000
L 2.59035059 3.76663307 2.59293337 3.76471673 1 P 0 ;0,1=621,2=270.000000
L 2.59293337 3.76471673 2.59396644 3.76241654 1 P 0 ;0,1=621,2=270.000000
L 2.59396644 3.76241654 2.59396644 3.75858337 1 P 0 ;0,1=621,2=270.000000
L 2.59396644 3.75858337 2.59551713 3.75513337 1 P 0 ;0,1=621,2=270.000000
L 2.59551713 3.75513337 2.59861732 3.75283317 1 P 0 ;0,1=621,2=270.000000
L 2.59861732 3.75283317 2.60223327 3.75206663 1 P 0 ;0,1=621,2=270.000000
L 2.60223327 3.75206663 2.60585108 3.75283317 1 P 0 ;0,1=621,2=270.000000
L 2.60585108 3.75283317 2.60843386 3.7547501 1 P 0 ;0,1=621,2=270.000000
L 2.60843386 3.7547501 2.60998346 3.75781683 1 P 0 ;0,1=621,2=270.000000
L 2.60998346 3.75781683 2.6105 3.76049961 1 P 0 ;0,1=621,2=270.000000
L 2.58466654 3.78421644 2.58156722 3.78651663 1 P 0 ;0,1=621,2=270.000000
L 2.58156722 3.78651663 2.58001663 3.7892001 1 P 0 ;0,1=621,2=270.000000
L 2.58001663 3.7892001 2.5795 3.79226683 1 P 0 ;0,1=621,2=270.000000
L 2.5795 3.79226683 2.58053317 3.7961 1 P 0 ;0,1=621,2=270.000000
L 2.58053317 3.7961 2.58311693 3.79878346 1 P 0 ;0,1=621,2=270.000000
L 2.58311693 3.79878346 2.58621624 3.79955 1 P 0 ;0,1=621,2=270.000000
L 2.58621624 3.79955 2.58931742 3.79916673 1 P 0 ;0,1=621,2=270.000000
L 2.58931742 3.79916673 2.5919002 3.79763307 1 P 0 ;0,1=621,2=270.000000
L 2.5919002 3.79763307 2.59706673 3.78996663 1 P 0 ;0,1=621,2=270.000000
L 2.59706673 3.78996663 2.60068356 3.78651663 1 P 0 ;0,1=621,2=270.000000
L 2.60068356 3.78651663 2.60585108 3.78421644 1 P 0 ;0,1=621,2=270.000000
L 2.60585108 3.78421644 2.6105 3.7834499 1 P 0 ;0,1=621,2=270.000000
L 2.6105 3.7834499 2.6105 3.79955 1 P 0 ;0,1=621,2=270.000000
L 3.604 2.922 3.56 2.922 1 P 0 
L 3.604 2.832 3.604 2.922 1 P 0 
L 3.56 2.922 3.56 2.832 1 P 0 
L 3.56 2.832 3.604 2.832 1 P 0 
L 2.48708376 3.61193327 2.48553317 3.60963307 1 P 0 ;0,1=622,2=270.000000
L 2.48553317 3.60963307 2.4845 3.6069503 1 P 0 ;0,1=622,2=270.000000
L 2.4845 3.6069503 2.4845 3.60388356 1 P 0 ;0,1=622,2=270.000000
L 2.4845 3.60388356 2.48605069 3.60043287 1 P 0 ;0,1=622,2=270.000000
L 2.48605069 3.60043287 2.48863346 3.5977501 1 P 0 ;0,1=622,2=270.000000
L 2.48863346 3.5977501 2.49173376 3.59583317 1 P 0 ;0,1=622,2=270.000000
L 2.49173376 3.59583317 2.4969002 3.59429951 1 P 0 ;0,1=622,2=270.000000
L 2.4969002 3.59429951 2.5015502 3.59391624 1 P 0 ;0,1=622,2=270.000000
L 2.5015502 3.59391624 2.5062001 3.59468337 1 P 0 ;0,1=622,2=270.000000
L 2.5062001 3.59468337 2.50930039 3.59583317 1 P 0 ;0,1=622,2=270.000000
L 2.50930039 3.59583317 2.51240069 3.59813337 1 P 0 ;0,1=622,2=270.000000
L 2.51240069 3.59813337 2.51446693 3.60081683 1 P 0 ;0,1=622,2=270.000000
L 2.51446693 3.60081683 2.5155 3.60349961 1 P 0 ;0,1=622,2=270.000000
L 2.5155 3.60349961 2.5155 3.60618307 1 P 0 ;0,1=622,2=270.000000
L 2.5155 3.60618307 2.51446693 3.60886654 1 P 0 ;0,1=622,2=270.000000
L 2.51446693 3.60886654 2.51291722 3.61116673 1 P 0 ;0,1=622,2=270.000000
L 2.51291722 3.61116673 2.51085108 3.61308366 1 P 0 ;0,1=622,2=270.000000
L 2.5155 3.63449961 2.4845 3.63449961 1 P 0 ;0,1=622,2=270.000000
L 2.4845 3.63449961 2.4906997 3.6298999 1 P 0 ;0,1=622,2=270.000000
L 2.5155 3.6298999 2.5155 3.63909931 1 P 0 ;0,1=622,2=270.000000
L 2.51188415 3.65898287 2.51446693 3.66166634 1 P 0 ;0,1=622,2=270.000000
L 2.51446693 3.66166634 2.5155 3.66473307 1 P 0 ;0,1=622,2=270.000000
L 2.5155 3.66473307 2.51446693 3.6677998 1 P 0 ;0,1=622,2=270.000000
L 2.51446693 3.6677998 2.51136762 3.67048327 1 P 0 ;0,1=622,2=270.000000
L 2.51136762 3.67048327 2.50671673 3.6724002 1 P 0 ;0,1=622,2=270.000000
L 2.50671673 3.6724002 2.50206673 3.67316673 1 P 0 ;0,1=622,2=270.000000
L 2.50206673 3.67316673 2.49638366 3.67316673 1 P 0 ;0,1=622,2=270.000000
L 2.49638366 3.67316673 2.49173376 3.6724002 1 P 0 ;0,1=622,2=270.000000
L 2.49173376 3.6724002 2.4876003 3.67048327 1 P 0 ;0,1=622,2=270.000000
L 2.4876003 3.67048327 2.48553317 3.66818307 1 P 0 ;0,1=622,2=270.000000
L 2.48553317 3.66818307 2.4845 3.66549961 1 P 0 ;0,1=622,2=270.000000
L 2.4845 3.66549961 2.48553317 3.66243287 1 P 0 ;0,1=622,2=270.000000
L 2.48553317 3.66243287 2.4876003 3.66013337 1 P 0 ;0,1=622,2=270.000000
L 2.4876003 3.66013337 2.4906997 3.6585997 1 P 0 ;0,1=622,2=270.000000
L 2.4906997 3.6585997 2.49483406 3.65783317 1 P 0 ;0,1=622,2=270.000000
L 2.49483406 3.65783317 2.4984499 3.6585997 1 P 0 ;0,1=622,2=270.000000
L 2.4984499 3.6585997 2.50206673 3.66051663 1 P 0 ;0,1=622,2=270.000000
L 2.50206673 3.66051663 2.50413396 3.66281683 1 P 0 ;0,1=622,2=270.000000
L 2.50413396 3.66281683 2.50465049 3.66549961 1 P 0 ;0,1=622,2=270.000000
L 2.50465049 3.66549961 2.50361732 3.66856634 1 P 0 ;0,1=622,2=270.000000
L 2.50361732 3.66856634 2.50103366 3.67086654 1 P 0 ;0,1=622,2=270.000000
L 2.50103366 3.67086654 2.49638366 3.67316673 1 P 0 ;0,1=622,2=270.000000
L 2.51188415 3.68998287 2.51446693 3.69266634 1 P 0 ;0,1=622,2=270.000000
L 2.51446693 3.69266634 2.5155 3.69573307 1 P 0 ;0,1=622,2=270.000000
L 2.5155 3.69573307 2.51446693 3.6987998 1 P 0 ;0,1=622,2=270.000000
L 2.51446693 3.6987998 2.51136762 3.70148327 1 P 0 ;0,1=622,2=270.000000
L 2.51136762 3.70148327 2.50671673 3.7034002 1 P 0 ;0,1=622,2=270.000000
L 2.50671673 3.7034002 2.50206673 3.70416673 1 P 0 ;0,1=622,2=270.000000
L 2.50206673 3.70416673 2.49638366 3.70416673 1 P 0 ;0,1=622,2=270.000000
L 2.49638366 3.70416673 2.49173376 3.7034002 1 P 0 ;0,1=622,2=270.000000
L 2.49173376 3.7034002 2.4876003 3.70148327 1 P 0 ;0,1=622,2=270.000000
L 2.4876003 3.70148327 2.48553317 3.69918307 1 P 0 ;0,1=622,2=270.000000
L 2.48553317 3.69918307 2.4845 3.69649961 1 P 0 ;0,1=622,2=270.000000
L 2.4845 3.69649961 2.48553317 3.69343287 1 P 0 ;0,1=622,2=270.000000
L 2.48553317 3.69343287 2.4876003 3.69113337 1 P 0 ;0,1=622,2=270.000000
L 2.4876003 3.69113337 2.4906997 3.6895997 1 P 0 ;0,1=622,2=270.000000
L 2.4906997 3.6895997 2.49483406 3.68883317 1 P 0 ;0,1=622,2=270.000000
L 2.49483406 3.68883317 2.4984499 3.6895997 1 P 0 ;0,1=622,2=270.000000
L 2.4984499 3.6895997 2.50206673 3.69151663 1 P 0 ;0,1=622,2=270.000000
L 2.50206673 3.69151663 2.50413396 3.69381683 1 P 0 ;0,1=622,2=270.000000
L 2.50413396 3.69381683 2.50465049 3.69649961 1 P 0 ;0,1=622,2=270.000000
L 2.50465049 3.69649961 2.50361732 3.69956634 1 P 0 ;0,1=622,2=270.000000
L 2.50361732 3.69956634 2.50103366 3.70186654 1 P 0 ;0,1=622,2=270.000000
L 2.50103366 3.70186654 2.49638366 3.70416673 1 P 0 ;0,1=622,2=270.000000
L 3.353 4.115 3.353 4.159 1 P 0 
L 3.353 4.159 3.263 4.159 1 P 0 
L 3.263 4.159 3.263 4.115 1 P 0 
L 3.263 4.115 3.353 4.115 1 P 0 
L 3.17543327 4.14491624 3.17313307 4.14646683 1 P 0 ;0,1=623,2=0.000000
L 3.17313307 4.14646683 3.1704503 4.1475 1 P 0 ;0,1=623,2=0.000000
L 3.1704503 4.1475 3.16738356 4.1475 1 P 0 ;0,1=623,2=0.000000
L 3.16738356 4.1475 3.16393287 4.14594931 1 P 0 ;0,1=623,2=0.000000
L 3.16393287 4.14594931 3.1612501 4.14336654 1 P 0 ;0,1=623,2=0.000000
L 3.1612501 4.14336654 3.15933317 4.14026624 1 P 0 ;0,1=623,2=0.000000
L 3.15933317 4.14026624 3.15779951 4.1350998 1 P 0 ;0,1=623,2=0.000000
L 3.15779951 4.1350998 3.15741624 4.1304498 1 P 0 ;0,1=623,2=0.000000
L 3.15741624 4.1304498 3.15818337 4.1257999 1 P 0 ;0,1=623,2=0.000000
L 3.15818337 4.1257999 3.15933317 4.12269961 1 P 0 ;0,1=623,2=0.000000
L 3.15933317 4.12269961 3.16163337 4.11959931 1 P 0 ;0,1=623,2=0.000000
L 3.16163337 4.11959931 3.16431683 4.11753307 1 P 0 ;0,1=623,2=0.000000
L 3.16431683 4.11753307 3.16699961 4.1165 1 P 0 ;0,1=623,2=0.000000
L 3.16699961 4.1165 3.16968307 4.1165 1 P 0 ;0,1=623,2=0.000000
L 3.16968307 4.1165 3.17236654 4.11753307 1 P 0 ;0,1=623,2=0.000000
L 3.17236654 4.11753307 3.17466673 4.11908278 1 P 0 ;0,1=623,2=0.000000
L 3.17466673 4.11908278 3.17658366 4.12114892 1 P 0 ;0,1=623,2=0.000000
L 3.18956663 4.12114892 3.19186614 4.11856614 1 P 0 ;0,1=623,2=0.000000
L 3.19186614 4.11856614 3.19454961 4.11701654 1 P 0 ;0,1=623,2=0.000000
L 3.19454961 4.11701654 3.19799961 4.1165 1 P 0 ;0,1=623,2=0.000000
L 3.19799961 4.1165 3.2014503 4.11753307 1 P 0 ;0,1=623,2=0.000000
L 3.2014503 4.11753307 3.20413307 4.11959931 1 P 0 ;0,1=623,2=0.000000
L 3.20413307 4.11959931 3.20605 4.12321614 1 P 0 ;0,1=623,2=0.000000
L 3.20605 4.12321614 3.20643327 4.12734951 1 P 0 ;0,1=623,2=0.000000
L 3.20643327 4.12734951 3.20566673 4.13148287 1 P 0 ;0,1=623,2=0.000000
L 3.20566673 4.13148287 3.2037498 4.13406663 1 P 0 ;0,1=623,2=0.000000
L 3.2037498 4.13406663 3.20106634 4.13613287 1 P 0 ;0,1=623,2=0.000000
L 3.20106634 4.13613287 3.19838356 4.13664941 1 P 0 ;0,1=623,2=0.000000
L 3.19838356 4.13664941 3.1957001 4.13613287 1 P 0 ;0,1=623,2=0.000000
L 3.1957001 4.13613287 3.1922501 4.13406663 1 P 0 ;0,1=623,2=0.000000
L 3.1922501 4.13406663 3.1933999 4.1475 1 P 0 ;0,1=623,2=0.000000
L 3.1933999 4.1475 3.2037498 4.1475 1 P 0 ;0,1=623,2=0.000000
L 3.22056663 4.12269961 3.22286614 4.11908278 1 P 0 ;0,1=623,2=0.000000
L 3.22286614 4.11908278 3.22593287 4.11701654 1 P 0 ;0,1=623,2=0.000000
L 3.22593287 4.11701654 3.22938356 4.1165 1 P 0 ;0,1=623,2=0.000000
L 3.22938356 4.1165 3.2324503 4.11701654 1 P 0 ;0,1=623,2=0.000000
L 3.2324503 4.11701654 3.23551703 4.11959931 1 P 0 ;0,1=623,2=0.000000
L 3.23551703 4.11959931 3.23743327 4.12269961 1 P 0 ;0,1=623,2=0.000000
L 3.23743327 4.12269961 3.23781654 4.1257999 1 P 0 ;0,1=623,2=0.000000
L 3.23781654 4.1257999 3.23705 4.12941575 1 P 0 ;0,1=623,2=0.000000
L 3.23705 4.12941575 3.23436654 4.13199951 1 P 0 ;0,1=623,2=0.000000
L 3.23436654 4.13199951 3.23168307 4.13303356 1 P 0 ;0,1=623,2=0.000000
L 3.23168307 4.13303356 3.22823307 4.13303356 1 P 0 ;0,1=623,2=0.000000
L 3.23168307 4.13303356 3.23398327 4.13458317 1 P 0 ;0,1=623,2=0.000000
L 3.23398327 4.13458317 3.2359002 4.13716594 1 P 0 ;0,1=623,2=0.000000
L 3.2359002 4.13716594 3.23666673 4.14026624 1 P 0 ;0,1=623,2=0.000000
L 3.23666673 4.14026624 3.2359002 4.14336654 1 P 0 ;0,1=623,2=0.000000
L 3.2359002 4.14336654 3.23398327 4.14594931 1 P 0 ;0,1=623,2=0.000000
L 3.23398327 4.14594931 3.23053327 4.1475 1 P 0 ;0,1=623,2=0.000000
L 3.23053327 4.1475 3.22708337 4.14698337 1 P 0 ;0,1=623,2=0.000000
L 3.22708337 4.14698337 3.22363337 4.14491624 1 P 0 ;0,1=623,2=0.000000
L 4.552 3.825 4.552 3.915 1 P 0 
L 4.552 3.915 4.508 3.915 1 P 0 
L 4.508 3.915 4.508 3.825 1 P 0 
L 4.508 3.825 4.552 3.825 1 P 0 
L 4.46208376 3.85243327 4.46053317 3.85013307 1 P 0 ;0,1=624,2=270.000000
L 4.46053317 3.85013307 4.4595 3.8474503 1 P 0 ;0,1=624,2=270.000000
L 4.4595 3.8474503 4.4595 3.84438356 1 P 0 ;0,1=624,2=270.000000
L 4.4595 3.84438356 4.46105069 3.84093287 1 P 0 ;0,1=624,2=270.000000
L 4.46105069 3.84093287 4.46363346 3.8382501 1 P 0 ;0,1=624,2=270.000000
L 4.46363346 3.8382501 4.46673376 3.83633317 1 P 0 ;0,1=624,2=270.000000
L 4.46673376 3.83633317 4.4719002 3.83479951 1 P 0 ;0,1=624,2=270.000000
L 4.4719002 3.83479951 4.4765502 3.83441624 1 P 0 ;0,1=624,2=270.000000
L 4.4765502 3.83441624 4.4812001 3.83518337 1 P 0 ;0,1=624,2=270.000000
L 4.4812001 3.83518337 4.48430039 3.83633317 1 P 0 ;0,1=624,2=270.000000
L 4.48430039 3.83633317 4.48740069 3.83863337 1 P 0 ;0,1=624,2=270.000000
L 4.48740069 3.83863337 4.48946693 3.84131683 1 P 0 ;0,1=624,2=270.000000
L 4.48946693 3.84131683 4.4905 3.84399961 1 P 0 ;0,1=624,2=270.000000
L 4.4905 3.84399961 4.4905 3.84668307 1 P 0 ;0,1=624,2=270.000000
L 4.4905 3.84668307 4.48946693 3.84936654 1 P 0 ;0,1=624,2=270.000000
L 4.48946693 3.84936654 4.48791722 3.85166673 1 P 0 ;0,1=624,2=270.000000
L 4.48791722 3.85166673 4.48585108 3.85358366 1 P 0 ;0,1=624,2=270.000000
L 4.4905 3.87499961 4.48998346 3.87768307 1 P 0 ;0,1=624,2=270.000000
L 4.48998346 3.87768307 4.48843386 3.8807498 1 P 0 ;0,1=624,2=270.000000
L 4.48843386 3.8807498 4.48585108 3.88266673 1 P 0 ;0,1=624,2=270.000000
L 4.48585108 3.88266673 4.48223327 3.88343327 1 P 0 ;0,1=624,2=270.000000
L 4.48223327 3.88343327 4.47861732 3.88266673 1 P 0 ;0,1=624,2=270.000000
L 4.47861732 3.88266673 4.47551713 3.88036654 1 P 0 ;0,1=624,2=270.000000
L 4.47551713 3.88036654 4.47396644 3.87691654 1 P 0 ;0,1=624,2=270.000000
L 4.47396644 3.87691654 4.47396644 3.87308337 1 P 0 ;0,1=624,2=270.000000
L 4.47396644 3.87308337 4.47293337 3.87078317 1 P 0 ;0,1=624,2=270.000000
L 4.47293337 3.87078317 4.47035059 3.86886614 1 P 0 ;0,1=624,2=270.000000
L 4.47035059 3.86886614 4.46673376 3.8680997 1 P 0 ;0,1=624,2=270.000000
L 4.46673376 3.8680997 4.46311693 3.8692501 1 P 0 ;0,1=624,2=270.000000
L 4.46311693 3.8692501 4.46053317 3.87193287 1 P 0 ;0,1=624,2=270.000000
L 4.46053317 3.87193287 4.4595 3.87499961 1 P 0 ;0,1=624,2=270.000000
L 4.4595 3.87499961 4.46053317 3.87806634 1 P 0 ;0,1=624,2=270.000000
L 4.46053317 3.87806634 4.46311693 3.8807498 1 P 0 ;0,1=624,2=270.000000
L 4.46311693 3.8807498 4.46673376 3.8819002 1 P 0 ;0,1=624,2=270.000000
L 4.46673376 3.8819002 4.47035059 3.88113307 1 P 0 ;0,1=624,2=270.000000
L 4.47035059 3.88113307 4.47293337 3.87921673 1 P 0 ;0,1=624,2=270.000000
L 4.47293337 3.87921673 4.47396644 3.87691654 1 P 0 ;0,1=624,2=270.000000
L 4.47396644 3.87691654 4.47396644 3.87308337 1 P 0 ;0,1=624,2=270.000000
L 4.47396644 3.87308337 4.47551713 3.86963337 1 P 0 ;0,1=624,2=270.000000
L 4.47551713 3.86963337 4.47861732 3.86733317 1 P 0 ;0,1=624,2=270.000000
L 4.47861732 3.86733317 4.48223327 3.86656663 1 P 0 ;0,1=624,2=270.000000
L 4.48223327 3.86656663 4.48585108 3.86733317 1 P 0 ;0,1=624,2=270.000000
L 4.48585108 3.86733317 4.48843386 3.8692501 1 P 0 ;0,1=624,2=270.000000
L 4.48843386 3.8692501 4.48998346 3.87231683 1 P 0 ;0,1=624,2=270.000000
L 4.48998346 3.87231683 4.4905 3.87499961 1 P 0 ;0,1=624,2=270.000000
L 4.4905 3.90599961 4.4595 3.90599961 1 P 0 ;0,1=624,2=270.000000
L 4.4595 3.90599961 4.4656997 3.9013999 1 P 0 ;0,1=624,2=270.000000
L 4.4905 3.9013999 4.4905 3.91059931 1 P 0 ;0,1=624,2=270.000000
L 5.228 2.614 5.138 2.614 1 P 0 
L 5.138 2.614 5.138 2.57 1 P 0 
L 5.138 2.57 5.228 2.57 1 P 0 
L 5.228 2.57 5.228 2.614 1 P 0 
L 5.16993327 2.44491624 5.16763307 2.44646683 1 P 0 ;0,1=625,2=0.000000
L 5.16763307 2.44646683 5.1649503 2.4475 1 P 0 ;0,1=625,2=0.000000
L 5.1649503 2.4475 5.16188356 2.4475 1 P 0 ;0,1=625,2=0.000000
L 5.16188356 2.4475 5.15843287 2.44594931 1 P 0 ;0,1=625,2=0.000000
L 5.15843287 2.44594931 5.1557501 2.44336654 1 P 0 ;0,1=625,2=0.000000
L 5.1557501 2.44336654 5.15383317 2.44026624 1 P 0 ;0,1=625,2=0.000000
L 5.15383317 2.44026624 5.15229951 2.4350998 1 P 0 ;0,1=625,2=0.000000
L 5.15229951 2.4350998 5.15191624 2.4304498 1 P 0 ;0,1=625,2=0.000000
L 5.15191624 2.4304498 5.15268337 2.4257999 1 P 0 ;0,1=625,2=0.000000
L 5.15268337 2.4257999 5.15383317 2.42269961 1 P 0 ;0,1=625,2=0.000000
L 5.15383317 2.42269961 5.15613337 2.41959931 1 P 0 ;0,1=625,2=0.000000
L 5.15613337 2.41959931 5.15881683 2.41753307 1 P 0 ;0,1=625,2=0.000000
L 5.15881683 2.41753307 5.16149961 2.4165 1 P 0 ;0,1=625,2=0.000000
L 5.16149961 2.4165 5.16418307 2.4165 1 P 0 ;0,1=625,2=0.000000
L 5.16418307 2.4165 5.16686654 2.41753307 1 P 0 ;0,1=625,2=0.000000
L 5.16686654 2.41753307 5.16916673 2.41908278 1 P 0 ;0,1=625,2=0.000000
L 5.16916673 2.41908278 5.17108366 2.42114892 1 P 0 ;0,1=625,2=0.000000
L 5.19249961 2.4165 5.19249961 2.4475 1 P 0 ;0,1=625,2=0.000000
L 5.19249961 2.4475 5.1878999 2.4413003 1 P 0 ;0,1=625,2=0.000000
L 5.1878999 2.4165 5.19709931 2.4165 1 P 0 ;0,1=625,2=0.000000
L 5.21698287 2.42011585 5.21966634 2.41753307 1 P 0 ;0,1=625,2=0.000000
L 5.21966634 2.41753307 5.22273307 2.4165 1 P 0 ;0,1=625,2=0.000000
L 5.22273307 2.4165 5.2257998 2.41753307 1 P 0 ;0,1=625,2=0.000000
L 5.2257998 2.41753307 5.22848327 2.42063238 1 P 0 ;0,1=625,2=0.000000
L 5.22848327 2.42063238 5.2304002 2.42528327 1 P 0 ;0,1=625,2=0.000000
L 5.2304002 2.42528327 5.23116673 2.42993327 1 P 0 ;0,1=625,2=0.000000
L 5.23116673 2.42993327 5.23116673 2.43561634 1 P 0 ;0,1=625,2=0.000000
L 5.23116673 2.43561634 5.2304002 2.44026624 1 P 0 ;0,1=625,2=0.000000
L 5.2304002 2.44026624 5.22848327 2.4443997 1 P 0 ;0,1=625,2=0.000000
L 5.22848327 2.4443997 5.22618307 2.44646683 1 P 0 ;0,1=625,2=0.000000
L 5.22618307 2.44646683 5.22349961 2.4475 1 P 0 ;0,1=625,2=0.000000
L 5.22349961 2.4475 5.22043287 2.44646683 1 P 0 ;0,1=625,2=0.000000
L 5.22043287 2.44646683 5.21813337 2.4443997 1 P 0 ;0,1=625,2=0.000000
L 5.21813337 2.4443997 5.2165997 2.4413003 1 P 0 ;0,1=625,2=0.000000
L 5.2165997 2.4413003 5.21583317 2.43716594 1 P 0 ;0,1=625,2=0.000000
L 5.21583317 2.43716594 5.2165997 2.4335501 1 P 0 ;0,1=625,2=0.000000
L 5.2165997 2.4335501 5.21851663 2.42993327 1 P 0 ;0,1=625,2=0.000000
L 5.21851663 2.42993327 5.22081683 2.42786604 1 P 0 ;0,1=625,2=0.000000
L 5.22081683 2.42786604 5.22349961 2.42734951 1 P 0 ;0,1=625,2=0.000000
L 5.22349961 2.42734951 5.22656634 2.42838268 1 P 0 ;0,1=625,2=0.000000
L 5.22656634 2.42838268 5.22886654 2.43096634 1 P 0 ;0,1=625,2=0.000000
L 5.22886654 2.43096634 5.23116673 2.43561634 1 P 0 ;0,1=625,2=0.000000
L 5.25373307 2.4165 5.25449961 2.42321614 1 P 0 ;0,1=625,2=0.000000
L 5.25449961 2.42321614 5.2556501 2.42889921 1 P 0 ;0,1=625,2=0.000000
L 5.2556501 2.42889921 5.25718307 2.43406663 1 P 0 ;0,1=625,2=0.000000
L 5.25718307 2.43406663 5.2591 2.4397497 1 P 0 ;0,1=625,2=0.000000
L 5.2591 2.4397497 5.26216673 2.4475 1 P 0 ;0,1=625,2=0.000000
L 5.26216673 2.4475 5.24683317 2.4475 1 P 0 ;0,1=625,2=0.000000
L 5.108 2.575 5.108 2.619 1 P 0 
L 5.018 2.575 5.108 2.575 1 P 0 
L 5.108 2.619 5.018 2.619 1 P 0 
L 5.018 2.619 5.018 2.575 1 P 0 
L 5.04493327 2.38491624 5.04263307 2.38646683 1 P 0 ;0,1=626,2=0.000000
L 5.04263307 2.38646683 5.0399503 2.3875 1 P 0 ;0,1=626,2=0.000000
L 5.0399503 2.3875 5.03688356 2.3875 1 P 0 ;0,1=626,2=0.000000
L 5.03688356 2.3875 5.03343287 2.38594931 1 P 0 ;0,1=626,2=0.000000
L 5.03343287 2.38594931 5.0307501 2.38336654 1 P 0 ;0,1=626,2=0.000000
L 5.0307501 2.38336654 5.02883317 2.38026624 1 P 0 ;0,1=626,2=0.000000
L 5.02883317 2.38026624 5.02729951 2.3750998 1 P 0 ;0,1=626,2=0.000000
L 5.02729951 2.3750998 5.02691624 2.3704498 1 P 0 ;0,1=626,2=0.000000
L 5.02691624 2.3704498 5.02768337 2.3657999 1 P 0 ;0,1=626,2=0.000000
L 5.02768337 2.3657999 5.02883317 2.36269961 1 P 0 ;0,1=626,2=0.000000
L 5.02883317 2.36269961 5.03113337 2.35959931 1 P 0 ;0,1=626,2=0.000000
L 5.03113337 2.35959931 5.03381683 2.35753307 1 P 0 ;0,1=626,2=0.000000
L 5.03381683 2.35753307 5.03649961 2.3565 1 P 0 ;0,1=626,2=0.000000
L 5.03649961 2.3565 5.03918307 2.3565 1 P 0 ;0,1=626,2=0.000000
L 5.03918307 2.3565 5.04186654 2.35753307 1 P 0 ;0,1=626,2=0.000000
L 5.04186654 2.35753307 5.04416673 2.35908278 1 P 0 ;0,1=626,2=0.000000
L 5.04416673 2.35908278 5.04608366 2.36114892 1 P 0 ;0,1=626,2=0.000000
L 5.06749961 2.3565 5.06749961 2.3875 1 P 0 ;0,1=626,2=0.000000
L 5.06749961 2.3875 5.0628999 2.3813003 1 P 0 ;0,1=626,2=0.000000
L 5.0628999 2.3565 5.07209931 2.3565 1 P 0 ;0,1=626,2=0.000000
L 5.09849961 2.3565 5.10118307 2.35701654 1 P 0 ;0,1=626,2=0.000000
L 5.10118307 2.35701654 5.1042498 2.35856614 1 P 0 ;0,1=626,2=0.000000
L 5.1042498 2.35856614 5.10616673 2.36114892 1 P 0 ;0,1=626,2=0.000000
L 5.10616673 2.36114892 5.10693327 2.36476673 1 P 0 ;0,1=626,2=0.000000
L 5.10693327 2.36476673 5.10616673 2.36838268 1 P 0 ;0,1=626,2=0.000000
L 5.10616673 2.36838268 5.10386654 2.37148287 1 P 0 ;0,1=626,2=0.000000
L 5.10386654 2.37148287 5.10041654 2.37303356 1 P 0 ;0,1=626,2=0.000000
L 5.10041654 2.37303356 5.09658337 2.37303356 1 P 0 ;0,1=626,2=0.000000
L 5.09658337 2.37303356 5.09428317 2.37406663 1 P 0 ;0,1=626,2=0.000000
L 5.09428317 2.37406663 5.09236614 2.37664941 1 P 0 ;0,1=626,2=0.000000
L 5.09236614 2.37664941 5.0915997 2.38026624 1 P 0 ;0,1=626,2=0.000000
L 5.0915997 2.38026624 5.0927501 2.38388307 1 P 0 ;0,1=626,2=0.000000
L 5.0927501 2.38388307 5.09543287 2.38646683 1 P 0 ;0,1=626,2=0.000000
L 5.09543287 2.38646683 5.09849961 2.3875 1 P 0 ;0,1=626,2=0.000000
L 5.09849961 2.3875 5.10156634 2.38646683 1 P 0 ;0,1=626,2=0.000000
L 5.10156634 2.38646683 5.1042498 2.38388307 1 P 0 ;0,1=626,2=0.000000
L 5.1042498 2.38388307 5.1054002 2.38026624 1 P 0 ;0,1=626,2=0.000000
L 5.1054002 2.38026624 5.10463307 2.37664941 1 P 0 ;0,1=626,2=0.000000
L 5.10463307 2.37664941 5.10271673 2.37406663 1 P 0 ;0,1=626,2=0.000000
L 5.10271673 2.37406663 5.10041654 2.37303356 1 P 0 ;0,1=626,2=0.000000
L 5.10041654 2.37303356 5.09658337 2.37303356 1 P 0 ;0,1=626,2=0.000000
L 5.09658337 2.37303356 5.09313337 2.37148287 1 P 0 ;0,1=626,2=0.000000
L 5.09313337 2.37148287 5.09083317 2.36838268 1 P 0 ;0,1=626,2=0.000000
L 5.09083317 2.36838268 5.09006663 2.36476673 1 P 0 ;0,1=626,2=0.000000
L 5.09006663 2.36476673 5.09083317 2.36114892 1 P 0 ;0,1=626,2=0.000000
L 5.09083317 2.36114892 5.0927501 2.35856614 1 P 0 ;0,1=626,2=0.000000
L 5.0927501 2.35856614 5.09581683 2.35701654 1 P 0 ;0,1=626,2=0.000000
L 5.09581683 2.35701654 5.09849961 2.3565 1 P 0 ;0,1=626,2=0.000000
L 5.12298287 2.36011585 5.12566634 2.35753307 1 P 0 ;0,1=626,2=0.000000
L 5.12566634 2.35753307 5.12873307 2.3565 1 P 0 ;0,1=626,2=0.000000
L 5.12873307 2.3565 5.1317998 2.35753307 1 P 0 ;0,1=626,2=0.000000
L 5.1317998 2.35753307 5.13448327 2.36063238 1 P 0 ;0,1=626,2=0.000000
L 5.13448327 2.36063238 5.1364002 2.36528327 1 P 0 ;0,1=626,2=0.000000
L 5.1364002 2.36528327 5.13716673 2.36993327 1 P 0 ;0,1=626,2=0.000000
L 5.13716673 2.36993327 5.13716673 2.37561634 1 P 0 ;0,1=626,2=0.000000
L 5.13716673 2.37561634 5.1364002 2.38026624 1 P 0 ;0,1=626,2=0.000000
L 5.1364002 2.38026624 5.13448327 2.3843997 1 P 0 ;0,1=626,2=0.000000
L 5.13448327 2.3843997 5.13218307 2.38646683 1 P 0 ;0,1=626,2=0.000000
L 5.13218307 2.38646683 5.12949961 2.3875 1 P 0 ;0,1=626,2=0.000000
L 5.12949961 2.3875 5.12643287 2.38646683 1 P 0 ;0,1=626,2=0.000000
L 5.12643287 2.38646683 5.12413337 2.3843997 1 P 0 ;0,1=626,2=0.000000
L 5.12413337 2.3843997 5.1225997 2.3813003 1 P 0 ;0,1=626,2=0.000000
L 5.1225997 2.3813003 5.12183317 2.37716594 1 P 0 ;0,1=626,2=0.000000
L 5.12183317 2.37716594 5.1225997 2.3735501 1 P 0 ;0,1=626,2=0.000000
L 5.1225997 2.3735501 5.12451663 2.36993327 1 P 0 ;0,1=626,2=0.000000
L 5.12451663 2.36993327 5.12681683 2.36786604 1 P 0 ;0,1=626,2=0.000000
L 5.12681683 2.36786604 5.12949961 2.36734951 1 P 0 ;0,1=626,2=0.000000
L 5.12949961 2.36734951 5.13256634 2.36838268 1 P 0 ;0,1=626,2=0.000000
L 5.13256634 2.36838268 5.13486654 2.37096634 1 P 0 ;0,1=626,2=0.000000
L 5.13486654 2.37096634 5.13716673 2.37561634 1 P 0 ;0,1=626,2=0.000000
L 5.622 2.3 5.622 2.39 1 P 0 
L 5.622 2.39 5.578 2.39 1 P 0 
L 5.578 2.39 5.578 2.3 1 P 0 
L 5.578 2.3 5.622 2.3 1 P 0 
L 5.51208376 2.42693327 5.51053317 2.42463307 1 P 0 ;0,1=627,2=270.000000
L 5.51053317 2.42463307 5.5095 2.4219503 1 P 0 ;0,1=627,2=270.000000
L 5.5095 2.4219503 5.5095 2.41888356 1 P 0 ;0,1=627,2=270.000000
L 5.5095 2.41888356 5.51105069 2.41543287 1 P 0 ;0,1=627,2=270.000000
L 5.51105069 2.41543287 5.51363346 2.4127501 1 P 0 ;0,1=627,2=270.000000
L 5.51363346 2.4127501 5.51673376 2.41083317 1 P 0 ;0,1=627,2=270.000000
L 5.51673376 2.41083317 5.5219002 2.40929951 1 P 0 ;0,1=627,2=270.000000
L 5.5219002 2.40929951 5.5265502 2.40891624 1 P 0 ;0,1=627,2=270.000000
L 5.5265502 2.40891624 5.5312001 2.40968337 1 P 0 ;0,1=627,2=270.000000
L 5.5312001 2.40968337 5.53430039 2.41083317 1 P 0 ;0,1=627,2=270.000000
L 5.53430039 2.41083317 5.53740069 2.41313337 1 P 0 ;0,1=627,2=270.000000
L 5.53740069 2.41313337 5.53946693 2.41581683 1 P 0 ;0,1=627,2=270.000000
L 5.53946693 2.41581683 5.5405 2.41849961 1 P 0 ;0,1=627,2=270.000000
L 5.5405 2.41849961 5.5405 2.42118307 1 P 0 ;0,1=627,2=270.000000
L 5.5405 2.42118307 5.53946693 2.42386654 1 P 0 ;0,1=627,2=270.000000
L 5.53946693 2.42386654 5.53791722 2.42616673 1 P 0 ;0,1=627,2=270.000000
L 5.53791722 2.42616673 5.53585108 2.42808366 1 P 0 ;0,1=627,2=270.000000
L 5.51466654 2.44221644 5.51156722 2.44451663 1 P 0 ;0,1=627,2=270.000000
L 5.51156722 2.44451663 5.51001663 2.4472001 1 P 0 ;0,1=627,2=270.000000
L 5.51001663 2.4472001 5.5095 2.45026683 1 P 0 ;0,1=627,2=270.000000
L 5.5095 2.45026683 5.51053317 2.4541 1 P 0 ;0,1=627,2=270.000000
L 5.51053317 2.4541 5.51311693 2.45678346 1 P 0 ;0,1=627,2=270.000000
L 5.51311693 2.45678346 5.51621624 2.45755 1 P 0 ;0,1=627,2=270.000000
L 5.51621624 2.45755 5.51931742 2.45716673 1 P 0 ;0,1=627,2=270.000000
L 5.51931742 2.45716673 5.5219002 2.45563307 1 P 0 ;0,1=627,2=270.000000
L 5.5219002 2.45563307 5.52706673 2.44796663 1 P 0 ;0,1=627,2=270.000000
L 5.52706673 2.44796663 5.53068356 2.44451663 1 P 0 ;0,1=627,2=270.000000
L 5.53068356 2.44451663 5.53585108 2.44221644 1 P 0 ;0,1=627,2=270.000000
L 5.53585108 2.44221644 5.5405 2.4414499 1 P 0 ;0,1=627,2=270.000000
L 5.5405 2.4414499 5.5405 2.45755 1 P 0 ;0,1=627,2=270.000000
L 5.53585108 2.47206663 5.53843386 2.47436614 1 P 0 ;0,1=627,2=270.000000
L 5.53843386 2.47436614 5.53998346 2.47704961 1 P 0 ;0,1=627,2=270.000000
L 5.53998346 2.47704961 5.5405 2.48049961 1 P 0 ;0,1=627,2=270.000000
L 5.5405 2.48049961 5.53946693 2.4839503 1 P 0 ;0,1=627,2=270.000000
L 5.53946693 2.4839503 5.53740069 2.48663307 1 P 0 ;0,1=627,2=270.000000
L 5.53740069 2.48663307 5.53378386 2.48855 1 P 0 ;0,1=627,2=270.000000
L 5.53378386 2.48855 5.52965049 2.48893327 1 P 0 ;0,1=627,2=270.000000
L 5.52965049 2.48893327 5.52551713 2.48816673 1 P 0 ;0,1=627,2=270.000000
L 5.52551713 2.48816673 5.52293337 2.4862498 1 P 0 ;0,1=627,2=270.000000
L 5.52293337 2.4862498 5.52086713 2.48356634 1 P 0 ;0,1=627,2=270.000000
L 5.52086713 2.48356634 5.52035059 2.48088356 1 P 0 ;0,1=627,2=270.000000
L 5.52035059 2.48088356 5.52086713 2.4782001 1 P 0 ;0,1=627,2=270.000000
L 5.52086713 2.4782001 5.52293337 2.4747501 1 P 0 ;0,1=627,2=270.000000
L 5.52293337 2.4747501 5.5095 2.4758999 1 P 0 ;0,1=627,2=270.000000
L 5.5095 2.4758999 5.5095 2.4862498 1 P 0 ;0,1=627,2=270.000000
L 5.53688415 2.50498287 5.53946693 2.50766634 1 P 0 ;0,1=627,2=270.000000
L 5.53946693 2.50766634 5.5405 2.51073307 1 P 0 ;0,1=627,2=270.000000
L 5.5405 2.51073307 5.53946693 2.5137998 1 P 0 ;0,1=627,2=270.000000
L 5.53946693 2.5137998 5.53636762 2.51648327 1 P 0 ;0,1=627,2=270.000000
L 5.53636762 2.51648327 5.53171673 2.5184002 1 P 0 ;0,1=627,2=270.000000
L 5.53171673 2.5184002 5.52706673 2.51916673 1 P 0 ;0,1=627,2=270.000000
L 5.52706673 2.51916673 5.52138366 2.51916673 1 P 0 ;0,1=627,2=270.000000
L 5.52138366 2.51916673 5.51673376 2.5184002 1 P 0 ;0,1=627,2=270.000000
L 5.51673376 2.5184002 5.5126003 2.51648327 1 P 0 ;0,1=627,2=270.000000
L 5.5126003 2.51648327 5.51053317 2.51418307 1 P 0 ;0,1=627,2=270.000000
L 5.51053317 2.51418307 5.5095 2.51149961 1 P 0 ;0,1=627,2=270.000000
L 5.5095 2.51149961 5.51053317 2.50843287 1 P 0 ;0,1=627,2=270.000000
L 5.51053317 2.50843287 5.5126003 2.50613337 1 P 0 ;0,1=627,2=270.000000
L 5.5126003 2.50613337 5.5156997 2.5045997 1 P 0 ;0,1=627,2=270.000000
L 5.5156997 2.5045997 5.51983406 2.50383317 1 P 0 ;0,1=627,2=270.000000
L 5.51983406 2.50383317 5.5234499 2.5045997 1 P 0 ;0,1=627,2=270.000000
L 5.5234499 2.5045997 5.52706673 2.50651663 1 P 0 ;0,1=627,2=270.000000
L 5.52706673 2.50651663 5.52913396 2.50881683 1 P 0 ;0,1=627,2=270.000000
L 5.52913396 2.50881683 5.52965049 2.51149961 1 P 0 ;0,1=627,2=270.000000
L 5.52965049 2.51149961 5.52861732 2.51456634 1 P 0 ;0,1=627,2=270.000000
L 5.52861732 2.51456634 5.52603366 2.51686654 1 P 0 ;0,1=627,2=270.000000
L 5.52603366 2.51686654 5.52138366 2.51916673 1 P 0 ;0,1=627,2=270.000000
L 5.577 2.39 5.533 2.39 1 P 0 
L 5.577 2.3 5.577 2.39 1 P 0 
L 5.533 2.39 5.533 2.3 1 P 0 
L 5.533 2.3 5.577 2.3 1 P 0 
L 5.47208376 2.42693327 5.47053317 2.42463307 1 P 0 ;0,1=628,2=270.000000
L 5.47053317 2.42463307 5.4695 2.4219503 1 P 0 ;0,1=628,2=270.000000
L 5.4695 2.4219503 5.4695 2.41888356 1 P 0 ;0,1=628,2=270.000000
L 5.4695 2.41888356 5.47105069 2.41543287 1 P 0 ;0,1=628,2=270.000000
L 5.47105069 2.41543287 5.47363346 2.4127501 1 P 0 ;0,1=628,2=270.000000
L 5.47363346 2.4127501 5.47673376 2.41083317 1 P 0 ;0,1=628,2=270.000000
L 5.47673376 2.41083317 5.4819002 2.40929951 1 P 0 ;0,1=628,2=270.000000
L 5.4819002 2.40929951 5.4865502 2.40891624 1 P 0 ;0,1=628,2=270.000000
L 5.4865502 2.40891624 5.4912001 2.40968337 1 P 0 ;0,1=628,2=270.000000
L 5.4912001 2.40968337 5.49430039 2.41083317 1 P 0 ;0,1=628,2=270.000000
L 5.49430039 2.41083317 5.49740069 2.41313337 1 P 0 ;0,1=628,2=270.000000
L 5.49740069 2.41313337 5.49946693 2.41581683 1 P 0 ;0,1=628,2=270.000000
L 5.49946693 2.41581683 5.5005 2.41849961 1 P 0 ;0,1=628,2=270.000000
L 5.5005 2.41849961 5.5005 2.42118307 1 P 0 ;0,1=628,2=270.000000
L 5.5005 2.42118307 5.49946693 2.42386654 1 P 0 ;0,1=628,2=270.000000
L 5.49946693 2.42386654 5.49791722 2.42616673 1 P 0 ;0,1=628,2=270.000000
L 5.49791722 2.42616673 5.49585108 2.42808366 1 P 0 ;0,1=628,2=270.000000
L 5.47466654 2.44221644 5.47156722 2.44451663 1 P 0 ;0,1=628,2=270.000000
L 5.47156722 2.44451663 5.47001663 2.4472001 1 P 0 ;0,1=628,2=270.000000
L 5.47001663 2.4472001 5.4695 2.45026683 1 P 0 ;0,1=628,2=270.000000
L 5.4695 2.45026683 5.47053317 2.4541 1 P 0 ;0,1=628,2=270.000000
L 5.47053317 2.4541 5.47311693 2.45678346 1 P 0 ;0,1=628,2=270.000000
L 5.47311693 2.45678346 5.47621624 2.45755 1 P 0 ;0,1=628,2=270.000000
L 5.47621624 2.45755 5.47931742 2.45716673 1 P 0 ;0,1=628,2=270.000000
L 5.47931742 2.45716673 5.4819002 2.45563307 1 P 0 ;0,1=628,2=270.000000
L 5.4819002 2.45563307 5.48706673 2.44796663 1 P 0 ;0,1=628,2=270.000000
L 5.48706673 2.44796663 5.49068356 2.44451663 1 P 0 ;0,1=628,2=270.000000
L 5.49068356 2.44451663 5.49585108 2.44221644 1 P 0 ;0,1=628,2=270.000000
L 5.49585108 2.44221644 5.5005 2.4414499 1 P 0 ;0,1=628,2=270.000000
L 5.5005 2.4414499 5.5005 2.45755 1 P 0 ;0,1=628,2=270.000000
L 5.49585108 2.47206663 5.49843386 2.47436614 1 P 0 ;0,1=628,2=270.000000
L 5.49843386 2.47436614 5.49998346 2.47704961 1 P 0 ;0,1=628,2=270.000000
L 5.49998346 2.47704961 5.5005 2.48049961 1 P 0 ;0,1=628,2=270.000000
L 5.5005 2.48049961 5.49946693 2.4839503 1 P 0 ;0,1=628,2=270.000000
L 5.49946693 2.4839503 5.49740069 2.48663307 1 P 0 ;0,1=628,2=270.000000
L 5.49740069 2.48663307 5.49378386 2.48855 1 P 0 ;0,1=628,2=270.000000
L 5.49378386 2.48855 5.48965049 2.48893327 1 P 0 ;0,1=628,2=270.000000
L 5.48965049 2.48893327 5.48551713 2.48816673 1 P 0 ;0,1=628,2=270.000000
L 5.48551713 2.48816673 5.48293337 2.4862498 1 P 0 ;0,1=628,2=270.000000
L 5.48293337 2.4862498 5.48086713 2.48356634 1 P 0 ;0,1=628,2=270.000000
L 5.48086713 2.48356634 5.48035059 2.48088356 1 P 0 ;0,1=628,2=270.000000
L 5.48035059 2.48088356 5.48086713 2.4782001 1 P 0 ;0,1=628,2=270.000000
L 5.48086713 2.4782001 5.48293337 2.4747501 1 P 0 ;0,1=628,2=270.000000
L 5.48293337 2.4747501 5.4695 2.4758999 1 P 0 ;0,1=628,2=270.000000
L 5.4695 2.4758999 5.4695 2.4862498 1 P 0 ;0,1=628,2=270.000000
L 5.48758425 2.50421644 5.48396644 2.5068999 1 P 0 ;0,1=628,2=270.000000
L 5.48396644 2.5068999 5.4819002 2.5092001 1 P 0 ;0,1=628,2=270.000000
L 5.4819002 2.5092001 5.48086713 2.51226683 1 P 0 ;0,1=628,2=270.000000
L 5.48086713 2.51226683 5.4819002 2.5149503 1 P 0 ;0,1=628,2=270.000000
L 5.4819002 2.5149503 5.48396644 2.51686654 1 P 0 ;0,1=628,2=270.000000
L 5.48396644 2.51686654 5.48706673 2.5184002 1 P 0 ;0,1=628,2=270.000000
L 5.48706673 2.5184002 5.49068356 2.51878346 1 P 0 ;0,1=628,2=270.000000
L 5.49068356 2.51878346 5.49378386 2.5184002 1 P 0 ;0,1=628,2=270.000000
L 5.49378386 2.5184002 5.49688415 2.51686654 1 P 0 ;0,1=628,2=270.000000
L 5.49688415 2.51686654 5.49946693 2.51456634 1 P 0 ;0,1=628,2=270.000000
L 5.49946693 2.51456634 5.5005 2.51188356 1 P 0 ;0,1=628,2=270.000000
L 5.5005 2.51188356 5.49946693 2.50881683 1 P 0 ;0,1=628,2=270.000000
L 5.49946693 2.50881683 5.49636762 2.50613337 1 P 0 ;0,1=628,2=270.000000
L 5.49636762 2.50613337 5.49171673 2.5045997 1 P 0 ;0,1=628,2=270.000000
L 5.49171673 2.5045997 5.4865502 2.50421644 1 P 0 ;0,1=628,2=270.000000
L 5.4865502 2.50421644 5.47983406 2.50498287 1 P 0 ;0,1=628,2=270.000000
L 5.47983406 2.50498287 5.47621624 2.50613337 1 P 0 ;0,1=628,2=270.000000
L 5.47621624 2.50613337 5.4726003 2.50804961 1 P 0 ;0,1=628,2=270.000000
L 5.4726003 2.50804961 5.47001663 2.51073307 1 P 0 ;0,1=628,2=270.000000
L 5.47001663 2.51073307 5.4695 2.51341654 1 P 0 ;0,1=628,2=270.000000
L 5.4695 2.51341654 5.47053317 2.5161 1 P 0 ;0,1=628,2=270.000000
L 5.47053317 2.5161 5.47311693 2.51801703 1 P 0 ;0,1=628,2=270.000000
L 5.722 2.175 5.678 2.175 1 P 0 
L 5.678 2.175 5.678 2.085 1 P 0 
L 5.678 2.085 5.722 2.085 1 P 0 
L 5.722 2.085 5.722 2.175 1 P 0 
L 5.80708376 2.03193327 5.80553317 2.02963307 1 P 0 ;0,1=629,2=270.000000
L 5.80553317 2.02963307 5.8045 2.0269503 1 P 0 ;0,1=629,2=270.000000
L 5.8045 2.0269503 5.8045 2.02388356 1 P 0 ;0,1=629,2=270.000000
L 5.8045 2.02388356 5.80605069 2.02043287 1 P 0 ;0,1=629,2=270.000000
L 5.80605069 2.02043287 5.80863346 2.0177501 1 P 0 ;0,1=629,2=270.000000
L 5.80863346 2.0177501 5.81173376 2.01583317 1 P 0 ;0,1=629,2=270.000000
L 5.81173376 2.01583317 5.8169002 2.01429951 1 P 0 ;0,1=629,2=270.000000
L 5.8169002 2.01429951 5.8215502 2.01391624 1 P 0 ;0,1=629,2=270.000000
L 5.8215502 2.01391624 5.8262001 2.01468337 1 P 0 ;0,1=629,2=270.000000
L 5.8262001 2.01468337 5.82930039 2.01583317 1 P 0 ;0,1=629,2=270.000000
L 5.82930039 2.01583317 5.83240069 2.01813337 1 P 0 ;0,1=629,2=270.000000
L 5.83240069 2.01813337 5.83446693 2.02081683 1 P 0 ;0,1=629,2=270.000000
L 5.83446693 2.02081683 5.8355 2.02349961 1 P 0 ;0,1=629,2=270.000000
L 5.8355 2.02349961 5.8355 2.02618307 1 P 0 ;0,1=629,2=270.000000
L 5.8355 2.02618307 5.83446693 2.02886654 1 P 0 ;0,1=629,2=270.000000
L 5.83446693 2.02886654 5.83291722 2.03116673 1 P 0 ;0,1=629,2=270.000000
L 5.83291722 2.03116673 5.83085108 2.03308366 1 P 0 ;0,1=629,2=270.000000
L 5.80966654 2.04721644 5.80656722 2.04951663 1 P 0 ;0,1=629,2=270.000000
L 5.80656722 2.04951663 5.80501663 2.0522001 1 P 0 ;0,1=629,2=270.000000
L 5.80501663 2.0522001 5.8045 2.05526683 1 P 0 ;0,1=629,2=270.000000
L 5.8045 2.05526683 5.80553317 2.0591 1 P 0 ;0,1=629,2=270.000000
L 5.80553317 2.0591 5.80811693 2.06178346 1 P 0 ;0,1=629,2=270.000000
L 5.80811693 2.06178346 5.81121624 2.06255 1 P 0 ;0,1=629,2=270.000000
L 5.81121624 2.06255 5.81431742 2.06216673 1 P 0 ;0,1=629,2=270.000000
L 5.81431742 2.06216673 5.8169002 2.06063307 1 P 0 ;0,1=629,2=270.000000
L 5.8169002 2.06063307 5.82206673 2.05296663 1 P 0 ;0,1=629,2=270.000000
L 5.82206673 2.05296663 5.82568356 2.04951663 1 P 0 ;0,1=629,2=270.000000
L 5.82568356 2.04951663 5.83085108 2.04721644 1 P 0 ;0,1=629,2=270.000000
L 5.83085108 2.04721644 5.8355 2.0464499 1 P 0 ;0,1=629,2=270.000000
L 5.8355 2.0464499 5.8355 2.06255 1 P 0 ;0,1=629,2=270.000000
L 5.82258425 2.07821644 5.81896644 2.0808999 1 P 0 ;0,1=629,2=270.000000
L 5.81896644 2.0808999 5.8169002 2.0832001 1 P 0 ;0,1=629,2=270.000000
L 5.8169002 2.0832001 5.81586713 2.08626683 1 P 0 ;0,1=629,2=270.000000
L 5.81586713 2.08626683 5.8169002 2.0889503 1 P 0 ;0,1=629,2=270.000000
L 5.8169002 2.0889503 5.81896644 2.09086654 1 P 0 ;0,1=629,2=270.000000
L 5.81896644 2.09086654 5.82206673 2.0924002 1 P 0 ;0,1=629,2=270.000000
L 5.82206673 2.0924002 5.82568356 2.09278346 1 P 0 ;0,1=629,2=270.000000
L 5.82568356 2.09278346 5.82878386 2.0924002 1 P 0 ;0,1=629,2=270.000000
L 5.82878386 2.0924002 5.83188415 2.09086654 1 P 0 ;0,1=629,2=270.000000
L 5.83188415 2.09086654 5.83446693 2.08856634 1 P 0 ;0,1=629,2=270.000000
L 5.83446693 2.08856634 5.8355 2.08588356 1 P 0 ;0,1=629,2=270.000000
L 5.8355 2.08588356 5.83446693 2.08281683 1 P 0 ;0,1=629,2=270.000000
L 5.83446693 2.08281683 5.83136762 2.08013337 1 P 0 ;0,1=629,2=270.000000
L 5.83136762 2.08013337 5.82671673 2.0785997 1 P 0 ;0,1=629,2=270.000000
L 5.82671673 2.0785997 5.8215502 2.07821644 1 P 0 ;0,1=629,2=270.000000
L 5.8215502 2.07821644 5.81483406 2.07898287 1 P 0 ;0,1=629,2=270.000000
L 5.81483406 2.07898287 5.81121624 2.08013337 1 P 0 ;0,1=629,2=270.000000
L 5.81121624 2.08013337 5.8076003 2.08204961 1 P 0 ;0,1=629,2=270.000000
L 5.8076003 2.08204961 5.80501663 2.08473307 1 P 0 ;0,1=629,2=270.000000
L 5.80501663 2.08473307 5.8045 2.08741654 1 P 0 ;0,1=629,2=270.000000
L 5.8045 2.08741654 5.80553317 2.0901 1 P 0 ;0,1=629,2=270.000000
L 5.80553317 2.0901 5.80811693 2.09201703 1 P 0 ;0,1=629,2=270.000000
L 5.80966654 2.10921644 5.80656722 2.11151663 1 P 0 ;0,1=629,2=270.000000
L 5.80656722 2.11151663 5.80501663 2.1142001 1 P 0 ;0,1=629,2=270.000000
L 5.80501663 2.1142001 5.8045 2.11726683 1 P 0 ;0,1=629,2=270.000000
L 5.8045 2.11726683 5.80553317 2.1211 1 P 0 ;0,1=629,2=270.000000
L 5.80553317 2.1211 5.80811693 2.12378346 1 P 0 ;0,1=629,2=270.000000
L 5.80811693 2.12378346 5.81121624 2.12455 1 P 0 ;0,1=629,2=270.000000
L 5.81121624 2.12455 5.81431742 2.12416673 1 P 0 ;0,1=629,2=270.000000
L 5.81431742 2.12416673 5.8169002 2.12263307 1 P 0 ;0,1=629,2=270.000000
L 5.8169002 2.12263307 5.82206673 2.11496663 1 P 0 ;0,1=629,2=270.000000
L 5.82206673 2.11496663 5.82568356 2.11151663 1 P 0 ;0,1=629,2=270.000000
L 5.82568356 2.11151663 5.83085108 2.10921644 1 P 0 ;0,1=629,2=270.000000
L 5.83085108 2.10921644 5.8355 2.1084499 1 P 0 ;0,1=629,2=270.000000
L 5.8355 2.1084499 5.8355 2.12455 1 P 0 ;0,1=629,2=270.000000
L 4.36 3.768 4.45 3.768 1 P 0 
L 4.45 3.768 4.45 3.812 1 P 0 
L 4.45 3.812 4.36 3.812 1 P 0 
L 4.36 3.812 4.36 3.768 1 P 0 
L 4.49243327 3.79791624 4.49013307 3.79946683 1 P 0 ;0,1=630,2=0.000000
L 4.49013307 3.79946683 4.4874503 3.8005 1 P 0 ;0,1=630,2=0.000000
L 4.4874503 3.8005 4.48438356 3.8005 1 P 0 ;0,1=630,2=0.000000
L 4.48438356 3.8005 4.48093287 3.79894931 1 P 0 ;0,1=630,2=0.000000
L 4.48093287 3.79894931 4.4782501 3.79636654 1 P 0 ;0,1=630,2=0.000000
L 4.4782501 3.79636654 4.47633317 3.79326624 1 P 0 ;0,1=630,2=0.000000
L 4.47633317 3.79326624 4.47479951 3.7880998 1 P 0 ;0,1=630,2=0.000000
L 4.47479951 3.7880998 4.47441624 3.7834498 1 P 0 ;0,1=630,2=0.000000
L 4.47441624 3.7834498 4.47518337 3.7787999 1 P 0 ;0,1=630,2=0.000000
L 4.47518337 3.7787999 4.47633317 3.77569961 1 P 0 ;0,1=630,2=0.000000
L 4.47633317 3.77569961 4.47863337 3.77259931 1 P 0 ;0,1=630,2=0.000000
L 4.47863337 3.77259931 4.48131683 3.77053307 1 P 0 ;0,1=630,2=0.000000
L 4.48131683 3.77053307 4.48399961 3.7695 1 P 0 ;0,1=630,2=0.000000
L 4.48399961 3.7695 4.48668307 3.7695 1 P 0 ;0,1=630,2=0.000000
L 4.48668307 3.7695 4.48936654 3.77053307 1 P 0 ;0,1=630,2=0.000000
L 4.48936654 3.77053307 4.49166673 3.77208278 1 P 0 ;0,1=630,2=0.000000
L 4.49166673 3.77208278 4.49358366 3.77414892 1 P 0 ;0,1=630,2=0.000000
L 4.51499961 3.7695 4.51768307 3.77001654 1 P 0 ;0,1=630,2=0.000000
L 4.51768307 3.77001654 4.5207498 3.77156614 1 P 0 ;0,1=630,2=0.000000
L 4.5207498 3.77156614 4.52266673 3.77414892 1 P 0 ;0,1=630,2=0.000000
L 4.52266673 3.77414892 4.52343327 3.77776673 1 P 0 ;0,1=630,2=0.000000
L 4.52343327 3.77776673 4.52266673 3.78138268 1 P 0 ;0,1=630,2=0.000000
L 4.52266673 3.78138268 4.52036654 3.78448287 1 P 0 ;0,1=630,2=0.000000
L 4.52036654 3.78448287 4.51691654 3.78603356 1 P 0 ;0,1=630,2=0.000000
L 4.51691654 3.78603356 4.51308337 3.78603356 1 P 0 ;0,1=630,2=0.000000
L 4.51308337 3.78603356 4.51078317 3.78706663 1 P 0 ;0,1=630,2=0.000000
L 4.51078317 3.78706663 4.50886614 3.78964941 1 P 0 ;0,1=630,2=0.000000
L 4.50886614 3.78964941 4.5080997 3.79326624 1 P 0 ;0,1=630,2=0.000000
L 4.5080997 3.79326624 4.5092501 3.79688307 1 P 0 ;0,1=630,2=0.000000
L 4.5092501 3.79688307 4.51193287 3.79946683 1 P 0 ;0,1=630,2=0.000000
L 4.51193287 3.79946683 4.51499961 3.8005 1 P 0 ;0,1=630,2=0.000000
L 4.51499961 3.8005 4.51806634 3.79946683 1 P 0 ;0,1=630,2=0.000000
L 4.51806634 3.79946683 4.5207498 3.79688307 1 P 0 ;0,1=630,2=0.000000
L 4.5207498 3.79688307 4.5219002 3.79326624 1 P 0 ;0,1=630,2=0.000000
L 4.5219002 3.79326624 4.52113307 3.78964941 1 P 0 ;0,1=630,2=0.000000
L 4.52113307 3.78964941 4.51921673 3.78706663 1 P 0 ;0,1=630,2=0.000000
L 4.51921673 3.78706663 4.51691654 3.78603356 1 P 0 ;0,1=630,2=0.000000
L 4.51691654 3.78603356 4.51308337 3.78603356 1 P 0 ;0,1=630,2=0.000000
L 4.51308337 3.78603356 4.50963337 3.78448287 1 P 0 ;0,1=630,2=0.000000
L 4.50963337 3.78448287 4.50733317 3.78138268 1 P 0 ;0,1=630,2=0.000000
L 4.50733317 3.78138268 4.50656663 3.77776673 1 P 0 ;0,1=630,2=0.000000
L 4.50656663 3.77776673 4.50733317 3.77414892 1 P 0 ;0,1=630,2=0.000000
L 4.50733317 3.77414892 4.5092501 3.77156614 1 P 0 ;0,1=630,2=0.000000
L 4.5092501 3.77156614 4.51231683 3.77001654 1 P 0 ;0,1=630,2=0.000000
L 4.51231683 3.77001654 4.51499961 3.7695 1 P 0 ;0,1=630,2=0.000000
L 4.53948287 3.77311585 4.54216634 3.77053307 1 P 0 ;0,1=630,2=0.000000
L 4.54216634 3.77053307 4.54523307 3.7695 1 P 0 ;0,1=630,2=0.000000
L 4.54523307 3.7695 4.5482998 3.77053307 1 P 0 ;0,1=630,2=0.000000
L 4.5482998 3.77053307 4.55098327 3.77363238 1 P 0 ;0,1=630,2=0.000000
L 4.55098327 3.77363238 4.5529002 3.77828327 1 P 0 ;0,1=630,2=0.000000
L 4.5529002 3.77828327 4.55366673 3.78293327 1 P 0 ;0,1=630,2=0.000000
L 4.55366673 3.78293327 4.55366673 3.78861634 1 P 0 ;0,1=630,2=0.000000
L 4.55366673 3.78861634 4.5529002 3.79326624 1 P 0 ;0,1=630,2=0.000000
L 4.5529002 3.79326624 4.55098327 3.7973997 1 P 0 ;0,1=630,2=0.000000
L 4.55098327 3.7973997 4.54868307 3.79946683 1 P 0 ;0,1=630,2=0.000000
L 4.54868307 3.79946683 4.54599961 3.8005 1 P 0 ;0,1=630,2=0.000000
L 4.54599961 3.8005 4.54293287 3.79946683 1 P 0 ;0,1=630,2=0.000000
L 4.54293287 3.79946683 4.54063337 3.7973997 1 P 0 ;0,1=630,2=0.000000
L 4.54063337 3.7973997 4.5390997 3.7943003 1 P 0 ;0,1=630,2=0.000000
L 4.5390997 3.7943003 4.53833317 3.79016594 1 P 0 ;0,1=630,2=0.000000
L 4.53833317 3.79016594 4.5390997 3.7865501 1 P 0 ;0,1=630,2=0.000000
L 4.5390997 3.7865501 4.54101663 3.78293327 1 P 0 ;0,1=630,2=0.000000
L 4.54101663 3.78293327 4.54331683 3.78086604 1 P 0 ;0,1=630,2=0.000000
L 4.54331683 3.78086604 4.54599961 3.78034951 1 P 0 ;0,1=630,2=0.000000
L 4.54599961 3.78034951 4.54906634 3.78138268 1 P 0 ;0,1=630,2=0.000000
L 4.54906634 3.78138268 4.55136654 3.78396634 1 P 0 ;0,1=630,2=0.000000
L 4.55136654 3.78396634 4.55366673 3.78861634 1 P 0 ;0,1=630,2=0.000000
L 5.309 2.304 5.309 2.214 1 P 0 
L 5.309 2.214 5.353 2.214 1 P 0 
L 5.353 2.214 5.353 2.304 1 P 0 
L 5.353 2.304 5.309 2.304 1 P 0 
L 5.23208376 2.23693327 5.23053317 2.23463307 1 P 0 ;0,1=631,2=270.000000
L 5.23053317 2.23463307 5.2295 2.2319503 1 P 0 ;0,1=631,2=270.000000
L 5.2295 2.2319503 5.2295 2.22888356 1 P 0 ;0,1=631,2=270.000000
L 5.2295 2.22888356 5.23105069 2.22543287 1 P 0 ;0,1=631,2=270.000000
L 5.23105069 2.22543287 5.23363346 2.2227501 1 P 0 ;0,1=631,2=270.000000
L 5.23363346 2.2227501 5.23673376 2.22083317 1 P 0 ;0,1=631,2=270.000000
L 5.23673376 2.22083317 5.2419002 2.21929951 1 P 0 ;0,1=631,2=270.000000
L 5.2419002 2.21929951 5.2465502 2.21891624 1 P 0 ;0,1=631,2=270.000000
L 5.2465502 2.21891624 5.2512001 2.21968337 1 P 0 ;0,1=631,2=270.000000
L 5.2512001 2.21968337 5.25430039 2.22083317 1 P 0 ;0,1=631,2=270.000000
L 5.25430039 2.22083317 5.25740069 2.22313337 1 P 0 ;0,1=631,2=270.000000
L 5.25740069 2.22313337 5.25946693 2.22581683 1 P 0 ;0,1=631,2=270.000000
L 5.25946693 2.22581683 5.2605 2.22849961 1 P 0 ;0,1=631,2=270.000000
L 5.2605 2.22849961 5.2605 2.23118307 1 P 0 ;0,1=631,2=270.000000
L 5.2605 2.23118307 5.25946693 2.23386654 1 P 0 ;0,1=631,2=270.000000
L 5.25946693 2.23386654 5.25791722 2.23616673 1 P 0 ;0,1=631,2=270.000000
L 5.25791722 2.23616673 5.25585108 2.23808366 1 P 0 ;0,1=631,2=270.000000
L 5.23466654 2.25221644 5.23156722 2.25451663 1 P 0 ;0,1=631,2=270.000000
L 5.23156722 2.25451663 5.23001663 2.2572001 1 P 0 ;0,1=631,2=270.000000
L 5.23001663 2.2572001 5.2295 2.26026683 1 P 0 ;0,1=631,2=270.000000
L 5.2295 2.26026683 5.23053317 2.2641 1 P 0 ;0,1=631,2=270.000000
L 5.23053317 2.2641 5.23311693 2.26678346 1 P 0 ;0,1=631,2=270.000000
L 5.23311693 2.26678346 5.23621624 2.26755 1 P 0 ;0,1=631,2=270.000000
L 5.23621624 2.26755 5.23931742 2.26716673 1 P 0 ;0,1=631,2=270.000000
L 5.23931742 2.26716673 5.2419002 2.26563307 1 P 0 ;0,1=631,2=270.000000
L 5.2419002 2.26563307 5.24706673 2.25796663 1 P 0 ;0,1=631,2=270.000000
L 5.24706673 2.25796663 5.25068356 2.25451663 1 P 0 ;0,1=631,2=270.000000
L 5.25068356 2.25451663 5.25585108 2.25221644 1 P 0 ;0,1=631,2=270.000000
L 5.25585108 2.25221644 5.2605 2.2514499 1 P 0 ;0,1=631,2=270.000000
L 5.2605 2.2514499 5.2605 2.26755 1 P 0 ;0,1=631,2=270.000000
L 5.25585108 2.28206663 5.25843386 2.28436614 1 P 0 ;0,1=631,2=270.000000
L 5.25843386 2.28436614 5.25998346 2.28704961 1 P 0 ;0,1=631,2=270.000000
L 5.25998346 2.28704961 5.2605 2.29049961 1 P 0 ;0,1=631,2=270.000000
L 5.2605 2.29049961 5.25946693 2.2939503 1 P 0 ;0,1=631,2=270.000000
L 5.25946693 2.2939503 5.25740069 2.29663307 1 P 0 ;0,1=631,2=270.000000
L 5.25740069 2.29663307 5.25378386 2.29855 1 P 0 ;0,1=631,2=270.000000
L 5.25378386 2.29855 5.24965049 2.29893327 1 P 0 ;0,1=631,2=270.000000
L 5.24965049 2.29893327 5.24551713 2.29816673 1 P 0 ;0,1=631,2=270.000000
L 5.24551713 2.29816673 5.24293337 2.2962498 1 P 0 ;0,1=631,2=270.000000
L 5.24293337 2.2962498 5.24086713 2.29356634 1 P 0 ;0,1=631,2=270.000000
L 5.24086713 2.29356634 5.24035059 2.29088356 1 P 0 ;0,1=631,2=270.000000
L 5.24035059 2.29088356 5.24086713 2.2882001 1 P 0 ;0,1=631,2=270.000000
L 5.24086713 2.2882001 5.24293337 2.2847501 1 P 0 ;0,1=631,2=270.000000
L 5.24293337 2.2847501 5.2295 2.2858999 1 P 0 ;0,1=631,2=270.000000
L 5.2295 2.2858999 5.2295 2.2962498 1 P 0 ;0,1=631,2=270.000000
L 5.25585108 2.31306663 5.25843386 2.31536614 1 P 0 ;0,1=631,2=270.000000
L 5.25843386 2.31536614 5.25998346 2.31804961 1 P 0 ;0,1=631,2=270.000000
L 5.25998346 2.31804961 5.2605 2.32149961 1 P 0 ;0,1=631,2=270.000000
L 5.2605 2.32149961 5.25946693 2.3249503 1 P 0 ;0,1=631,2=270.000000
L 5.25946693 2.3249503 5.25740069 2.32763307 1 P 0 ;0,1=631,2=270.000000
L 5.25740069 2.32763307 5.25378386 2.32955 1 P 0 ;0,1=631,2=270.000000
L 5.25378386 2.32955 5.24965049 2.32993327 1 P 0 ;0,1=631,2=270.000000
L 5.24965049 2.32993327 5.24551713 2.32916673 1 P 0 ;0,1=631,2=270.000000
L 5.24551713 2.32916673 5.24293337 2.3272498 1 P 0 ;0,1=631,2=270.000000
L 5.24293337 2.3272498 5.24086713 2.32456634 1 P 0 ;0,1=631,2=270.000000
L 5.24086713 2.32456634 5.24035059 2.32188356 1 P 0 ;0,1=631,2=270.000000
L 5.24035059 2.32188356 5.24086713 2.3192001 1 P 0 ;0,1=631,2=270.000000
L 5.24086713 2.3192001 5.24293337 2.3157501 1 P 0 ;0,1=631,2=270.000000
L 5.24293337 2.3157501 5.2295 2.3168999 1 P 0 ;0,1=631,2=270.000000
L 5.2295 2.3168999 5.2295 2.3272498 1 P 0 ;0,1=631,2=270.000000
L 5.472 2.155 5.428 2.155 1 P 0 
L 5.428 2.155 5.428 2.065 1 P 0 
L 5.428 2.065 5.472 2.065 1 P 0 
L 5.472 2.065 5.472 2.155 1 P 0 
L 5.30708376 2.05193327 5.30553317 2.04963307 1 P 0 ;0,1=632,2=270.000000
L 5.30553317 2.04963307 5.3045 2.0469503 1 P 0 ;0,1=632,2=270.000000
L 5.3045 2.0469503 5.3045 2.04388356 1 P 0 ;0,1=632,2=270.000000
L 5.3045 2.04388356 5.30605069 2.04043287 1 P 0 ;0,1=632,2=270.000000
L 5.30605069 2.04043287 5.30863346 2.0377501 1 P 0 ;0,1=632,2=270.000000
L 5.30863346 2.0377501 5.31173376 2.03583317 1 P 0 ;0,1=632,2=270.000000
L 5.31173376 2.03583317 5.3169002 2.03429951 1 P 0 ;0,1=632,2=270.000000
L 5.3169002 2.03429951 5.3215502 2.03391624 1 P 0 ;0,1=632,2=270.000000
L 5.3215502 2.03391624 5.3262001 2.03468337 1 P 0 ;0,1=632,2=270.000000
L 5.3262001 2.03468337 5.32930039 2.03583317 1 P 0 ;0,1=632,2=270.000000
L 5.32930039 2.03583317 5.33240069 2.03813337 1 P 0 ;0,1=632,2=270.000000
L 5.33240069 2.03813337 5.33446693 2.04081683 1 P 0 ;0,1=632,2=270.000000
L 5.33446693 2.04081683 5.3355 2.04349961 1 P 0 ;0,1=632,2=270.000000
L 5.3355 2.04349961 5.3355 2.04618307 1 P 0 ;0,1=632,2=270.000000
L 5.3355 2.04618307 5.33446693 2.04886654 1 P 0 ;0,1=632,2=270.000000
L 5.33446693 2.04886654 5.33291722 2.05116673 1 P 0 ;0,1=632,2=270.000000
L 5.33291722 2.05116673 5.33085108 2.05308366 1 P 0 ;0,1=632,2=270.000000
L 5.30966654 2.06721644 5.30656722 2.06951663 1 P 0 ;0,1=632,2=270.000000
L 5.30656722 2.06951663 5.30501663 2.0722001 1 P 0 ;0,1=632,2=270.000000
L 5.30501663 2.0722001 5.3045 2.07526683 1 P 0 ;0,1=632,2=270.000000
L 5.3045 2.07526683 5.30553317 2.0791 1 P 0 ;0,1=632,2=270.000000
L 5.30553317 2.0791 5.30811693 2.08178346 1 P 0 ;0,1=632,2=270.000000
L 5.30811693 2.08178346 5.31121624 2.08255 1 P 0 ;0,1=632,2=270.000000
L 5.31121624 2.08255 5.31431742 2.08216673 1 P 0 ;0,1=632,2=270.000000
L 5.31431742 2.08216673 5.3169002 2.08063307 1 P 0 ;0,1=632,2=270.000000
L 5.3169002 2.08063307 5.32206673 2.07296663 1 P 0 ;0,1=632,2=270.000000
L 5.32206673 2.07296663 5.32568356 2.06951663 1 P 0 ;0,1=632,2=270.000000
L 5.32568356 2.06951663 5.33085108 2.06721644 1 P 0 ;0,1=632,2=270.000000
L 5.33085108 2.06721644 5.3355 2.0664499 1 P 0 ;0,1=632,2=270.000000
L 5.3355 2.0664499 5.3355 2.08255 1 P 0 ;0,1=632,2=270.000000
L 5.32258425 2.09821644 5.31896644 2.1008999 1 P 0 ;0,1=632,2=270.000000
L 5.31896644 2.1008999 5.3169002 2.1032001 1 P 0 ;0,1=632,2=270.000000
L 5.3169002 2.1032001 5.31586713 2.10626683 1 P 0 ;0,1=632,2=270.000000
L 5.31586713 2.10626683 5.3169002 2.1089503 1 P 0 ;0,1=632,2=270.000000
L 5.3169002 2.1089503 5.31896644 2.11086654 1 P 0 ;0,1=632,2=270.000000
L 5.31896644 2.11086654 5.32206673 2.1124002 1 P 0 ;0,1=632,2=270.000000
L 5.32206673 2.1124002 5.32568356 2.11278346 1 P 0 ;0,1=632,2=270.000000
L 5.32568356 2.11278346 5.32878386 2.1124002 1 P 0 ;0,1=632,2=270.000000
L 5.32878386 2.1124002 5.33188415 2.11086654 1 P 0 ;0,1=632,2=270.000000
L 5.33188415 2.11086654 5.33446693 2.10856634 1 P 0 ;0,1=632,2=270.000000
L 5.33446693 2.10856634 5.3355 2.10588356 1 P 0 ;0,1=632,2=270.000000
L 5.3355 2.10588356 5.33446693 2.10281683 1 P 0 ;0,1=632,2=270.000000
L 5.33446693 2.10281683 5.33136762 2.10013337 1 P 0 ;0,1=632,2=270.000000
L 5.33136762 2.10013337 5.32671673 2.0985997 1 P 0 ;0,1=632,2=270.000000
L 5.32671673 2.0985997 5.3215502 2.09821644 1 P 0 ;0,1=632,2=270.000000
L 5.3215502 2.09821644 5.31483406 2.09898287 1 P 0 ;0,1=632,2=270.000000
L 5.31483406 2.09898287 5.31121624 2.10013337 1 P 0 ;0,1=632,2=270.000000
L 5.31121624 2.10013337 5.3076003 2.10204961 1 P 0 ;0,1=632,2=270.000000
L 5.3076003 2.10204961 5.30501663 2.10473307 1 P 0 ;0,1=632,2=270.000000
L 5.30501663 2.10473307 5.3045 2.10741654 1 P 0 ;0,1=632,2=270.000000
L 5.3045 2.10741654 5.30553317 2.1101 1 P 0 ;0,1=632,2=270.000000
L 5.30553317 2.1101 5.30811693 2.11201703 1 P 0 ;0,1=632,2=270.000000
L 5.3355 2.13649961 5.3045 2.13649961 1 P 0 ;0,1=632,2=270.000000
L 5.3045 2.13649961 5.3106997 2.1318999 1 P 0 ;0,1=632,2=270.000000
L 5.3355 2.1318999 5.3355 2.14109931 1 P 0 ;0,1=632,2=270.000000
L 6.445 1.157 6.355 1.157 1 P 0 
L 6.355 1.157 6.355 1.113 1 P 0 
L 6.355 1.113 6.445 1.113 1 P 0 
L 6.445 1.113 6.445 1.157 1 P 0 
L 6.46693327 1.17791624 6.46463307 1.17946683 1 P 0 ;0,1=633,2=0.000000
L 6.46463307 1.17946683 6.4619503 1.1805 1 P 0 ;0,1=633,2=0.000000
L 6.4619503 1.1805 6.45888356 1.1805 1 P 0 ;0,1=633,2=0.000000
L 6.45888356 1.1805 6.45543287 1.17894931 1 P 0 ;0,1=633,2=0.000000
L 6.45543287 1.17894931 6.4527501 1.17636654 1 P 0 ;0,1=633,2=0.000000
L 6.4527501 1.17636654 6.45083317 1.17326624 1 P 0 ;0,1=633,2=0.000000
L 6.45083317 1.17326624 6.44929951 1.1680998 1 P 0 ;0,1=633,2=0.000000
L 6.44929951 1.1680998 6.44891624 1.1634498 1 P 0 ;0,1=633,2=0.000000
L 6.44891624 1.1634498 6.44968337 1.1587999 1 P 0 ;0,1=633,2=0.000000
L 6.44968337 1.1587999 6.45083317 1.15569961 1 P 0 ;0,1=633,2=0.000000
L 6.45083317 1.15569961 6.45313337 1.15259931 1 P 0 ;0,1=633,2=0.000000
L 6.45313337 1.15259931 6.45581683 1.15053307 1 P 0 ;0,1=633,2=0.000000
L 6.45581683 1.15053307 6.45849961 1.1495 1 P 0 ;0,1=633,2=0.000000
L 6.45849961 1.1495 6.46118307 1.1495 1 P 0 ;0,1=633,2=0.000000
L 6.46118307 1.1495 6.46386654 1.15053307 1 P 0 ;0,1=633,2=0.000000
L 6.46386654 1.15053307 6.46616673 1.15208278 1 P 0 ;0,1=633,2=0.000000
L 6.46616673 1.15208278 6.46808366 1.15414892 1 P 0 ;0,1=633,2=0.000000
L 6.48106663 1.15569961 6.48336614 1.15208278 1 P 0 ;0,1=633,2=0.000000
L 6.48336614 1.15208278 6.48643287 1.15001654 1 P 0 ;0,1=633,2=0.000000
L 6.48643287 1.15001654 6.48988356 1.1495 1 P 0 ;0,1=633,2=0.000000
L 6.48988356 1.1495 6.4929503 1.15001654 1 P 0 ;0,1=633,2=0.000000
L 6.4929503 1.15001654 6.49601703 1.15259931 1 P 0 ;0,1=633,2=0.000000
L 6.49601703 1.15259931 6.49793327 1.15569961 1 P 0 ;0,1=633,2=0.000000
L 6.49793327 1.15569961 6.49831654 1.1587999 1 P 0 ;0,1=633,2=0.000000
L 6.49831654 1.1587999 6.49755 1.16241575 1 P 0 ;0,1=633,2=0.000000
L 6.49755 1.16241575 6.49486654 1.16499951 1 P 0 ;0,1=633,2=0.000000
L 6.49486654 1.16499951 6.49218307 1.16603356 1 P 0 ;0,1=633,2=0.000000
L 6.49218307 1.16603356 6.48873307 1.16603356 1 P 0 ;0,1=633,2=0.000000
L 6.49218307 1.16603356 6.49448327 1.16758317 1 P 0 ;0,1=633,2=0.000000
L 6.49448327 1.16758317 6.4964002 1.17016594 1 P 0 ;0,1=633,2=0.000000
L 6.4964002 1.17016594 6.49716673 1.17326624 1 P 0 ;0,1=633,2=0.000000
L 6.49716673 1.17326624 6.4964002 1.17636654 1 P 0 ;0,1=633,2=0.000000
L 6.4964002 1.17636654 6.49448327 1.17894931 1 P 0 ;0,1=633,2=0.000000
L 6.49448327 1.17894931 6.49103327 1.1805 1 P 0 ;0,1=633,2=0.000000
L 6.49103327 1.1805 6.48758337 1.17998337 1 P 0 ;0,1=633,2=0.000000
L 6.48758337 1.17998337 6.48413337 1.17791624 1 P 0 ;0,1=633,2=0.000000
L 6.52049961 1.1805 6.51743287 1.17946683 1 P 0 ;0,1=633,2=0.000000
L 6.51743287 1.17946683 6.51513337 1.17688307 1 P 0 ;0,1=633,2=0.000000
L 6.51513337 1.17688307 6.5135997 1.17378376 1 P 0 ;0,1=633,2=0.000000
L 6.5135997 1.17378376 6.5124499 1.16964941 1 P 0 ;0,1=633,2=0.000000
L 6.5124499 1.16964941 6.51206663 1.16499951 1 P 0 ;0,1=633,2=0.000000
L 6.51206663 1.16499951 6.5124499 1.16034951 1 P 0 ;0,1=633,2=0.000000
L 6.5124499 1.16034951 6.5135997 1.15621614 1 P 0 ;0,1=633,2=0.000000
L 6.5135997 1.15621614 6.51513337 1.15311585 1 P 0 ;0,1=633,2=0.000000
L 6.51513337 1.15311585 6.51743287 1.15053307 1 P 0 ;0,1=633,2=0.000000
L 6.51743287 1.15053307 6.52049961 1.1495 1 P 0 ;0,1=633,2=0.000000
L 6.52049961 1.1495 6.52356634 1.15053307 1 P 0 ;0,1=633,2=0.000000
L 6.52356634 1.15053307 6.52586654 1.15311585 1 P 0 ;0,1=633,2=0.000000
L 6.52586654 1.15311585 6.5274002 1.15621614 1 P 0 ;0,1=633,2=0.000000
L 6.5274002 1.15621614 6.52855 1.16034951 1 P 0 ;0,1=633,2=0.000000
L 6.52855 1.16034951 6.52893327 1.16499951 1 P 0 ;0,1=633,2=0.000000
L 6.52893327 1.16499951 6.52855 1.16964941 1 P 0 ;0,1=633,2=0.000000
L 6.52855 1.16964941 6.5274002 1.17378376 1 P 0 ;0,1=633,2=0.000000
L 6.5274002 1.17378376 6.52586654 1.17688307 1 P 0 ;0,1=633,2=0.000000
L 6.52586654 1.17688307 6.52356634 1.17946683 1 P 0 ;0,1=633,2=0.000000
L 6.52356634 1.17946683 6.52049961 1.1805 1 P 0 ;0,1=633,2=0.000000
L 6.54306663 1.15414892 6.54536614 1.15156614 1 P 0 ;0,1=633,2=0.000000
L 6.54536614 1.15156614 6.54804961 1.15001654 1 P 0 ;0,1=633,2=0.000000
L 6.54804961 1.15001654 6.55149961 1.1495 1 P 0 ;0,1=633,2=0.000000
L 6.55149961 1.1495 6.5549503 1.15053307 1 P 0 ;0,1=633,2=0.000000
L 6.5549503 1.15053307 6.55763307 1.15259931 1 P 0 ;0,1=633,2=0.000000
L 6.55763307 1.15259931 6.55955 1.15621614 1 P 0 ;0,1=633,2=0.000000
L 6.55955 1.15621614 6.55993327 1.16034951 1 P 0 ;0,1=633,2=0.000000
L 6.55993327 1.16034951 6.55916673 1.16448287 1 P 0 ;0,1=633,2=0.000000
L 6.55916673 1.16448287 6.5572498 1.16706663 1 P 0 ;0,1=633,2=0.000000
L 6.5572498 1.16706663 6.55456634 1.16913287 1 P 0 ;0,1=633,2=0.000000
L 6.55456634 1.16913287 6.55188356 1.16964941 1 P 0 ;0,1=633,2=0.000000
L 6.55188356 1.16964941 6.5492001 1.16913287 1 P 0 ;0,1=633,2=0.000000
L 6.5492001 1.16913287 6.5457501 1.16706663 1 P 0 ;0,1=633,2=0.000000
L 6.5457501 1.16706663 6.5468999 1.1805 1 P 0 ;0,1=633,2=0.000000
L 6.5468999 1.1805 6.5572498 1.1805 1 P 0 ;0,1=633,2=0.000000
L 6.311 1.94673996 6.311 2.03673996 1 P 0 
L 6.311 2.03673996 6.267 2.03673996 1 P 0 
L 6.267 2.03673996 6.267 1.94673996 1 P 0 
L 6.267 1.94673996 6.311 1.94673996 1 P 0 
L 6.15208376 2.01243327 6.15053317 2.01013307 1 P 0 ;0,1=634,2=270.000000
L 6.15053317 2.01013307 6.1495 2.0074503 1 P 0 ;0,1=634,2=270.000000
L 6.1495 2.0074503 6.1495 2.00438356 1 P 0 ;0,1=634,2=270.000000
L 6.1495 2.00438356 6.15105069 2.00093287 1 P 0 ;0,1=634,2=270.000000
L 6.15105069 2.00093287 6.15363346 1.9982501 1 P 0 ;0,1=634,2=270.000000
L 6.15363346 1.9982501 6.15673376 1.99633317 1 P 0 ;0,1=634,2=270.000000
L 6.15673376 1.99633317 6.1619002 1.99479951 1 P 0 ;0,1=634,2=270.000000
L 6.1619002 1.99479951 6.1665502 1.99441624 1 P 0 ;0,1=634,2=270.000000
L 6.1665502 1.99441624 6.1712001 1.99518337 1 P 0 ;0,1=634,2=270.000000
L 6.1712001 1.99518337 6.17430039 1.99633317 1 P 0 ;0,1=634,2=270.000000
L 6.17430039 1.99633317 6.17740069 1.99863337 1 P 0 ;0,1=634,2=270.000000
L 6.17740069 1.99863337 6.17946693 2.00131683 1 P 0 ;0,1=634,2=270.000000
L 6.17946693 2.00131683 6.1805 2.00399961 1 P 0 ;0,1=634,2=270.000000
L 6.1805 2.00399961 6.1805 2.00668307 1 P 0 ;0,1=634,2=270.000000
L 6.1805 2.00668307 6.17946693 2.00936654 1 P 0 ;0,1=634,2=270.000000
L 6.17946693 2.00936654 6.17791722 2.01166673 1 P 0 ;0,1=634,2=270.000000
L 6.17791722 2.01166673 6.17585108 2.01358366 1 P 0 ;0,1=634,2=270.000000
L 6.16758425 2.02771644 6.16396644 2.0303999 1 P 0 ;0,1=634,2=270.000000
L 6.16396644 2.0303999 6.1619002 2.0327001 1 P 0 ;0,1=634,2=270.000000
L 6.1619002 2.0327001 6.16086713 2.03576683 1 P 0 ;0,1=634,2=270.000000
L 6.16086713 2.03576683 6.1619002 2.0384503 1 P 0 ;0,1=634,2=270.000000
L 6.1619002 2.0384503 6.16396644 2.04036654 1 P 0 ;0,1=634,2=270.000000
L 6.16396644 2.04036654 6.16706673 2.0419002 1 P 0 ;0,1=634,2=270.000000
L 6.16706673 2.0419002 6.17068356 2.04228346 1 P 0 ;0,1=634,2=270.000000
L 6.17068356 2.04228346 6.17378386 2.0419002 1 P 0 ;0,1=634,2=270.000000
L 6.17378386 2.0419002 6.17688415 2.04036654 1 P 0 ;0,1=634,2=270.000000
L 6.17688415 2.04036654 6.17946693 2.03806634 1 P 0 ;0,1=634,2=270.000000
L 6.17946693 2.03806634 6.1805 2.03538356 1 P 0 ;0,1=634,2=270.000000
L 6.1805 2.03538356 6.17946693 2.03231683 1 P 0 ;0,1=634,2=270.000000
L 6.17946693 2.03231683 6.17636762 2.02963337 1 P 0 ;0,1=634,2=270.000000
L 6.17636762 2.02963337 6.17171673 2.0280997 1 P 0 ;0,1=634,2=270.000000
L 6.17171673 2.0280997 6.1665502 2.02771644 1 P 0 ;0,1=634,2=270.000000
L 6.1665502 2.02771644 6.15983406 2.02848287 1 P 0 ;0,1=634,2=270.000000
L 6.15983406 2.02848287 6.15621624 2.02963337 1 P 0 ;0,1=634,2=270.000000
L 6.15621624 2.02963337 6.1526003 2.03154961 1 P 0 ;0,1=634,2=270.000000
L 6.1526003 2.03154961 6.15001663 2.03423307 1 P 0 ;0,1=634,2=270.000000
L 6.15001663 2.03423307 6.1495 2.03691654 1 P 0 ;0,1=634,2=270.000000
L 6.1495 2.03691654 6.15053317 2.0396 1 P 0 ;0,1=634,2=270.000000
L 6.15053317 2.0396 6.15311693 2.04151703 1 P 0 ;0,1=634,2=270.000000
L 6.17430039 2.05756663 6.17791722 2.05986614 1 P 0 ;0,1=634,2=270.000000
L 6.17791722 2.05986614 6.17998346 2.06293287 1 P 0 ;0,1=634,2=270.000000
L 6.17998346 2.06293287 6.1805 2.06638356 1 P 0 ;0,1=634,2=270.000000
L 6.1805 2.06638356 6.17998346 2.0694503 1 P 0 ;0,1=634,2=270.000000
L 6.17998346 2.0694503 6.17740069 2.07251703 1 P 0 ;0,1=634,2=270.000000
L 6.17740069 2.07251703 6.17430039 2.07443327 1 P 0 ;0,1=634,2=270.000000
L 6.17430039 2.07443327 6.1712001 2.07481654 1 P 0 ;0,1=634,2=270.000000
L 6.1712001 2.07481654 6.16758425 2.07405 1 P 0 ;0,1=634,2=270.000000
L 6.16758425 2.07405 6.16500049 2.07136654 1 P 0 ;0,1=634,2=270.000000
L 6.16500049 2.07136654 6.16396644 2.06868307 1 P 0 ;0,1=634,2=270.000000
L 6.16396644 2.06868307 6.16396644 2.06523307 1 P 0 ;0,1=634,2=270.000000
L 6.16396644 2.06868307 6.16241683 2.07098327 1 P 0 ;0,1=634,2=270.000000
L 6.16241683 2.07098327 6.15983406 2.0729002 1 P 0 ;0,1=634,2=270.000000
L 6.15983406 2.0729002 6.15673376 2.07366673 1 P 0 ;0,1=634,2=270.000000
L 6.15673376 2.07366673 6.15363346 2.0729002 1 P 0 ;0,1=634,2=270.000000
L 6.15363346 2.0729002 6.15105069 2.07098327 1 P 0 ;0,1=634,2=270.000000
L 6.15105069 2.07098327 6.1495 2.06753327 1 P 0 ;0,1=634,2=270.000000
L 6.1495 2.06753327 6.15001663 2.06408337 1 P 0 ;0,1=634,2=270.000000
L 6.15001663 2.06408337 6.15208376 2.06063337 1 P 0 ;0,1=634,2=270.000000
L 6.163 2.344 6.119 2.344 1 P 0 
L 6.119 2.344 6.119 2.254 1 P 0 
L 6.119 2.254 6.163 2.254 1 P 0 
L 6.163 2.254 6.163 2.344 1 P 0 
L 6.13708376 2.40743327 6.13553317 2.40513307 1 P 0 ;0,1=635,2=270.000000
L 6.13553317 2.40513307 6.1345 2.4024503 1 P 0 ;0,1=635,2=270.000000
L 6.1345 2.4024503 6.1345 2.39938356 1 P 0 ;0,1=635,2=270.000000
L 6.1345 2.39938356 6.13605069 2.39593287 1 P 0 ;0,1=635,2=270.000000
L 6.13605069 2.39593287 6.13863346 2.3932501 1 P 0 ;0,1=635,2=270.000000
L 6.13863346 2.3932501 6.14173376 2.39133317 1 P 0 ;0,1=635,2=270.000000
L 6.14173376 2.39133317 6.1469002 2.38979951 1 P 0 ;0,1=635,2=270.000000
L 6.1469002 2.38979951 6.1515502 2.38941624 1 P 0 ;0,1=635,2=270.000000
L 6.1515502 2.38941624 6.1562001 2.39018337 1 P 0 ;0,1=635,2=270.000000
L 6.1562001 2.39018337 6.15930039 2.39133317 1 P 0 ;0,1=635,2=270.000000
L 6.15930039 2.39133317 6.16240069 2.39363337 1 P 0 ;0,1=635,2=270.000000
L 6.16240069 2.39363337 6.16446693 2.39631683 1 P 0 ;0,1=635,2=270.000000
L 6.16446693 2.39631683 6.1655 2.39899961 1 P 0 ;0,1=635,2=270.000000
L 6.1655 2.39899961 6.1655 2.40168307 1 P 0 ;0,1=635,2=270.000000
L 6.1655 2.40168307 6.16446693 2.40436654 1 P 0 ;0,1=635,2=270.000000
L 6.16446693 2.40436654 6.16291722 2.40666673 1 P 0 ;0,1=635,2=270.000000
L 6.16291722 2.40666673 6.16085108 2.40858366 1 P 0 ;0,1=635,2=270.000000
L 6.1655 2.4346 6.1345 2.4346 1 P 0 ;0,1=635,2=270.000000
L 6.1345 2.4346 6.15671673 2.42041624 1 P 0 ;0,1=635,2=270.000000
L 6.15671673 2.42041624 6.15671673 2.43958366 1 P 0 ;0,1=635,2=270.000000
L 6.1345 2.46099961 6.13553317 2.45793287 1 P 0 ;0,1=635,2=270.000000
L 6.13553317 2.45793287 6.13811693 2.45563337 1 P 0 ;0,1=635,2=270.000000
L 6.13811693 2.45563337 6.14121624 2.4540997 1 P 0 ;0,1=635,2=270.000000
L 6.14121624 2.4540997 6.14535059 2.4529499 1 P 0 ;0,1=635,2=270.000000
L 6.14535059 2.4529499 6.15000049 2.45256663 1 P 0 ;0,1=635,2=270.000000
L 6.15000049 2.45256663 6.15465049 2.4529499 1 P 0 ;0,1=635,2=270.000000
L 6.15465049 2.4529499 6.15878386 2.4540997 1 P 0 ;0,1=635,2=270.000000
L 6.15878386 2.4540997 6.16188415 2.45563337 1 P 0 ;0,1=635,2=270.000000
L 6.16188415 2.45563337 6.16446693 2.45793287 1 P 0 ;0,1=635,2=270.000000
L 6.16446693 2.45793287 6.1655 2.46099961 1 P 0 ;0,1=635,2=270.000000
L 6.1655 2.46099961 6.16446693 2.46406634 1 P 0 ;0,1=635,2=270.000000
L 6.16446693 2.46406634 6.16188415 2.46636654 1 P 0 ;0,1=635,2=270.000000
L 6.16188415 2.46636654 6.15878386 2.4679002 1 P 0 ;0,1=635,2=270.000000
L 6.15878386 2.4679002 6.15465049 2.46905 1 P 0 ;0,1=635,2=270.000000
L 6.15465049 2.46905 6.15000049 2.46943327 1 P 0 ;0,1=635,2=270.000000
L 6.15000049 2.46943327 6.14535059 2.46905 1 P 0 ;0,1=635,2=270.000000
L 6.14535059 2.46905 6.14121624 2.4679002 1 P 0 ;0,1=635,2=270.000000
L 6.14121624 2.4679002 6.13811693 2.46636654 1 P 0 ;0,1=635,2=270.000000
L 6.13811693 2.46636654 6.13553317 2.46406634 1 P 0 ;0,1=635,2=270.000000
L 6.13553317 2.46406634 6.1345 2.46099961 1 P 0 ;0,1=635,2=270.000000
L 6.005 2.203 6.095 2.203 1 P 0 
L 6.095 2.203 6.095 2.247 1 P 0 
L 6.095 2.247 6.005 2.247 1 P 0 
L 6.005 2.247 6.005 2.203 1 P 0 
L 6.08693327 2.15291624 6.08463307 2.15446683 1 P 0 ;0,1=636,2=0.000000
L 6.08463307 2.15446683 6.0819503 2.1555 1 P 0 ;0,1=636,2=0.000000
L 6.0819503 2.1555 6.07888356 2.1555 1 P 0 ;0,1=636,2=0.000000
L 6.07888356 2.1555 6.07543287 2.15394931 1 P 0 ;0,1=636,2=0.000000
L 6.07543287 2.15394931 6.0727501 2.15136654 1 P 0 ;0,1=636,2=0.000000
L 6.0727501 2.15136654 6.07083317 2.14826624 1 P 0 ;0,1=636,2=0.000000
L 6.07083317 2.14826624 6.06929951 2.1430998 1 P 0 ;0,1=636,2=0.000000
L 6.06929951 2.1430998 6.06891624 2.1384498 1 P 0 ;0,1=636,2=0.000000
L 6.06891624 2.1384498 6.06968337 2.1337999 1 P 0 ;0,1=636,2=0.000000
L 6.06968337 2.1337999 6.07083317 2.13069961 1 P 0 ;0,1=636,2=0.000000
L 6.07083317 2.13069961 6.07313337 2.12759931 1 P 0 ;0,1=636,2=0.000000
L 6.07313337 2.12759931 6.07581683 2.12553307 1 P 0 ;0,1=636,2=0.000000
L 6.07581683 2.12553307 6.07849961 2.1245 1 P 0 ;0,1=636,2=0.000000
L 6.07849961 2.1245 6.08118307 2.1245 1 P 0 ;0,1=636,2=0.000000
L 6.08118307 2.1245 6.08386654 2.12553307 1 P 0 ;0,1=636,2=0.000000
L 6.08386654 2.12553307 6.08616673 2.12708278 1 P 0 ;0,1=636,2=0.000000
L 6.08616673 2.12708278 6.08808366 2.12914892 1 P 0 ;0,1=636,2=0.000000
L 6.10221644 2.15033346 6.10451663 2.15343278 1 P 0 ;0,1=636,2=0.000000
L 6.10451663 2.15343278 6.1072001 2.15498337 1 P 0 ;0,1=636,2=0.000000
L 6.1072001 2.15498337 6.11026683 2.1555 1 P 0 ;0,1=636,2=0.000000
L 6.11026683 2.1555 6.1141 2.15446683 1 P 0 ;0,1=636,2=0.000000
L 6.1141 2.15446683 6.11678346 2.15188307 1 P 0 ;0,1=636,2=0.000000
L 6.11678346 2.15188307 6.11755 2.14878376 1 P 0 ;0,1=636,2=0.000000
L 6.11755 2.14878376 6.11716673 2.14568258 1 P 0 ;0,1=636,2=0.000000
L 6.11716673 2.14568258 6.11563307 2.1430998 1 P 0 ;0,1=636,2=0.000000
L 6.11563307 2.1430998 6.10796663 2.13793327 1 P 0 ;0,1=636,2=0.000000
L 6.10796663 2.13793327 6.10451663 2.13431644 1 P 0 ;0,1=636,2=0.000000
L 6.10451663 2.13431644 6.10221644 2.12914892 1 P 0 ;0,1=636,2=0.000000
L 6.10221644 2.12914892 6.1014499 2.1245 1 P 0 ;0,1=636,2=0.000000
L 6.1014499 2.1245 6.11755 2.1245 1 P 0 ;0,1=636,2=0.000000
L 6.13973307 2.1245 6.14049961 2.13121614 1 P 0 ;0,1=636,2=0.000000
L 6.14049961 2.13121614 6.1416501 2.13689921 1 P 0 ;0,1=636,2=0.000000
L 6.1416501 2.13689921 6.14318307 2.14206663 1 P 0 ;0,1=636,2=0.000000
L 6.14318307 2.14206663 6.1451 2.1477497 1 P 0 ;0,1=636,2=0.000000
L 6.1451 2.1477497 6.14816673 2.1555 1 P 0 ;0,1=636,2=0.000000
L 6.14816673 2.1555 6.13283317 2.1555 1 P 0 ;0,1=636,2=0.000000
L 6.1761 2.1245 6.1761 2.1555 1 P 0 ;0,1=636,2=0.000000
L 6.1761 2.1555 6.16191624 2.13328327 1 P 0 ;0,1=636,2=0.000000
L 6.16191624 2.13328327 6.18108366 2.13328327 1 P 0 ;0,1=636,2=0.000000
L 6.005 2.248 6.095 2.248 1 P 0 
L 6.095 2.248 6.095 2.292 1 P 0 
L 6.095 2.292 6.005 2.292 1 P 0 
L 6.005 2.292 6.005 2.248 1 P 0 
L 6.08693327 2.19291624 6.08463307 2.19446683 1 P 0 ;0,1=637,2=0.000000
L 6.08463307 2.19446683 6.0819503 2.1955 1 P 0 ;0,1=637,2=0.000000
L 6.0819503 2.1955 6.07888356 2.1955 1 P 0 ;0,1=637,2=0.000000
L 6.07888356 2.1955 6.07543287 2.19394931 1 P 0 ;0,1=637,2=0.000000
L 6.07543287 2.19394931 6.0727501 2.19136654 1 P 0 ;0,1=637,2=0.000000
L 6.0727501 2.19136654 6.07083317 2.18826624 1 P 0 ;0,1=637,2=0.000000
L 6.07083317 2.18826624 6.06929951 2.1830998 1 P 0 ;0,1=637,2=0.000000
L 6.06929951 2.1830998 6.06891624 2.1784498 1 P 0 ;0,1=637,2=0.000000
L 6.06891624 2.1784498 6.06968337 2.1737999 1 P 0 ;0,1=637,2=0.000000
L 6.06968337 2.1737999 6.07083317 2.17069961 1 P 0 ;0,1=637,2=0.000000
L 6.07083317 2.17069961 6.07313337 2.16759931 1 P 0 ;0,1=637,2=0.000000
L 6.07313337 2.16759931 6.07581683 2.16553307 1 P 0 ;0,1=637,2=0.000000
L 6.07581683 2.16553307 6.07849961 2.1645 1 P 0 ;0,1=637,2=0.000000
L 6.07849961 2.1645 6.08118307 2.1645 1 P 0 ;0,1=637,2=0.000000
L 6.08118307 2.1645 6.08386654 2.16553307 1 P 0 ;0,1=637,2=0.000000
L 6.08386654 2.16553307 6.08616673 2.16708278 1 P 0 ;0,1=637,2=0.000000
L 6.08616673 2.16708278 6.08808366 2.16914892 1 P 0 ;0,1=637,2=0.000000
L 6.10221644 2.19033346 6.10451663 2.19343278 1 P 0 ;0,1=637,2=0.000000
L 6.10451663 2.19343278 6.1072001 2.19498337 1 P 0 ;0,1=637,2=0.000000
L 6.1072001 2.19498337 6.11026683 2.1955 1 P 0 ;0,1=637,2=0.000000
L 6.11026683 2.1955 6.1141 2.19446683 1 P 0 ;0,1=637,2=0.000000
L 6.1141 2.19446683 6.11678346 2.19188307 1 P 0 ;0,1=637,2=0.000000
L 6.11678346 2.19188307 6.11755 2.18878376 1 P 0 ;0,1=637,2=0.000000
L 6.11755 2.18878376 6.11716673 2.18568258 1 P 0 ;0,1=637,2=0.000000
L 6.11716673 2.18568258 6.11563307 2.1830998 1 P 0 ;0,1=637,2=0.000000
L 6.11563307 2.1830998 6.10796663 2.17793327 1 P 0 ;0,1=637,2=0.000000
L 6.10796663 2.17793327 6.10451663 2.17431644 1 P 0 ;0,1=637,2=0.000000
L 6.10451663 2.17431644 6.10221644 2.16914892 1 P 0 ;0,1=637,2=0.000000
L 6.10221644 2.16914892 6.1014499 2.1645 1 P 0 ;0,1=637,2=0.000000
L 6.1014499 2.1645 6.11755 2.1645 1 P 0 ;0,1=637,2=0.000000
L 6.13973307 2.1645 6.14049961 2.17121614 1 P 0 ;0,1=637,2=0.000000
L 6.14049961 2.17121614 6.1416501 2.17689921 1 P 0 ;0,1=637,2=0.000000
L 6.1416501 2.17689921 6.14318307 2.18206663 1 P 0 ;0,1=637,2=0.000000
L 6.14318307 2.18206663 6.1451 2.1877497 1 P 0 ;0,1=637,2=0.000000
L 6.1451 2.1877497 6.14816673 2.1955 1 P 0 ;0,1=637,2=0.000000
L 6.14816673 2.1955 6.13283317 2.1955 1 P 0 ;0,1=637,2=0.000000
L 6.16306663 2.16914892 6.16536614 2.16656614 1 P 0 ;0,1=637,2=0.000000
L 6.16536614 2.16656614 6.16804961 2.16501654 1 P 0 ;0,1=637,2=0.000000
L 6.16804961 2.16501654 6.17149961 2.1645 1 P 0 ;0,1=637,2=0.000000
L 6.17149961 2.1645 6.1749503 2.16553307 1 P 0 ;0,1=637,2=0.000000
L 6.1749503 2.16553307 6.17763307 2.16759931 1 P 0 ;0,1=637,2=0.000000
L 6.17763307 2.16759931 6.17955 2.17121614 1 P 0 ;0,1=637,2=0.000000
L 6.17955 2.17121614 6.17993327 2.17534951 1 P 0 ;0,1=637,2=0.000000
L 6.17993327 2.17534951 6.17916673 2.17948287 1 P 0 ;0,1=637,2=0.000000
L 6.17916673 2.17948287 6.1772498 2.18206663 1 P 0 ;0,1=637,2=0.000000
L 6.1772498 2.18206663 6.17456634 2.18413287 1 P 0 ;0,1=637,2=0.000000
L 6.17456634 2.18413287 6.17188356 2.18464941 1 P 0 ;0,1=637,2=0.000000
L 6.17188356 2.18464941 6.1692001 2.18413287 1 P 0 ;0,1=637,2=0.000000
L 6.1692001 2.18413287 6.1657501 2.18206663 1 P 0 ;0,1=637,2=0.000000
L 6.1657501 2.18206663 6.1668999 2.1955 1 P 0 ;0,1=637,2=0.000000
L 6.1668999 2.1955 6.1772498 2.1955 1 P 0 ;0,1=637,2=0.000000
L 3.40683996 2.577 3.36283996 2.577 1 P 0 
L 3.40683996 2.487 3.40683996 2.577 1 P 0 
L 3.36283996 2.577 3.36283996 2.487 1 P 0 
L 3.36283996 2.487 3.40683996 2.487 1 P 0 
L 3.00208376 3.01693327 3.00053317 3.01463307 1 P 0 ;0,1=638,2=270.000000
L 3.00053317 3.01463307 2.9995 3.0119503 1 P 0 ;0,1=638,2=270.000000
L 2.9995 3.0119503 2.9995 3.00888356 1 P 0 ;0,1=638,2=270.000000
L 2.9995 3.00888356 3.00105069 3.00543287 1 P 0 ;0,1=638,2=270.000000
L 3.00105069 3.00543287 3.00363346 3.0027501 1 P 0 ;0,1=638,2=270.000000
L 3.00363346 3.0027501 3.00673376 3.00083317 1 P 0 ;0,1=638,2=270.000000
L 3.00673376 3.00083317 3.0119002 2.99929951 1 P 0 ;0,1=638,2=270.000000
L 3.0119002 2.99929951 3.0165502 2.99891624 1 P 0 ;0,1=638,2=270.000000
L 3.0165502 2.99891624 3.0212001 2.99968337 1 P 0 ;0,1=638,2=270.000000
L 3.0212001 2.99968337 3.02430039 3.00083317 1 P 0 ;0,1=638,2=270.000000
L 3.02430039 3.00083317 3.02740069 3.00313337 1 P 0 ;0,1=638,2=270.000000
L 3.02740069 3.00313337 3.02946693 3.00581683 1 P 0 ;0,1=638,2=270.000000
L 3.02946693 3.00581683 3.0305 3.00849961 1 P 0 ;0,1=638,2=270.000000
L 3.0305 3.00849961 3.0305 3.01118307 1 P 0 ;0,1=638,2=270.000000
L 3.0305 3.01118307 3.02946693 3.01386654 1 P 0 ;0,1=638,2=270.000000
L 3.02946693 3.01386654 3.02791722 3.01616673 1 P 0 ;0,1=638,2=270.000000
L 3.02791722 3.01616673 3.02585108 3.01808366 1 P 0 ;0,1=638,2=270.000000
L 3.00466654 3.03221644 3.00156722 3.03451663 1 P 0 ;0,1=638,2=270.000000
L 3.00156722 3.03451663 3.00001663 3.0372001 1 P 0 ;0,1=638,2=270.000000
L 3.00001663 3.0372001 2.9995 3.04026683 1 P 0 ;0,1=638,2=270.000000
L 2.9995 3.04026683 3.00053317 3.0441 1 P 0 ;0,1=638,2=270.000000
L 3.00053317 3.0441 3.00311693 3.04678346 1 P 0 ;0,1=638,2=270.000000
L 3.00311693 3.04678346 3.00621624 3.04755 1 P 0 ;0,1=638,2=270.000000
L 3.00621624 3.04755 3.00931742 3.04716673 1 P 0 ;0,1=638,2=270.000000
L 3.00931742 3.04716673 3.0119002 3.04563307 1 P 0 ;0,1=638,2=270.000000
L 3.0119002 3.04563307 3.01706673 3.03796663 1 P 0 ;0,1=638,2=270.000000
L 3.01706673 3.03796663 3.02068356 3.03451663 1 P 0 ;0,1=638,2=270.000000
L 3.02068356 3.03451663 3.02585108 3.03221644 1 P 0 ;0,1=638,2=270.000000
L 3.02585108 3.03221644 3.0305 3.0314499 1 P 0 ;0,1=638,2=270.000000
L 3.0305 3.0314499 3.0305 3.04755 1 P 0 ;0,1=638,2=270.000000
L 3.0305 3.07049961 3.02998346 3.07318307 1 P 0 ;0,1=638,2=270.000000
L 3.02998346 3.07318307 3.02843386 3.0762498 1 P 0 ;0,1=638,2=270.000000
L 3.02843386 3.0762498 3.02585108 3.07816673 1 P 0 ;0,1=638,2=270.000000
L 3.02585108 3.07816673 3.02223327 3.07893327 1 P 0 ;0,1=638,2=270.000000
L 3.02223327 3.07893327 3.01861732 3.07816673 1 P 0 ;0,1=638,2=270.000000
L 3.01861732 3.07816673 3.01551713 3.07586654 1 P 0 ;0,1=638,2=270.000000
L 3.01551713 3.07586654 3.01396644 3.07241654 1 P 0 ;0,1=638,2=270.000000
L 3.01396644 3.07241654 3.01396644 3.06858337 1 P 0 ;0,1=638,2=270.000000
L 3.01396644 3.06858337 3.01293337 3.06628317 1 P 0 ;0,1=638,2=270.000000
L 3.01293337 3.06628317 3.01035059 3.06436614 1 P 0 ;0,1=638,2=270.000000
L 3.01035059 3.06436614 3.00673376 3.0635997 1 P 0 ;0,1=638,2=270.000000
L 3.00673376 3.0635997 3.00311693 3.0647501 1 P 0 ;0,1=638,2=270.000000
L 3.00311693 3.0647501 3.00053317 3.06743287 1 P 0 ;0,1=638,2=270.000000
L 3.00053317 3.06743287 2.9995 3.07049961 1 P 0 ;0,1=638,2=270.000000
L 2.9995 3.07049961 3.00053317 3.07356634 1 P 0 ;0,1=638,2=270.000000
L 3.00053317 3.07356634 3.00311693 3.0762498 1 P 0 ;0,1=638,2=270.000000
L 3.00311693 3.0762498 3.00673376 3.0774002 1 P 0 ;0,1=638,2=270.000000
L 3.00673376 3.0774002 3.01035059 3.07663307 1 P 0 ;0,1=638,2=270.000000
L 3.01035059 3.07663307 3.01293337 3.07471673 1 P 0 ;0,1=638,2=270.000000
L 3.01293337 3.07471673 3.01396644 3.07241654 1 P 0 ;0,1=638,2=270.000000
L 3.01396644 3.07241654 3.01396644 3.06858337 1 P 0 ;0,1=638,2=270.000000
L 3.01396644 3.06858337 3.01551713 3.06513337 1 P 0 ;0,1=638,2=270.000000
L 3.01551713 3.06513337 3.01861732 3.06283317 1 P 0 ;0,1=638,2=270.000000
L 3.01861732 3.06283317 3.02223327 3.06206663 1 P 0 ;0,1=638,2=270.000000
L 3.02223327 3.06206663 3.02585108 3.06283317 1 P 0 ;0,1=638,2=270.000000
L 3.02585108 3.06283317 3.02843386 3.0647501 1 P 0 ;0,1=638,2=270.000000
L 3.02843386 3.0647501 3.02998346 3.06781683 1 P 0 ;0,1=638,2=270.000000
L 3.02998346 3.06781683 3.0305 3.07049961 1 P 0 ;0,1=638,2=270.000000
L 2.9995 3.10149961 3.00053317 3.09843287 1 P 0 ;0,1=638,2=270.000000
L 3.00053317 3.09843287 3.00311693 3.09613337 1 P 0 ;0,1=638,2=270.000000
L 3.00311693 3.09613337 3.00621624 3.0945997 1 P 0 ;0,1=638,2=270.000000
L 3.00621624 3.0945997 3.01035059 3.0934499 1 P 0 ;0,1=638,2=270.000000
L 3.01035059 3.0934499 3.01500049 3.09306663 1 P 0 ;0,1=638,2=270.000000
L 3.01500049 3.09306663 3.01965049 3.0934499 1 P 0 ;0,1=638,2=270.000000
L 3.01965049 3.0934499 3.02378386 3.0945997 1 P 0 ;0,1=638,2=270.000000
L 3.02378386 3.0945997 3.02688415 3.09613337 1 P 0 ;0,1=638,2=270.000000
L 3.02688415 3.09613337 3.02946693 3.09843287 1 P 0 ;0,1=638,2=270.000000
L 3.02946693 3.09843287 3.0305 3.10149961 1 P 0 ;0,1=638,2=270.000000
L 3.0305 3.10149961 3.02946693 3.10456634 1 P 0 ;0,1=638,2=270.000000
L 3.02946693 3.10456634 3.02688415 3.10686654 1 P 0 ;0,1=638,2=270.000000
L 3.02688415 3.10686654 3.02378386 3.1084002 1 P 0 ;0,1=638,2=270.000000
L 3.02378386 3.1084002 3.01965049 3.10955 1 P 0 ;0,1=638,2=270.000000
L 3.01965049 3.10955 3.01500049 3.10993327 1 P 0 ;0,1=638,2=270.000000
L 3.01500049 3.10993327 3.01035059 3.10955 1 P 0 ;0,1=638,2=270.000000
L 3.01035059 3.10955 3.00621624 3.1084002 1 P 0 ;0,1=638,2=270.000000
L 3.00621624 3.1084002 3.00311693 3.10686654 1 P 0 ;0,1=638,2=270.000000
L 3.00311693 3.10686654 3.00053317 3.10456634 1 P 0 ;0,1=638,2=270.000000
L 3.00053317 3.10456634 2.9995 3.10149961 1 P 0 ;0,1=638,2=270.000000
L 3.457 2.577 3.413 2.577 1 P 0 
L 3.457 2.487 3.457 2.577 1 P 0 
L 3.413 2.577 3.413 2.487 1 P 0 
L 3.413 2.487 3.457 2.487 1 P 0 
L 3.04208376 3.01693327 3.04053317 3.01463307 1 P 0 ;0,1=639,2=270.000000
L 3.04053317 3.01463307 3.0395 3.0119503 1 P 0 ;0,1=639,2=270.000000
L 3.0395 3.0119503 3.0395 3.00888356 1 P 0 ;0,1=639,2=270.000000
L 3.0395 3.00888356 3.04105069 3.00543287 1 P 0 ;0,1=639,2=270.000000
L 3.04105069 3.00543287 3.04363346 3.0027501 1 P 0 ;0,1=639,2=270.000000
L 3.04363346 3.0027501 3.04673376 3.00083317 1 P 0 ;0,1=639,2=270.000000
L 3.04673376 3.00083317 3.0519002 2.99929951 1 P 0 ;0,1=639,2=270.000000
L 3.0519002 2.99929951 3.0565502 2.99891624 1 P 0 ;0,1=639,2=270.000000
L 3.0565502 2.99891624 3.0612001 2.99968337 1 P 0 ;0,1=639,2=270.000000
L 3.0612001 2.99968337 3.06430039 3.00083317 1 P 0 ;0,1=639,2=270.000000
L 3.06430039 3.00083317 3.06740069 3.00313337 1 P 0 ;0,1=639,2=270.000000
L 3.06740069 3.00313337 3.06946693 3.00581683 1 P 0 ;0,1=639,2=270.000000
L 3.06946693 3.00581683 3.0705 3.00849961 1 P 0 ;0,1=639,2=270.000000
L 3.0705 3.00849961 3.0705 3.01118307 1 P 0 ;0,1=639,2=270.000000
L 3.0705 3.01118307 3.06946693 3.01386654 1 P 0 ;0,1=639,2=270.000000
L 3.06946693 3.01386654 3.06791722 3.01616673 1 P 0 ;0,1=639,2=270.000000
L 3.06791722 3.01616673 3.06585108 3.01808366 1 P 0 ;0,1=639,2=270.000000
L 3.04466654 3.03221644 3.04156722 3.03451663 1 P 0 ;0,1=639,2=270.000000
L 3.04156722 3.03451663 3.04001663 3.0372001 1 P 0 ;0,1=639,2=270.000000
L 3.04001663 3.0372001 3.0395 3.04026683 1 P 0 ;0,1=639,2=270.000000
L 3.0395 3.04026683 3.04053317 3.0441 1 P 0 ;0,1=639,2=270.000000
L 3.04053317 3.0441 3.04311693 3.04678346 1 P 0 ;0,1=639,2=270.000000
L 3.04311693 3.04678346 3.04621624 3.04755 1 P 0 ;0,1=639,2=270.000000
L 3.04621624 3.04755 3.04931742 3.04716673 1 P 0 ;0,1=639,2=270.000000
L 3.04931742 3.04716673 3.0519002 3.04563307 1 P 0 ;0,1=639,2=270.000000
L 3.0519002 3.04563307 3.05706673 3.03796663 1 P 0 ;0,1=639,2=270.000000
L 3.05706673 3.03796663 3.06068356 3.03451663 1 P 0 ;0,1=639,2=270.000000
L 3.06068356 3.03451663 3.06585108 3.03221644 1 P 0 ;0,1=639,2=270.000000
L 3.06585108 3.03221644 3.0705 3.0314499 1 P 0 ;0,1=639,2=270.000000
L 3.0705 3.0314499 3.0705 3.04755 1 P 0 ;0,1=639,2=270.000000
L 3.0705 3.07049961 3.06998346 3.07318307 1 P 0 ;0,1=639,2=270.000000
L 3.06998346 3.07318307 3.06843386 3.0762498 1 P 0 ;0,1=639,2=270.000000
L 3.06843386 3.0762498 3.06585108 3.07816673 1 P 0 ;0,1=639,2=270.000000
L 3.06585108 3.07816673 3.06223327 3.07893327 1 P 0 ;0,1=639,2=270.000000
L 3.06223327 3.07893327 3.05861732 3.07816673 1 P 0 ;0,1=639,2=270.000000
L 3.05861732 3.07816673 3.05551713 3.07586654 1 P 0 ;0,1=639,2=270.000000
L 3.05551713 3.07586654 3.05396644 3.07241654 1 P 0 ;0,1=639,2=270.000000
L 3.05396644 3.07241654 3.05396644 3.06858337 1 P 0 ;0,1=639,2=270.000000
L 3.05396644 3.06858337 3.05293337 3.06628317 1 P 0 ;0,1=639,2=270.000000
L 3.05293337 3.06628317 3.05035059 3.06436614 1 P 0 ;0,1=639,2=270.000000
L 3.05035059 3.06436614 3.04673376 3.0635997 1 P 0 ;0,1=639,2=270.000000
L 3.04673376 3.0635997 3.04311693 3.0647501 1 P 0 ;0,1=639,2=270.000000
L 3.04311693 3.0647501 3.04053317 3.06743287 1 P 0 ;0,1=639,2=270.000000
L 3.04053317 3.06743287 3.0395 3.07049961 1 P 0 ;0,1=639,2=270.000000
L 3.0395 3.07049961 3.04053317 3.07356634 1 P 0 ;0,1=639,2=270.000000
L 3.04053317 3.07356634 3.04311693 3.0762498 1 P 0 ;0,1=639,2=270.000000
L 3.04311693 3.0762498 3.04673376 3.0774002 1 P 0 ;0,1=639,2=270.000000
L 3.04673376 3.0774002 3.05035059 3.07663307 1 P 0 ;0,1=639,2=270.000000
L 3.05035059 3.07663307 3.05293337 3.07471673 1 P 0 ;0,1=639,2=270.000000
L 3.05293337 3.07471673 3.05396644 3.07241654 1 P 0 ;0,1=639,2=270.000000
L 3.05396644 3.07241654 3.05396644 3.06858337 1 P 0 ;0,1=639,2=270.000000
L 3.05396644 3.06858337 3.05551713 3.06513337 1 P 0 ;0,1=639,2=270.000000
L 3.05551713 3.06513337 3.05861732 3.06283317 1 P 0 ;0,1=639,2=270.000000
L 3.05861732 3.06283317 3.06223327 3.06206663 1 P 0 ;0,1=639,2=270.000000
L 3.06223327 3.06206663 3.06585108 3.06283317 1 P 0 ;0,1=639,2=270.000000
L 3.06585108 3.06283317 3.06843386 3.0647501 1 P 0 ;0,1=639,2=270.000000
L 3.06843386 3.0647501 3.06998346 3.06781683 1 P 0 ;0,1=639,2=270.000000
L 3.06998346 3.06781683 3.0705 3.07049961 1 P 0 ;0,1=639,2=270.000000
L 3.0705 3.10149961 3.0395 3.10149961 1 P 0 ;0,1=639,2=270.000000
L 3.0395 3.10149961 3.0456997 3.0968999 1 P 0 ;0,1=639,2=270.000000
L 3.0705 3.0968999 3.0705 3.10609931 1 P 0 ;0,1=639,2=270.000000
L 3.568 2.579 3.524 2.579 1 P 0 
L 3.524 2.579 3.524 2.489 1 P 0 
L 3.524 2.489 3.568 2.489 1 P 0 
L 3.568 2.489 3.568 2.579 1 P 0 
L 3.15208376 3.01193327 3.15053317 3.00963307 1 P 0 ;0,1=640,2=270.000000
L 3.15053317 3.00963307 3.1495 3.0069503 1 P 0 ;0,1=640,2=270.000000
L 3.1495 3.0069503 3.1495 3.00388356 1 P 0 ;0,1=640,2=270.000000
L 3.1495 3.00388356 3.15105069 3.00043287 1 P 0 ;0,1=640,2=270.000000
L 3.15105069 3.00043287 3.15363346 2.9977501 1 P 0 ;0,1=640,2=270.000000
L 3.15363346 2.9977501 3.15673376 2.99583317 1 P 0 ;0,1=640,2=270.000000
L 3.15673376 2.99583317 3.1619002 2.99429951 1 P 0 ;0,1=640,2=270.000000
L 3.1619002 2.99429951 3.1665502 2.99391624 1 P 0 ;0,1=640,2=270.000000
L 3.1665502 2.99391624 3.1712001 2.99468337 1 P 0 ;0,1=640,2=270.000000
L 3.1712001 2.99468337 3.17430039 2.99583317 1 P 0 ;0,1=640,2=270.000000
L 3.17430039 2.99583317 3.17740069 2.99813337 1 P 0 ;0,1=640,2=270.000000
L 3.17740069 2.99813337 3.17946693 3.00081683 1 P 0 ;0,1=640,2=270.000000
L 3.17946693 3.00081683 3.1805 3.00349961 1 P 0 ;0,1=640,2=270.000000
L 3.1805 3.00349961 3.1805 3.00618307 1 P 0 ;0,1=640,2=270.000000
L 3.1805 3.00618307 3.17946693 3.00886654 1 P 0 ;0,1=640,2=270.000000
L 3.17946693 3.00886654 3.17791722 3.01116673 1 P 0 ;0,1=640,2=270.000000
L 3.17791722 3.01116673 3.17585108 3.01308366 1 P 0 ;0,1=640,2=270.000000
L 3.15466654 3.02721644 3.15156722 3.02951663 1 P 0 ;0,1=640,2=270.000000
L 3.15156722 3.02951663 3.15001663 3.0322001 1 P 0 ;0,1=640,2=270.000000
L 3.15001663 3.0322001 3.1495 3.03526683 1 P 0 ;0,1=640,2=270.000000
L 3.1495 3.03526683 3.15053317 3.0391 1 P 0 ;0,1=640,2=270.000000
L 3.15053317 3.0391 3.15311693 3.04178346 1 P 0 ;0,1=640,2=270.000000
L 3.15311693 3.04178346 3.15621624 3.04255 1 P 0 ;0,1=640,2=270.000000
L 3.15621624 3.04255 3.15931742 3.04216673 1 P 0 ;0,1=640,2=270.000000
L 3.15931742 3.04216673 3.1619002 3.04063307 1 P 0 ;0,1=640,2=270.000000
L 3.1619002 3.04063307 3.16706673 3.03296663 1 P 0 ;0,1=640,2=270.000000
L 3.16706673 3.03296663 3.17068356 3.02951663 1 P 0 ;0,1=640,2=270.000000
L 3.17068356 3.02951663 3.17585108 3.02721644 1 P 0 ;0,1=640,2=270.000000
L 3.17585108 3.02721644 3.1805 3.0264499 1 P 0 ;0,1=640,2=270.000000
L 3.1805 3.0264499 3.1805 3.04255 1 P 0 ;0,1=640,2=270.000000
L 3.1805 3.06473307 3.17378386 3.06549961 1 P 0 ;0,1=640,2=270.000000
L 3.17378386 3.06549961 3.16810079 3.0666501 1 P 0 ;0,1=640,2=270.000000
L 3.16810079 3.0666501 3.16293337 3.06818307 1 P 0 ;0,1=640,2=270.000000
L 3.16293337 3.06818307 3.1572503 3.0701 1 P 0 ;0,1=640,2=270.000000
L 3.1572503 3.0701 3.1495 3.07316673 1 P 0 ;0,1=640,2=270.000000
L 3.1495 3.07316673 3.1495 3.05783317 1 P 0 ;0,1=640,2=270.000000
L 3.17688415 3.08998287 3.17946693 3.09266634 1 P 0 ;0,1=640,2=270.000000
L 3.17946693 3.09266634 3.1805 3.09573307 1 P 0 ;0,1=640,2=270.000000
L 3.1805 3.09573307 3.17946693 3.0987998 1 P 0 ;0,1=640,2=270.000000
L 3.17946693 3.0987998 3.17636762 3.10148327 1 P 0 ;0,1=640,2=270.000000
L 3.17636762 3.10148327 3.17171673 3.1034002 1 P 0 ;0,1=640,2=270.000000
L 3.17171673 3.1034002 3.16706673 3.10416673 1 P 0 ;0,1=640,2=270.000000
L 3.16706673 3.10416673 3.16138366 3.10416673 1 P 0 ;0,1=640,2=270.000000
L 3.16138366 3.10416673 3.15673376 3.1034002 1 P 0 ;0,1=640,2=270.000000
L 3.15673376 3.1034002 3.1526003 3.10148327 1 P 0 ;0,1=640,2=270.000000
L 3.1526003 3.10148327 3.15053317 3.09918307 1 P 0 ;0,1=640,2=270.000000
L 3.15053317 3.09918307 3.1495 3.09649961 1 P 0 ;0,1=640,2=270.000000
L 3.1495 3.09649961 3.15053317 3.09343287 1 P 0 ;0,1=640,2=270.000000
L 3.15053317 3.09343287 3.1526003 3.09113337 1 P 0 ;0,1=640,2=270.000000
L 3.1526003 3.09113337 3.1556997 3.0895997 1 P 0 ;0,1=640,2=270.000000
L 3.1556997 3.0895997 3.15983406 3.08883317 1 P 0 ;0,1=640,2=270.000000
L 3.15983406 3.08883317 3.1634499 3.0895997 1 P 0 ;0,1=640,2=270.000000
L 3.1634499 3.0895997 3.16706673 3.09151663 1 P 0 ;0,1=640,2=270.000000
L 3.16706673 3.09151663 3.16913396 3.09381683 1 P 0 ;0,1=640,2=270.000000
L 3.16913396 3.09381683 3.16965049 3.09649961 1 P 0 ;0,1=640,2=270.000000
L 3.16965049 3.09649961 3.16861732 3.09956634 1 P 0 ;0,1=640,2=270.000000
L 3.16861732 3.09956634 3.16603366 3.10186654 1 P 0 ;0,1=640,2=270.000000
L 3.16603366 3.10186654 3.16138366 3.10416673 1 P 0 ;0,1=640,2=270.000000
L 0.89256998 2.18153996 0.89256998 2.0249 1 P 0 
L 0.71543002 2.18153996 0.89256998 2.18153996 1 P 0 
L 0.89256998 2.0249 0.71543002 2.0249 1 P 0 
L 0.71543002 2.0249 0.71543002 2.18153996 1 P 0 
L 0.90633317 2.09569961 0.9082501 2.09259931 1 P 0 ;0,1=641,2=0.000000
L 0.9082501 2.09259931 0.91054961 2.09053307 1 P 0 ;0,1=641,2=0.000000
L 0.91054961 2.09053307 0.91323307 2.0895 1 P 0 ;0,1=641,2=0.000000
L 0.91323307 2.0895 0.9162998 2.09053307 1 P 0 ;0,1=641,2=0.000000
L 0.9162998 2.09053307 0.9186 2.09259931 1 P 0 ;0,1=641,2=0.000000
L 0.9186 2.09259931 0.9209002 2.09569961 1 P 0 ;0,1=641,2=0.000000
L 0.9209002 2.09569961 0.92166673 2.09983297 1 P 0 ;0,1=641,2=0.000000
L 0.92166673 2.09983297 0.92166673 2.1205 1 P 0 ;0,1=641,2=0.000000
L 0.94499961 2.0895 0.94499961 2.1205 1 P 0 ;0,1=641,2=0.000000
L 0.94499961 2.1205 0.9403999 2.1143003 1 P 0 ;0,1=641,2=0.000000
L 0.9403999 2.0895 0.94959931 2.0895 1 P 0 ;0,1=641,2=0.000000
L 0.97599961 2.0895 0.97868307 2.09001654 1 P 0 ;0,1=641,2=0.000000
L 0.97868307 2.09001654 0.9817498 2.09156614 1 P 0 ;0,1=641,2=0.000000
L 0.9817498 2.09156614 0.98366673 2.09414892 1 P 0 ;0,1=641,2=0.000000
L 0.98366673 2.09414892 0.98443327 2.09776673 1 P 0 ;0,1=641,2=0.000000
L 0.98443327 2.09776673 0.98366673 2.10138268 1 P 0 ;0,1=641,2=0.000000
L 0.98366673 2.10138268 0.98136654 2.10448287 1 P 0 ;0,1=641,2=0.000000
L 0.98136654 2.10448287 0.97791654 2.10603356 1 P 0 ;0,1=641,2=0.000000
L 0.97791654 2.10603356 0.97408337 2.10603356 1 P 0 ;0,1=641,2=0.000000
L 0.97408337 2.10603356 0.97178317 2.10706663 1 P 0 ;0,1=641,2=0.000000
L 0.97178317 2.10706663 0.96986614 2.10964941 1 P 0 ;0,1=641,2=0.000000
L 0.96986614 2.10964941 0.9690997 2.11326624 1 P 0 ;0,1=641,2=0.000000
L 0.9690997 2.11326624 0.9702501 2.11688307 1 P 0 ;0,1=641,2=0.000000
L 0.9702501 2.11688307 0.97293287 2.11946683 1 P 0 ;0,1=641,2=0.000000
L 0.97293287 2.11946683 0.97599961 2.1205 1 P 0 ;0,1=641,2=0.000000
L 0.97599961 2.1205 0.97906634 2.11946683 1 P 0 ;0,1=641,2=0.000000
L 0.97906634 2.11946683 0.9817498 2.11688307 1 P 0 ;0,1=641,2=0.000000
L 0.9817498 2.11688307 0.9829002 2.11326624 1 P 0 ;0,1=641,2=0.000000
L 0.9829002 2.11326624 0.98213307 2.10964941 1 P 0 ;0,1=641,2=0.000000
L 0.98213307 2.10964941 0.98021673 2.10706663 1 P 0 ;0,1=641,2=0.000000
L 0.98021673 2.10706663 0.97791654 2.10603356 1 P 0 ;0,1=641,2=0.000000
L 0.97791654 2.10603356 0.97408337 2.10603356 1 P 0 ;0,1=641,2=0.000000
L 0.97408337 2.10603356 0.97063337 2.10448287 1 P 0 ;0,1=641,2=0.000000
L 0.97063337 2.10448287 0.96833317 2.10138268 1 P 0 ;0,1=641,2=0.000000
L 0.96833317 2.10138268 0.96756663 2.09776673 1 P 0 ;0,1=641,2=0.000000
L 0.96756663 2.09776673 0.96833317 2.09414892 1 P 0 ;0,1=641,2=0.000000
L 0.96833317 2.09414892 0.9702501 2.09156614 1 P 0 ;0,1=641,2=0.000000
L 0.9702501 2.09156614 0.97331683 2.09001654 1 P 0 ;0,1=641,2=0.000000
L 0.97331683 2.09001654 0.97599961 2.0895 1 P 0 ;0,1=641,2=0.000000
L 0.9199997 2.0445 0.9199997 2.0695 1 P 0 ;0,1=2,2=0.000000
L 0.9199997 2.0695 0.9167999 2.0645003 1 P 0 ;0,1=2,2=0.000000
L 0.9167999 2.0445 0.92319951 2.0445 1 P 0 ;0,1=2,2=0.000000
L 0.89993317 2.17833337 0.90153327 2.18083287 1 P 0 ;0,1=4,2=0.000000
L 0.90153327 2.18083287 0.9034 2.18208337 1 P 0 ;0,1=4,2=0.000000
L 0.9034 2.18208337 0.90553337 2.1825 1 P 0 ;0,1=4,2=0.000000
L 0.90553337 2.1825 0.9082 2.18166683 1 P 0 ;0,1=4,2=0.000000
L 0.9082 2.18166683 0.91006673 2.17958317 1 P 0 ;0,1=4,2=0.000000
L 0.91006673 2.17958317 0.9106 2.17708366 1 P 0 ;0,1=4,2=0.000000
L 0.9106 2.17708366 0.91033337 2.17458268 1 P 0 ;0,1=4,2=0.000000
L 0.91033337 2.17458268 0.90926644 2.1724998 1 P 0 ;0,1=4,2=0.000000
L 0.90926644 2.1724998 0.90393327 2.16833327 1 P 0 ;0,1=4,2=0.000000
L 0.90393327 2.16833327 0.90153327 2.16541644 1 P 0 ;0,1=4,2=0.000000
L 0.90153327 2.16541644 0.89993317 2.16124911 1 P 0 ;0,1=4,2=0.000000
L 0.89993317 2.16124911 0.8993999 2.1575 1 P 0 ;0,1=4,2=0.000000
L 0.8993999 2.1575 0.9106 2.1575 1 P 0 ;0,1=4,2=0.000000
L 0.69413327 2.05749961 0.69573297 2.05458287 1 P 0 ;0,1=10,2=0.000000
L 0.69573297 2.05458287 0.69786634 2.05291654 1 P 0 ;0,1=10,2=0.000000
L 0.69786634 2.05291654 0.70026683 2.0525 1 P 0 ;0,1=10,2=0.000000
L 0.70026683 2.0525 0.7024002 2.05291654 1 P 0 ;0,1=10,2=0.000000
L 0.7024002 2.05291654 0.70453356 2.05499941 1 P 0 ;0,1=10,2=0.000000
L 0.70453356 2.05499941 0.70586663 2.05749961 1 P 0 ;0,1=10,2=0.000000
L 0.70586663 2.05749961 0.70613317 2.0599999 1 P 0 ;0,1=10,2=0.000000
L 0.70613317 2.0599999 0.7056 2.06291594 1 P 0 ;0,1=10,2=0.000000
L 0.7056 2.06291594 0.70373327 2.06499961 1 P 0 ;0,1=10,2=0.000000
L 0.70373327 2.06499961 0.70186644 2.06583346 1 P 0 ;0,1=10,2=0.000000
L 0.70186644 2.06583346 0.69946654 2.06583346 1 P 0 ;0,1=10,2=0.000000
L 0.70186644 2.06583346 0.70346663 2.06708327 1 P 0 ;0,1=10,2=0.000000
L 0.70346663 2.06708327 0.7048001 2.06916614 1 P 0 ;0,1=10,2=0.000000
L 0.7048001 2.06916614 0.70533337 2.07166634 1 P 0 ;0,1=10,2=0.000000
L 0.70533337 2.07166634 0.7048001 2.07416654 1 P 0 ;0,1=10,2=0.000000
L 0.7048001 2.07416654 0.70346663 2.07624941 1 P 0 ;0,1=10,2=0.000000
L 0.70346663 2.07624941 0.70106663 2.0775 1 P 0 ;0,1=10,2=0.000000
L 0.70106663 2.0775 0.69866663 2.07708337 1 P 0 ;0,1=10,2=0.000000
L 0.69866663 2.07708337 0.69626663 2.07541634 1 P 0 ;0,1=10,2=0.000000
L 0.168 1.082 0.302 1.082 1 P 0 
L 0.302 1.082 0.302 0.918 1 P 0 
L 0.302 0.918 0.168 0.918 1 P 0 
L 0.168 0.918 0.168 1.082 1 P 0 
S P 0
OB 0.215 0.897 I
OC 0.215 0.897 0.2 0.897 Y
OE
SE
L 0.19456004 1.08756998 0.19456004 1.11256998 1 P 0 ;0,1=11,2=0.000000
L 0.19456004 1.11256998 0.18469301 1.09465325 1 P 0 ;0,1=11,2=0.000000
L 0.18469301 1.09465325 0.19802697 1.09465325 1 P 0 ;0,1=11,2=0.000000
L 0.29413327 1.09249961 0.29573297 1.08958287 1 P 0 ;0,1=10,2=0.000000
L 0.29573297 1.08958287 0.29786634 1.08791654 1 P 0 ;0,1=10,2=0.000000
L 0.29786634 1.08791654 0.30026683 1.0875 1 P 0 ;0,1=10,2=0.000000
L 0.30026683 1.0875 0.3024002 1.08791654 1 P 0 ;0,1=10,2=0.000000
L 0.3024002 1.08791654 0.30453356 1.08999941 1 P 0 ;0,1=10,2=0.000000
L 0.30453356 1.08999941 0.30586663 1.09249961 1 P 0 ;0,1=10,2=0.000000
L 0.30586663 1.09249961 0.30613317 1.0949999 1 P 0 ;0,1=10,2=0.000000
L 0.30613317 1.0949999 0.3056 1.09791594 1 P 0 ;0,1=10,2=0.000000
L 0.3056 1.09791594 0.30373327 1.09999961 1 P 0 ;0,1=10,2=0.000000
L 0.30373327 1.09999961 0.30186644 1.10083346 1 P 0 ;0,1=10,2=0.000000
L 0.30186644 1.10083346 0.29946654 1.10083346 1 P 0 ;0,1=10,2=0.000000
L 0.30186644 1.10083346 0.30346663 1.10208327 1 P 0 ;0,1=10,2=0.000000
L 0.30346663 1.10208327 0.3048001 1.10416614 1 P 0 ;0,1=10,2=0.000000
L 0.3048001 1.10416614 0.30533337 1.10666634 1 P 0 ;0,1=10,2=0.000000
L 0.30533337 1.10666634 0.3048001 1.10916654 1 P 0 ;0,1=10,2=0.000000
L 0.3048001 1.10916654 0.30346663 1.11124941 1 P 0 ;0,1=10,2=0.000000
L 0.30346663 1.11124941 0.30106663 1.1125 1 P 0 ;0,1=10,2=0.000000
L 0.30106663 1.1125 0.29866663 1.11208337 1 P 0 ;0,1=10,2=0.000000
L 0.29866663 1.11208337 0.29626663 1.11041634 1 P 0 ;0,1=10,2=0.000000
L 0.31208376 0.95743327 0.31053317 0.95513307 1 P 0 ;0,1=642,2=270.000000
L 0.31053317 0.95513307 0.3095 0.9524503 1 P 0 ;0,1=642,2=270.000000
L 0.3095 0.9524503 0.3095 0.94938356 1 P 0 ;0,1=642,2=270.000000
L 0.3095 0.94938356 0.31105069 0.94593287 1 P 0 ;0,1=642,2=270.000000
L 0.31105069 0.94593287 0.31363346 0.9432501 1 P 0 ;0,1=642,2=270.000000
L 0.31363346 0.9432501 0.31673376 0.94133317 1 P 0 ;0,1=642,2=270.000000
L 0.31673376 0.94133317 0.3219002 0.93979951 1 P 0 ;0,1=642,2=270.000000
L 0.3219002 0.93979951 0.3265502 0.93941624 1 P 0 ;0,1=642,2=270.000000
L 0.3265502 0.93941624 0.3312001 0.94018337 1 P 0 ;0,1=642,2=270.000000
L 0.3312001 0.94018337 0.33430039 0.94133317 1 P 0 ;0,1=642,2=270.000000
L 0.33430039 0.94133317 0.33740069 0.94363337 1 P 0 ;0,1=642,2=270.000000
L 0.33740069 0.94363337 0.33946693 0.94631683 1 P 0 ;0,1=642,2=270.000000
L 0.33946693 0.94631683 0.3405 0.94899961 1 P 0 ;0,1=642,2=270.000000
L 0.3405 0.94899961 0.3405 0.95168307 1 P 0 ;0,1=642,2=270.000000
L 0.3405 0.95168307 0.33946693 0.95436654 1 P 0 ;0,1=642,2=270.000000
L 0.33946693 0.95436654 0.33791722 0.95666673 1 P 0 ;0,1=642,2=270.000000
L 0.33791722 0.95666673 0.33585108 0.95858366 1 P 0 ;0,1=642,2=270.000000
L 0.3405 0.97233317 0.3095 0.97233317 1 P 0 ;0,1=642,2=270.000000
L 0.3095 0.97233317 0.3095 0.98191654 1 P 0 ;0,1=642,2=270.000000
L 0.3095 0.98191654 0.31105069 0.98498327 1 P 0 ;0,1=642,2=270.000000
L 0.31105069 0.98498327 0.31311693 0.9869002 1 P 0 ;0,1=642,2=270.000000
L 0.31311693 0.9869002 0.3172503 0.98766673 1 P 0 ;0,1=642,2=270.000000
L 0.3172503 0.98766673 0.32138366 0.9869002 1 P 0 ;0,1=642,2=270.000000
L 0.32138366 0.9869002 0.32396644 0.9846 1 P 0 ;0,1=642,2=270.000000
L 0.32396644 0.9846 0.32551713 0.98191654 1 P 0 ;0,1=642,2=270.000000
L 0.32551713 0.98191654 0.32551713 0.97233317 1 P 0 ;0,1=642,2=270.000000
L 0.32551713 0.98191654 0.3405 0.98766673 1 P 0 ;0,1=642,2=270.000000
L 0.33585108 1.00256663 0.33843386 1.00486614 1 P 0 ;0,1=642,2=270.000000
L 0.33843386 1.00486614 0.33998346 1.00754961 1 P 0 ;0,1=642,2=270.000000
L 0.33998346 1.00754961 0.3405 1.01099961 1 P 0 ;0,1=642,2=270.000000
L 0.3405 1.01099961 0.33946693 1.0144503 1 P 0 ;0,1=642,2=270.000000
L 0.33946693 1.0144503 0.33740069 1.01713307 1 P 0 ;0,1=642,2=270.000000
L 0.33740069 1.01713307 0.33378386 1.01905 1 P 0 ;0,1=642,2=270.000000
L 0.33378386 1.01905 0.32965049 1.01943327 1 P 0 ;0,1=642,2=270.000000
L 0.32965049 1.01943327 0.32551713 1.01866673 1 P 0 ;0,1=642,2=270.000000
L 0.32551713 1.01866673 0.32293337 1.0167498 1 P 0 ;0,1=642,2=270.000000
L 0.32293337 1.0167498 0.32086713 1.01406634 1 P 0 ;0,1=642,2=270.000000
L 0.32086713 1.01406634 0.32035059 1.01138356 1 P 0 ;0,1=642,2=270.000000
L 0.32035059 1.01138356 0.32086713 1.0087001 1 P 0 ;0,1=642,2=270.000000
L 0.32086713 1.0087001 0.32293337 1.0052501 1 P 0 ;0,1=642,2=270.000000
L 0.32293337 1.0052501 0.3095 1.0063999 1 P 0 ;0,1=642,2=270.000000
L 0.3095 1.0063999 0.3095 1.0167498 1 P 0 ;0,1=642,2=270.000000
L 0.30993317 0.91333337 0.31153327 0.91583287 1 P 0 ;0,1=4,2=0.000000
L 0.31153327 0.91583287 0.3134 0.91708337 1 P 0 ;0,1=4,2=0.000000
L 0.3134 0.91708337 0.31553337 0.9175 1 P 0 ;0,1=4,2=0.000000
L 0.31553337 0.9175 0.3182 0.91666683 1 P 0 ;0,1=4,2=0.000000
L 0.3182 0.91666683 0.32006673 0.91458317 1 P 0 ;0,1=4,2=0.000000
L 0.32006673 0.91458317 0.3206 0.91208366 1 P 0 ;0,1=4,2=0.000000
L 0.3206 0.91208366 0.32033337 0.90958268 1 P 0 ;0,1=4,2=0.000000
L 0.32033337 0.90958268 0.31926644 0.9074998 1 P 0 ;0,1=4,2=0.000000
L 0.31926644 0.9074998 0.31393327 0.90333327 1 P 0 ;0,1=4,2=0.000000
L 0.31393327 0.90333327 0.31153327 0.90041644 1 P 0 ;0,1=4,2=0.000000
L 0.31153327 0.90041644 0.30993317 0.89624911 1 P 0 ;0,1=4,2=0.000000
L 0.30993317 0.89624911 0.3093999 0.8925 1 P 0 ;0,1=4,2=0.000000
L 0.3093999 0.8925 0.3206 0.8925 1 P 0 ;0,1=4,2=0.000000
L 0.168 2.222 0.302 2.222 1 P 0 
L 0.302 2.222 0.302 2.058 1 P 0 
L 0.302 2.058 0.168 2.058 1 P 0 
L 0.168 2.058 0.168 2.222 1 P 0 
S P 0
OB 0.215 2.037 I
OC 0.215 2.037 0.2 2.037 Y
OE
SE
L 0.32063327 2.20949961 0.32223297 2.20658287 1 P 0 ;0,1=10,2=0.000000
L 0.32223297 2.20658287 0.32436634 2.20491654 1 P 0 ;0,1=10,2=0.000000
L 0.32436634 2.20491654 0.32676683 2.2045 1 P 0 ;0,1=10,2=0.000000
L 0.32676683 2.2045 0.3289002 2.20491654 1 P 0 ;0,1=10,2=0.000000
L 0.3289002 2.20491654 0.33103356 2.20699941 1 P 0 ;0,1=10,2=0.000000
L 0.33103356 2.20699941 0.33236663 2.20949961 1 P 0 ;0,1=10,2=0.000000
L 0.33236663 2.20949961 0.33263317 2.2119999 1 P 0 ;0,1=10,2=0.000000
L 0.33263317 2.2119999 0.3321 2.21491594 1 P 0 ;0,1=10,2=0.000000
L 0.3321 2.21491594 0.33023327 2.21699961 1 P 0 ;0,1=10,2=0.000000
L 0.33023327 2.21699961 0.32836644 2.21783346 1 P 0 ;0,1=10,2=0.000000
L 0.32836644 2.21783346 0.32596654 2.21783346 1 P 0 ;0,1=10,2=0.000000
L 0.32836644 2.21783346 0.32996663 2.21908327 1 P 0 ;0,1=10,2=0.000000
L 0.32996663 2.21908327 0.3313001 2.22116614 1 P 0 ;0,1=10,2=0.000000
L 0.3313001 2.22116614 0.33183337 2.22366634 1 P 0 ;0,1=10,2=0.000000
L 0.33183337 2.22366634 0.3313001 2.22616654 1 P 0 ;0,1=10,2=0.000000
L 0.3313001 2.22616654 0.32996663 2.22824941 1 P 0 ;0,1=10,2=0.000000
L 0.32996663 2.22824941 0.32756663 2.2295 1 P 0 ;0,1=10,2=0.000000
L 0.32756663 2.2295 0.32516663 2.22908337 1 P 0 ;0,1=10,2=0.000000
L 0.32516663 2.22908337 0.32276663 2.22741634 1 P 0 ;0,1=10,2=0.000000
L 0.31993317 2.04833337 0.32153327 2.05083287 1 P 0 ;0,1=4,2=0.000000
L 0.32153327 2.05083287 0.3234 2.05208337 1 P 0 ;0,1=4,2=0.000000
L 0.3234 2.05208337 0.32553337 2.0525 1 P 0 ;0,1=4,2=0.000000
L 0.32553337 2.0525 0.3282 2.05166683 1 P 0 ;0,1=4,2=0.000000
L 0.3282 2.05166683 0.33006673 2.04958317 1 P 0 ;0,1=4,2=0.000000
L 0.33006673 2.04958317 0.3306 2.04708366 1 P 0 ;0,1=4,2=0.000000
L 0.3306 2.04708366 0.33033337 2.04458268 1 P 0 ;0,1=4,2=0.000000
L 0.33033337 2.04458268 0.32926644 2.0424998 1 P 0 ;0,1=4,2=0.000000
L 0.32926644 2.0424998 0.32393327 2.03833327 1 P 0 ;0,1=4,2=0.000000
L 0.32393327 2.03833327 0.32153327 2.03541644 1 P 0 ;0,1=4,2=0.000000
L 0.32153327 2.03541644 0.31993317 2.03124911 1 P 0 ;0,1=4,2=0.000000
L 0.31993317 2.03124911 0.3193999 2.0275 1 P 0 ;0,1=4,2=0.000000
L 0.3193999 2.0275 0.3306 2.0275 1 P 0 ;0,1=4,2=0.000000
L 0.32208376 2.13243327 0.32053317 2.13013307 1 P 0 ;0,1=643,2=270.000000
L 0.32053317 2.13013307 0.3195 2.1274503 1 P 0 ;0,1=643,2=270.000000
L 0.3195 2.1274503 0.3195 2.12438356 1 P 0 ;0,1=643,2=270.000000
L 0.3195 2.12438356 0.32105069 2.12093287 1 P 0 ;0,1=643,2=270.000000
L 0.32105069 2.12093287 0.32363346 2.1182501 1 P 0 ;0,1=643,2=270.000000
L 0.32363346 2.1182501 0.32673376 2.11633317 1 P 0 ;0,1=643,2=270.000000
L 0.32673376 2.11633317 0.3319002 2.11479951 1 P 0 ;0,1=643,2=270.000000
L 0.3319002 2.11479951 0.3365502 2.11441624 1 P 0 ;0,1=643,2=270.000000
L 0.3365502 2.11441624 0.3412001 2.11518337 1 P 0 ;0,1=643,2=270.000000
L 0.3412001 2.11518337 0.34430039 2.11633317 1 P 0 ;0,1=643,2=270.000000
L 0.34430039 2.11633317 0.34740069 2.11863337 1 P 0 ;0,1=643,2=270.000000
L 0.34740069 2.11863337 0.34946693 2.12131683 1 P 0 ;0,1=643,2=270.000000
L 0.34946693 2.12131683 0.3505 2.12399961 1 P 0 ;0,1=643,2=270.000000
L 0.3505 2.12399961 0.3505 2.12668307 1 P 0 ;0,1=643,2=270.000000
L 0.3505 2.12668307 0.34946693 2.12936654 1 P 0 ;0,1=643,2=270.000000
L 0.34946693 2.12936654 0.34791722 2.13166673 1 P 0 ;0,1=643,2=270.000000
L 0.34791722 2.13166673 0.34585108 2.13358366 1 P 0 ;0,1=643,2=270.000000
L 0.3505 2.14733317 0.3195 2.14733317 1 P 0 ;0,1=643,2=270.000000
L 0.3195 2.14733317 0.3195 2.15691654 1 P 0 ;0,1=643,2=270.000000
L 0.3195 2.15691654 0.32105069 2.15998327 1 P 0 ;0,1=643,2=270.000000
L 0.32105069 2.15998327 0.32311693 2.1619002 1 P 0 ;0,1=643,2=270.000000
L 0.32311693 2.1619002 0.3272503 2.16266673 1 P 0 ;0,1=643,2=270.000000
L 0.3272503 2.16266673 0.33138366 2.1619002 1 P 0 ;0,1=643,2=270.000000
L 0.33138366 2.1619002 0.33396644 2.1596 1 P 0 ;0,1=643,2=270.000000
L 0.33396644 2.1596 0.33551713 2.15691654 1 P 0 ;0,1=643,2=270.000000
L 0.33551713 2.15691654 0.33551713 2.14733317 1 P 0 ;0,1=643,2=270.000000
L 0.33551713 2.15691654 0.3505 2.16266673 1 P 0 ;0,1=643,2=270.000000
L 0.3505 2.1906 0.3195 2.1906 1 P 0 ;0,1=643,2=270.000000
L 0.3195 2.1906 0.34171673 2.17641624 1 P 0 ;0,1=643,2=270.000000
L 0.34171673 2.17641624 0.34171673 2.19558366 1 P 0 ;0,1=643,2=270.000000
L 0.1532 2.1825 0.1532 2.2075 1 P 0 ;0,1=11,2=0.000000
L 0.1532 2.2075 0.14333297 2.18958327 1 P 0 ;0,1=11,2=0.000000
L 0.14333297 2.18958327 0.15666693 2.18958327 1 P 0 ;0,1=11,2=0.000000
L 1.33581004 3.95196004 1.33581004 3.81803996 1 P 0 
L 1.17418996 3.95196004 1.33581004 3.95196004 1 P 0 
L 1.17418996 3.81803996 1.17418996 3.95196004 1 P 0 
L 1.33581004 3.81803996 1.17418996 3.81803996 1 P 0 
S P 0
OB 1.32583996063 3.98 I
OC 1.32583996063 3.98 1.31083996063 3.98 Y
OE
SE
L 1.3646 3.7895 1.3646 3.8205 1 P 0 ;0,1=11,2=0.000000
L 1.3646 3.8205 1.35041624 3.79828327 1 P 0 ;0,1=11,2=0.000000
L 1.35041624 3.79828327 1.36958366 3.79828327 1 P 0 ;0,1=11,2=0.000000
L 1.14271644 4.00033346 1.14501663 4.00343278 1 P 0 ;0,1=4,2=0.000000
L 1.14501663 4.00343278 1.1477001 4.00498337 1 P 0 ;0,1=4,2=0.000000
L 1.1477001 4.00498337 1.15076683 4.0055 1 P 0 ;0,1=4,2=0.000000
L 1.15076683 4.0055 1.1546 4.00446683 1 P 0 ;0,1=4,2=0.000000
L 1.1546 4.00446683 1.15728346 4.00188307 1 P 0 ;0,1=4,2=0.000000
L 1.15728346 4.00188307 1.15805 3.99878376 1 P 0 ;0,1=4,2=0.000000
L 1.15805 3.99878376 1.15766673 3.99568258 1 P 0 ;0,1=4,2=0.000000
L 1.15766673 3.99568258 1.15613307 3.9930998 1 P 0 ;0,1=4,2=0.000000
L 1.15613307 3.9930998 1.14846663 3.98793327 1 P 0 ;0,1=4,2=0.000000
L 1.14846663 3.98793327 1.14501663 3.98431644 1 P 0 ;0,1=4,2=0.000000
L 1.14501663 3.98431644 1.14271644 3.97914892 1 P 0 ;0,1=4,2=0.000000
L 1.14271644 3.97914892 1.1419499 3.9745 1 P 0 ;0,1=4,2=0.000000
L 1.1419499 3.9745 1.15805 3.9745 1 P 0 ;0,1=4,2=0.000000
L 1.19449961 3.9945 1.19449961 4.0084498 1 P 0 ;0,1=644,2=0.000000
L 1.19449961 4.0084498 1.18683317 4.0255 1 P 0 ;0,1=644,2=0.000000
L 1.20216673 4.0255 1.19449961 4.0084498 1 P 0 ;0,1=644,2=0.000000
L 1.21821644 4.02033346 1.22051663 4.02343278 1 P 0 ;0,1=644,2=0.000000
L 1.22051663 4.02343278 1.2232001 4.02498337 1 P 0 ;0,1=644,2=0.000000
L 1.2232001 4.02498337 1.22626683 4.0255 1 P 0 ;0,1=644,2=0.000000
L 1.22626683 4.0255 1.2301 4.02446683 1 P 0 ;0,1=644,2=0.000000
L 1.2301 4.02446683 1.23278346 4.02188307 1 P 0 ;0,1=644,2=0.000000
L 1.23278346 4.02188307 1.23355 4.01878376 1 P 0 ;0,1=644,2=0.000000
L 1.23355 4.01878376 1.23316673 4.01568258 1 P 0 ;0,1=644,2=0.000000
L 1.23316673 4.01568258 1.23163307 4.0130998 1 P 0 ;0,1=644,2=0.000000
L 1.23163307 4.0130998 1.22396663 4.00793327 1 P 0 ;0,1=644,2=0.000000
L 1.22396663 4.00793327 1.22051663 4.00431644 1 P 0 ;0,1=644,2=0.000000
L 1.22051663 4.00431644 1.21821644 3.99914892 1 P 0 ;0,1=644,2=0.000000
L 1.21821644 3.99914892 1.2174499 3.9945 1 P 0 ;0,1=644,2=0.000000
L 1.2174499 3.9945 1.23355 3.9945 1 P 0 ;0,1=644,2=0.000000
L 1.14656663 3.79569961 1.14886614 3.79208278 1 P 0 ;0,1=10,2=0.000000
L 1.14886614 3.79208278 1.15193287 3.79001654 1 P 0 ;0,1=10,2=0.000000
L 1.15193287 3.79001654 1.15538356 3.7895 1 P 0 ;0,1=10,2=0.000000
L 1.15538356 3.7895 1.1584503 3.79001654 1 P 0 ;0,1=10,2=0.000000
L 1.1584503 3.79001654 1.16151703 3.79259931 1 P 0 ;0,1=10,2=0.000000
L 1.16151703 3.79259931 1.16343327 3.79569961 1 P 0 ;0,1=10,2=0.000000
L 1.16343327 3.79569961 1.16381654 3.7987999 1 P 0 ;0,1=10,2=0.000000
L 1.16381654 3.7987999 1.16305 3.80241575 1 P 0 ;0,1=10,2=0.000000
L 1.16305 3.80241575 1.16036654 3.80499951 1 P 0 ;0,1=10,2=0.000000
L 1.16036654 3.80499951 1.15768307 3.80603356 1 P 0 ;0,1=10,2=0.000000
L 1.15768307 3.80603356 1.15423307 3.80603356 1 P 0 ;0,1=10,2=0.000000
L 1.15768307 3.80603356 1.15998327 3.80758317 1 P 0 ;0,1=10,2=0.000000
L 1.15998327 3.80758317 1.1619002 3.81016594 1 P 0 ;0,1=10,2=0.000000
L 1.1619002 3.81016594 1.16266673 3.81326624 1 P 0 ;0,1=10,2=0.000000
L 1.16266673 3.81326624 1.1619002 3.81636654 1 P 0 ;0,1=10,2=0.000000
L 1.1619002 3.81636654 1.15998327 3.81894931 1 P 0 ;0,1=10,2=0.000000
L 1.15998327 3.81894931 1.15653327 3.8205 1 P 0 ;0,1=10,2=0.000000
L 1.15653327 3.8205 1.15308337 3.81998337 1 P 0 ;0,1=10,2=0.000000
L 1.15308337 3.81998337 1.14963337 3.81791624 1 P 0 ;0,1=10,2=0.000000
L 2.76348996 0.5527 2.83851004 0.5527 1 P 0 
L 2.76348996 0.56291004 2.76348996 0.5527 1 P 0 
L 2.725 0.56291004 2.76348996 0.56291004 1 P 0 
L 2.725 0.64708996 2.725 0.56291004 1 P 0 
L 2.76348996 0.64708996 2.725 0.64708996 1 P 0 
L 2.76348996 0.6573 2.76348996 0.64708996 1 P 0 
L 2.83851004 0.6573 2.76348996 0.6573 1 P 0 
L 2.83851004 0.56291004 2.877 0.56291004 1 P 0 
L 2.83851004 0.5527 2.83851004 0.56291004 1 P 0 
L 2.877 0.56291004 2.877 0.64708996 1 P 0 
L 2.83851004 0.64708996 2.83851004 0.6573 1 P 0 
L 2.877 0.64708996 2.83851004 0.64708996 1 P 0 
S P 0
OB 2.714519980315 0.6347 I
OC 2.714519980315 0.6347 2.699519980315 0.6347 Y
OE
SE
L 2.69756663 0.56585965 2.69986614 0.56224282 1 P 0 ;0,1=10,2=0.000000
L 2.69986614 0.56224282 2.70293287 0.56017657 1 P 0 ;0,1=10,2=0.000000
L 2.70293287 0.56017657 2.70638356 0.55966004 1 P 0 ;0,1=10,2=0.000000
L 2.70638356 0.55966004 2.7094503 0.56017657 1 P 0 ;0,1=10,2=0.000000
L 2.7094503 0.56017657 2.71251703 0.56275935 1 P 0 ;0,1=10,2=0.000000
L 2.71251703 0.56275935 2.71443327 0.56585965 1 P 0 ;0,1=10,2=0.000000
L 2.71443327 0.56585965 2.71481654 0.56895994 1 P 0 ;0,1=10,2=0.000000
L 2.71481654 0.56895994 2.71405 0.57257579 1 P 0 ;0,1=10,2=0.000000
L 2.71405 0.57257579 2.71136654 0.57515955 1 P 0 ;0,1=10,2=0.000000
L 2.71136654 0.57515955 2.70868307 0.5761936 1 P 0 ;0,1=10,2=0.000000
L 2.70868307 0.5761936 2.70523307 0.5761936 1 P 0 ;0,1=10,2=0.000000
L 2.70868307 0.5761936 2.71098327 0.57774321 1 P 0 ;0,1=10,2=0.000000
L 2.71098327 0.57774321 2.7129002 0.58032598 1 P 0 ;0,1=10,2=0.000000
L 2.7129002 0.58032598 2.71366673 0.58342628 1 P 0 ;0,1=10,2=0.000000
L 2.71366673 0.58342628 2.7129002 0.58652657 1 P 0 ;0,1=10,2=0.000000
L 2.7129002 0.58652657 2.71098327 0.58910935 1 P 0 ;0,1=10,2=0.000000
L 2.71098327 0.58910935 2.70753327 0.59066004 1 P 0 ;0,1=10,2=0.000000
L 2.70753327 0.59066004 2.70408337 0.59014341 1 P 0 ;0,1=10,2=0.000000
L 2.70408337 0.59014341 2.70063337 0.58807628 1 P 0 ;0,1=10,2=0.000000
L 2.77206663 0.7055 2.77206663 0.68328327 1 P 0 ;0,1=645,2=0.000000
L 2.77206663 0.68328327 2.7735997 0.67863238 1 P 0 ;0,1=645,2=0.000000
L 2.7735997 0.67863238 2.77666634 0.67553307 1 P 0 ;0,1=645,2=0.000000
L 2.77666634 0.67553307 2.78049961 0.6745 1 P 0 ;0,1=645,2=0.000000
L 2.78049961 0.6745 2.78433356 0.67553307 1 P 0 ;0,1=645,2=0.000000
L 2.78433356 0.67553307 2.7874002 0.67863238 1 P 0 ;0,1=645,2=0.000000
L 2.7874002 0.67863238 2.78893327 0.68328327 1 P 0 ;0,1=645,2=0.000000
L 2.78893327 0.68328327 2.78893327 0.7055 1 P 0 ;0,1=645,2=0.000000
L 2.80306663 0.68069961 2.80536614 0.67708278 1 P 0 ;0,1=645,2=0.000000
L 2.80536614 0.67708278 2.80843287 0.67501654 1 P 0 ;0,1=645,2=0.000000
L 2.80843287 0.67501654 2.81188356 0.6745 1 P 0 ;0,1=645,2=0.000000
L 2.81188356 0.6745 2.8149503 0.67501654 1 P 0 ;0,1=645,2=0.000000
L 2.8149503 0.67501654 2.81801703 0.67759931 1 P 0 ;0,1=645,2=0.000000
L 2.81801703 0.67759931 2.81993327 0.68069961 1 P 0 ;0,1=645,2=0.000000
L 2.81993327 0.68069961 2.82031654 0.6837999 1 P 0 ;0,1=645,2=0.000000
L 2.82031654 0.6837999 2.81955 0.68741575 1 P 0 ;0,1=645,2=0.000000
L 2.81955 0.68741575 2.81686654 0.68999951 1 P 0 ;0,1=645,2=0.000000
L 2.81686654 0.68999951 2.81418307 0.69103356 1 P 0 ;0,1=645,2=0.000000
L 2.81418307 0.69103356 2.81073307 0.69103356 1 P 0 ;0,1=645,2=0.000000
L 2.81418307 0.69103356 2.81648327 0.69258317 1 P 0 ;0,1=645,2=0.000000
L 2.81648327 0.69258317 2.8184002 0.69516594 1 P 0 ;0,1=645,2=0.000000
L 2.8184002 0.69516594 2.81916673 0.69826624 1 P 0 ;0,1=645,2=0.000000
L 2.81916673 0.69826624 2.8184002 0.70136654 1 P 0 ;0,1=645,2=0.000000
L 2.8184002 0.70136654 2.81648327 0.70394931 1 P 0 ;0,1=645,2=0.000000
L 2.81648327 0.70394931 2.81303327 0.7055 1 P 0 ;0,1=645,2=0.000000
L 2.81303327 0.7055 2.80958337 0.70498337 1 P 0 ;0,1=645,2=0.000000
L 2.80958337 0.70498337 2.80613337 0.70291624 1 P 0 ;0,1=645,2=0.000000
L 2.90178002 0.56055 2.90178002 0.59155 1 P 0 ;0,1=11,2=0.000000
L 2.90178002 0.59155 2.88759626 0.56933327 1 P 0 ;0,1=11,2=0.000000
L 2.88759626 0.56933327 2.90676368 0.56933327 1 P 0 ;0,1=11,2=0.000000
L 2.88756663 0.6193189 2.88986614 0.61673612 1 P 0 ;0,1=20,2=0.000000
L 2.88986614 0.61673612 2.89254961 0.61518652 1 P 0 ;0,1=20,2=0.000000
L 2.89254961 0.61518652 2.89599961 0.61466998 1 P 0 ;0,1=20,2=0.000000
L 2.89599961 0.61466998 2.8994503 0.61570305 1 P 0 ;0,1=20,2=0.000000
L 2.8994503 0.61570305 2.90213307 0.61776929 1 P 0 ;0,1=20,2=0.000000
L 2.90213307 0.61776929 2.90405 0.62138612 1 P 0 ;0,1=20,2=0.000000
L 2.90405 0.62138612 2.90443327 0.62551949 1 P 0 ;0,1=20,2=0.000000
L 2.90443327 0.62551949 2.90366673 0.62965285 1 P 0 ;0,1=20,2=0.000000
L 2.90366673 0.62965285 2.9017498 0.63223661 1 P 0 ;0,1=20,2=0.000000
L 2.9017498 0.63223661 2.89906634 0.63430285 1 P 0 ;0,1=20,2=0.000000
L 2.89906634 0.63430285 2.89638356 0.63481939 1 P 0 ;0,1=20,2=0.000000
L 2.89638356 0.63481939 2.8937001 0.63430285 1 P 0 ;0,1=20,2=0.000000
L 2.8937001 0.63430285 2.8902501 0.63223661 1 P 0 ;0,1=20,2=0.000000
L 2.8902501 0.63223661 2.8913999 0.64566998 1 P 0 ;0,1=20,2=0.000000
L 2.8913999 0.64566998 2.9017498 0.64566998 1 P 0 ;0,1=20,2=0.000000
L 3.7524 2.6115 3.7524 2.66 1 P 0 
L 3.76208996 2.6115 3.7524 2.6115 1 P 0 
L 3.76208996 2.5285 3.76208996 2.6115 1 P 0 
L 3.7524 2.5285 3.76208996 2.5285 1 P 0 
L 3.7524 2.48 3.7524 2.5285 1 P 0 
L 3.62791004 2.5285 3.6376 2.5285 1 P 0 
L 3.62791004 2.6115 3.62791004 2.5285 1 P 0 
L 3.6376 2.6115 3.62791004 2.6115 1 P 0 
L 3.6376 2.66 3.6376 2.6115 1 P 0 
L 3.7524 2.66 3.6376 2.66 1 P 0 
L 3.6376 2.5285 3.6376 2.48 1 P 0 
L 3.6376 2.48 3.7524 2.48 1 P 0 
S P 0
OB 3.785 2.66 I
OC 3.785 2.66 3.77 2.66 Y
OE
SE
L 3.80056663 2.6355 3.80056663 2.61328327 1 P 0 ;0,1=646,2=0.000000
L 3.80056663 2.61328327 3.8020997 2.60863238 1 P 0 ;0,1=646,2=0.000000
L 3.8020997 2.60863238 3.80516634 2.60553307 1 P 0 ;0,1=646,2=0.000000
L 3.80516634 2.60553307 3.80899961 2.6045 1 P 0 ;0,1=646,2=0.000000
L 3.80899961 2.6045 3.81283356 2.60553307 1 P 0 ;0,1=646,2=0.000000
L 3.81283356 2.60553307 3.8159002 2.60863238 1 P 0 ;0,1=646,2=0.000000
L 3.8159002 2.60863238 3.81743327 2.61328327 1 P 0 ;0,1=646,2=0.000000
L 3.81743327 2.61328327 3.81743327 2.6355 1 P 0 ;0,1=646,2=0.000000
L 3.83156663 2.61069961 3.83386614 2.60708278 1 P 0 ;0,1=646,2=0.000000
L 3.83386614 2.60708278 3.83693287 2.60501654 1 P 0 ;0,1=646,2=0.000000
L 3.83693287 2.60501654 3.84038356 2.6045 1 P 0 ;0,1=646,2=0.000000
L 3.84038356 2.6045 3.8434503 2.60501654 1 P 0 ;0,1=646,2=0.000000
L 3.8434503 2.60501654 3.84651703 2.60759931 1 P 0 ;0,1=646,2=0.000000
L 3.84651703 2.60759931 3.84843327 2.61069961 1 P 0 ;0,1=646,2=0.000000
L 3.84843327 2.61069961 3.84881654 2.6137999 1 P 0 ;0,1=646,2=0.000000
L 3.84881654 2.6137999 3.84805 2.61741575 1 P 0 ;0,1=646,2=0.000000
L 3.84805 2.61741575 3.84536654 2.61999951 1 P 0 ;0,1=646,2=0.000000
L 3.84536654 2.61999951 3.84268307 2.62103356 1 P 0 ;0,1=646,2=0.000000
L 3.84268307 2.62103356 3.83923307 2.62103356 1 P 0 ;0,1=646,2=0.000000
L 3.84268307 2.62103356 3.84498327 2.62258317 1 P 0 ;0,1=646,2=0.000000
L 3.84498327 2.62258317 3.8469002 2.62516594 1 P 0 ;0,1=646,2=0.000000
L 3.8469002 2.62516594 3.84766673 2.62826624 1 P 0 ;0,1=646,2=0.000000
L 3.84766673 2.62826624 3.8469002 2.63136654 1 P 0 ;0,1=646,2=0.000000
L 3.8469002 2.63136654 3.84498327 2.63394931 1 P 0 ;0,1=646,2=0.000000
L 3.84498327 2.63394931 3.84153327 2.6355 1 P 0 ;0,1=646,2=0.000000
L 3.84153327 2.6355 3.83808337 2.63498337 1 P 0 ;0,1=646,2=0.000000
L 3.83808337 2.63498337 3.83463337 2.63291624 1 P 0 ;0,1=646,2=0.000000
L 3.8756 2.6045 3.8756 2.6355 1 P 0 ;0,1=646,2=0.000000
L 3.8756 2.6355 3.86141624 2.61328327 1 P 0 ;0,1=646,2=0.000000
L 3.86141624 2.61328327 3.88058366 2.61328327 1 P 0 ;0,1=646,2=0.000000
L 3.76493317 2.46291594 3.7667999 2.46583346 1 P 0 ;0,1=8,2=0.000000
L 3.7667999 2.46583346 3.7684 2.4674998 1 P 0 ;0,1=8,2=0.000000
L 3.7684 2.4674998 3.77053337 2.46833297 1 P 0 ;0,1=8,2=0.000000
L 3.77053337 2.46833297 3.7724002 2.4674998 1 P 0 ;0,1=8,2=0.000000
L 3.7724002 2.4674998 3.77373327 2.46583346 1 P 0 ;0,1=8,2=0.000000
L 3.77373327 2.46583346 3.7748001 2.46333327 1 P 0 ;0,1=8,2=0.000000
L 3.7748001 2.46333327 3.77506673 2.46041644 1 P 0 ;0,1=8,2=0.000000
L 3.77506673 2.46041644 3.7748001 2.45791624 1 P 0 ;0,1=8,2=0.000000
L 3.7748001 2.45791624 3.77373327 2.45541604 1 P 0 ;0,1=8,2=0.000000
L 3.77373327 2.45541604 3.77213307 2.45333307 1 P 0 ;0,1=8,2=0.000000
L 3.77213307 2.45333307 3.77026683 2.4525 1 P 0 ;0,1=8,2=0.000000
L 3.77026683 2.4525 3.76813346 2.45333307 1 P 0 ;0,1=8,2=0.000000
L 3.76813346 2.45333307 3.76626663 2.45583258 1 P 0 ;0,1=8,2=0.000000
L 3.76626663 2.45583258 3.7651998 2.45958327 1 P 0 ;0,1=8,2=0.000000
L 3.7651998 2.45958327 3.76493317 2.4637498 1 P 0 ;0,1=8,2=0.000000
L 3.76493317 2.4637498 3.76546634 2.46916614 1 P 0 ;0,1=8,2=0.000000
L 3.76546634 2.46916614 3.76626663 2.47208366 1 P 0 ;0,1=8,2=0.000000
L 3.76626663 2.47208366 3.7675997 2.4749997 1 P 0 ;0,1=8,2=0.000000
L 3.7675997 2.4749997 3.76946654 2.47708337 1 P 0 ;0,1=8,2=0.000000
L 3.76946654 2.47708337 3.77133327 2.4775 1 P 0 ;0,1=8,2=0.000000
L 3.77133327 2.4775 3.7732 2.47666683 1 P 0 ;0,1=8,2=0.000000
L 3.7732 2.47666683 3.77453356 2.47458317 1 P 0 ;0,1=8,2=0.000000
L 3.60913327 2.65249961 3.61073297 2.64958287 1 P 0 ;0,1=10,2=0.000000
L 3.61073297 2.64958287 3.61286634 2.64791654 1 P 0 ;0,1=10,2=0.000000
L 3.61286634 2.64791654 3.61526683 2.6475 1 P 0 ;0,1=10,2=0.000000
L 3.61526683 2.6475 3.6174002 2.64791654 1 P 0 ;0,1=10,2=0.000000
L 3.6174002 2.64791654 3.61953356 2.64999941 1 P 0 ;0,1=10,2=0.000000
L 3.61953356 2.64999941 3.62086663 2.65249961 1 P 0 ;0,1=10,2=0.000000
L 3.62086663 2.65249961 3.62113317 2.6549999 1 P 0 ;0,1=10,2=0.000000
L 3.62113317 2.6549999 3.6206 2.65791594 1 P 0 ;0,1=10,2=0.000000
L 3.6206 2.65791594 3.61873327 2.65999961 1 P 0 ;0,1=10,2=0.000000
L 3.61873327 2.65999961 3.61686644 2.66083346 1 P 0 ;0,1=10,2=0.000000
L 3.61686644 2.66083346 3.61446654 2.66083346 1 P 0 ;0,1=10,2=0.000000
L 3.61686644 2.66083346 3.61846663 2.66208327 1 P 0 ;0,1=10,2=0.000000
L 3.61846663 2.66208327 3.6198001 2.66416614 1 P 0 ;0,1=10,2=0.000000
L 3.6198001 2.66416614 3.62033337 2.66666634 1 P 0 ;0,1=10,2=0.000000
L 3.62033337 2.66666634 3.6198001 2.66916654 1 P 0 ;0,1=10,2=0.000000
L 3.6198001 2.66916654 3.61846663 2.67124941 1 P 0 ;0,1=10,2=0.000000
L 3.61846663 2.67124941 3.61606663 2.6725 1 P 0 ;0,1=10,2=0.000000
L 3.61606663 2.6725 3.61366663 2.67208337 1 P 0 ;0,1=10,2=0.000000
L 3.61366663 2.67208337 3.61126663 2.67041634 1 P 0 ;0,1=10,2=0.000000
L 3.6382 2.4395 3.6382 2.4645 1 P 0 ;0,1=11,2=0.000000
L 3.6382 2.4645 3.62833297 2.44658327 1 P 0 ;0,1=11,2=0.000000
L 3.62833297 2.44658327 3.64166693 2.44658327 1 P 0 ;0,1=11,2=0.000000
L 0.7774 3.4085 0.78708996 3.4085 1 P 0 
L 0.78708996 3.4085 0.78708996 3.4915 1 P 0 
L 0.78708996 3.4915 0.7774 3.4915 1 P 0 
L 0.7774 3.4915 0.7774 3.54 1 P 0 
L 0.7774 3.36 0.7774 3.4085 1 P 0 
L 0.7774 3.54 0.6626 3.54 1 P 0 
L 0.6626 3.54 0.6626 3.4915 1 P 0 
L 0.6626 3.4915 0.65291004 3.4915 1 P 0 
L 0.65291004 3.4915 0.65291004 3.4085 1 P 0 
L 0.65291004 3.4085 0.6626 3.4085 1 P 0 
L 0.6626 3.4085 0.6626 3.36 1 P 0 
L 0.6626 3.36 0.7774 3.36 1 P 0 
S P 0
OB 0.693 3.336 I
OC 0.693 3.336 0.678 3.336 Y
OE
SE
L 0.8032 3.5475 0.8032 3.5725 1 P 0 ;0,1=11,2=0.000000
L 0.8032 3.5725 0.79333297 3.55458327 1 P 0 ;0,1=11,2=0.000000
L 0.79333297 3.55458327 0.80666693 3.55458327 1 P 0 ;0,1=11,2=0.000000
L 0.79913327 3.36249961 0.80073297 3.35958287 1 P 0 ;0,1=10,2=0.000000
L 0.80073297 3.35958287 0.80286634 3.35791654 1 P 0 ;0,1=10,2=0.000000
L 0.80286634 3.35791654 0.80526683 3.3575 1 P 0 ;0,1=10,2=0.000000
L 0.80526683 3.3575 0.8074002 3.35791654 1 P 0 ;0,1=10,2=0.000000
L 0.8074002 3.35791654 0.80953356 3.35999941 1 P 0 ;0,1=10,2=0.000000
L 0.80953356 3.35999941 0.81086663 3.36249961 1 P 0 ;0,1=10,2=0.000000
L 0.81086663 3.36249961 0.81113317 3.3649999 1 P 0 ;0,1=10,2=0.000000
L 0.81113317 3.3649999 0.8106 3.36791594 1 P 0 ;0,1=10,2=0.000000
L 0.8106 3.36791594 0.80873327 3.36999961 1 P 0 ;0,1=10,2=0.000000
L 0.80873327 3.36999961 0.80686644 3.37083346 1 P 0 ;0,1=10,2=0.000000
L 0.80686644 3.37083346 0.80446654 3.37083346 1 P 0 ;0,1=10,2=0.000000
L 0.80686644 3.37083346 0.80846663 3.37208327 1 P 0 ;0,1=10,2=0.000000
L 0.80846663 3.37208327 0.8098001 3.37416614 1 P 0 ;0,1=10,2=0.000000
L 0.8098001 3.37416614 0.81033337 3.37666634 1 P 0 ;0,1=10,2=0.000000
L 0.81033337 3.37666634 0.8098001 3.37916654 1 P 0 ;0,1=10,2=0.000000
L 0.8098001 3.37916654 0.80846663 3.38124941 1 P 0 ;0,1=10,2=0.000000
L 0.80846663 3.38124941 0.80606663 3.3825 1 P 0 ;0,1=10,2=0.000000
L 0.80606663 3.3825 0.80366663 3.38208337 1 P 0 ;0,1=10,2=0.000000
L 0.80366663 3.38208337 0.80126663 3.38041634 1 P 0 ;0,1=10,2=0.000000
L 0.64544321 3.51098593 0.64730994 3.51390344 1 P 0 ;0,1=8,2=0.000000
L 0.64730994 3.51390344 0.64891004 3.51556978 1 P 0 ;0,1=8,2=0.000000
L 0.64891004 3.51556978 0.65104341 3.51640295 1 P 0 ;0,1=8,2=0.000000
L 0.65104341 3.51640295 0.65291024 3.51556978 1 P 0 ;0,1=8,2=0.000000
L 0.65291024 3.51556978 0.65424331 3.51390344 1 P 0 ;0,1=8,2=0.000000
L 0.65424331 3.51390344 0.65531014 3.51140325 1 P 0 ;0,1=8,2=0.000000
L 0.65531014 3.51140325 0.65557677 3.50848642 1 P 0 ;0,1=8,2=0.000000
L 0.65557677 3.50848642 0.65531014 3.50598622 1 P 0 ;0,1=8,2=0.000000
L 0.65531014 3.50598622 0.65424331 3.50348602 1 P 0 ;0,1=8,2=0.000000
L 0.65424331 3.50348602 0.65264311 3.50140305 1 P 0 ;0,1=8,2=0.000000
L 0.65264311 3.50140305 0.65077687 3.50056998 1 P 0 ;0,1=8,2=0.000000
L 0.65077687 3.50056998 0.6486435 3.50140305 1 P 0 ;0,1=8,2=0.000000
L 0.6486435 3.50140305 0.64677667 3.50390256 1 P 0 ;0,1=8,2=0.000000
L 0.64677667 3.50390256 0.64570984 3.50765325 1 P 0 ;0,1=8,2=0.000000
L 0.64570984 3.50765325 0.64544321 3.51181978 1 P 0 ;0,1=8,2=0.000000
L 0.64544321 3.51181978 0.64597638 3.51723612 1 P 0 ;0,1=8,2=0.000000
L 0.64597638 3.51723612 0.64677667 3.52015364 1 P 0 ;0,1=8,2=0.000000
L 0.64677667 3.52015364 0.64810974 3.52306969 1 P 0 ;0,1=8,2=0.000000
L 0.64810974 3.52306969 0.64997657 3.52515335 1 P 0 ;0,1=8,2=0.000000
L 0.64997657 3.52515335 0.65184331 3.52556998 1 P 0 ;0,1=8,2=0.000000
L 0.65184331 3.52556998 0.65371004 3.52473681 1 P 0 ;0,1=8,2=0.000000
L 0.65371004 3.52473681 0.6550436 3.52265315 1 P 0 ;0,1=8,2=0.000000
L 0.6045 3.35056663 0.62671673 3.35056663 1 P 0 ;0,1=647,2=270.000000
L 0.62671673 3.35056663 0.63136762 3.3520997 1 P 0 ;0,1=647,2=270.000000
L 0.63136762 3.3520997 0.63446693 3.35516634 1 P 0 ;0,1=647,2=270.000000
L 0.63446693 3.35516634 0.6355 3.35899961 1 P 0 ;0,1=647,2=270.000000
L 0.6355 3.35899961 0.63446693 3.36283356 1 P 0 ;0,1=647,2=270.000000
L 0.63446693 3.36283356 0.63136762 3.3659002 1 P 0 ;0,1=647,2=270.000000
L 0.63136762 3.3659002 0.62671673 3.36743327 1 P 0 ;0,1=647,2=270.000000
L 0.62671673 3.36743327 0.6045 3.36743327 1 P 0 ;0,1=647,2=270.000000
L 0.6355 3.38999961 0.6045 3.38999961 1 P 0 ;0,1=647,2=270.000000
L 0.6045 3.38999961 0.6106997 3.3853999 1 P 0 ;0,1=647,2=270.000000
L 0.6355 3.3853999 0.6355 3.39459931 1 P 0 ;0,1=647,2=270.000000
L 0.6355 3.42023307 0.62878386 3.42099961 1 P 0 ;0,1=647,2=270.000000
L 0.62878386 3.42099961 0.62310079 3.4221501 1 P 0 ;0,1=647,2=270.000000
L 0.62310079 3.4221501 0.61793337 3.42368307 1 P 0 ;0,1=647,2=270.000000
L 0.61793337 3.42368307 0.6122503 3.4256 1 P 0 ;0,1=647,2=270.000000
L 0.6122503 3.4256 0.6045 3.42866673 1 P 0 ;0,1=647,2=270.000000
L 0.6045 3.42866673 0.6045 3.41333317 1 P 0 ;0,1=647,2=270.000000
L 6.32728996 2.16833996 6.32728996 2.21683996 1 P 0 
L 6.32728996 2.21683996 6.33698002 2.21683996 1 P 0 
L 6.33698002 2.21683996 6.33698002 2.29983996 1 P 0 
L 6.33698002 2.29983996 6.32728996 2.29983996 1 P 0 
L 6.32728996 2.29983996 6.32728996 2.34833996 1 P 0 
L 6.32728996 2.34833996 6.21248996 2.34833996 1 P 0 
L 6.21248996 2.16833996 6.32728996 2.16833996 1 P 0 
L 6.21248996 2.34833996 6.21248996 2.29983996 1 P 0 
L 6.21248996 2.29983996 6.2028 2.29983996 1 P 0 
L 6.2028 2.29983996 6.2028 2.21683996 1 P 0 
L 6.2028 2.21683996 6.21248996 2.21683996 1 P 0 
L 6.21248996 2.21683996 6.21248996 2.16833996 1 P 0 
S P 0
OB 6.361 2.33973996063 I
OC 6.361 2.33973996063 6.346 2.33973996063 Y
OE
SE
L 6.30771644 2.13741575 6.3103999 2.14103356 1 P 0 ;0,1=8,2=0.000000
L 6.3103999 2.14103356 6.3127001 2.1430998 1 P 0 ;0,1=8,2=0.000000
L 6.3127001 2.1430998 6.31576683 2.14413287 1 P 0 ;0,1=8,2=0.000000
L 6.31576683 2.14413287 6.3184503 2.1430998 1 P 0 ;0,1=8,2=0.000000
L 6.3184503 2.1430998 6.32036654 2.14103356 1 P 0 ;0,1=8,2=0.000000
L 6.32036654 2.14103356 6.3219002 2.13793327 1 P 0 ;0,1=8,2=0.000000
L 6.3219002 2.13793327 6.32228346 2.13431644 1 P 0 ;0,1=8,2=0.000000
L 6.32228346 2.13431644 6.3219002 2.13121614 1 P 0 ;0,1=8,2=0.000000
L 6.3219002 2.13121614 6.32036654 2.12811585 1 P 0 ;0,1=8,2=0.000000
L 6.32036654 2.12811585 6.31806634 2.12553307 1 P 0 ;0,1=8,2=0.000000
L 6.31806634 2.12553307 6.31538356 2.1245 1 P 0 ;0,1=8,2=0.000000
L 6.31538356 2.1245 6.31231683 2.12553307 1 P 0 ;0,1=8,2=0.000000
L 6.31231683 2.12553307 6.30963337 2.12863238 1 P 0 ;0,1=8,2=0.000000
L 6.30963337 2.12863238 6.3080997 2.13328327 1 P 0 ;0,1=8,2=0.000000
L 6.3080997 2.13328327 6.30771644 2.1384498 1 P 0 ;0,1=8,2=0.000000
L 6.30771644 2.1384498 6.30848287 2.14516594 1 P 0 ;0,1=8,2=0.000000
L 6.30848287 2.14516594 6.30963337 2.14878376 1 P 0 ;0,1=8,2=0.000000
L 6.30963337 2.14878376 6.31154961 2.1523997 1 P 0 ;0,1=8,2=0.000000
L 6.31154961 2.1523997 6.31423307 2.15498337 1 P 0 ;0,1=8,2=0.000000
L 6.31423307 2.15498337 6.31691654 2.1555 1 P 0 ;0,1=8,2=0.000000
L 6.31691654 2.1555 6.3196 2.15446683 1 P 0 ;0,1=8,2=0.000000
L 6.3196 2.15446683 6.32151703 2.15188307 1 P 0 ;0,1=8,2=0.000000
L 6.25106663 2.4255 6.25106663 2.40328327 1 P 0 ;0,1=648,2=0.000000
L 6.25106663 2.40328327 6.2525997 2.39863238 1 P 0 ;0,1=648,2=0.000000
L 6.2525997 2.39863238 6.25566634 2.39553307 1 P 0 ;0,1=648,2=0.000000
L 6.25566634 2.39553307 6.25949961 2.3945 1 P 0 ;0,1=648,2=0.000000
L 6.25949961 2.3945 6.26333356 2.39553307 1 P 0 ;0,1=648,2=0.000000
L 6.26333356 2.39553307 6.2664002 2.39863238 1 P 0 ;0,1=648,2=0.000000
L 6.2664002 2.39863238 6.26793327 2.40328327 1 P 0 ;0,1=648,2=0.000000
L 6.26793327 2.40328327 6.26793327 2.4255 1 P 0 ;0,1=648,2=0.000000
L 6.28398287 2.39811585 6.28666634 2.39553307 1 P 0 ;0,1=648,2=0.000000
L 6.28666634 2.39553307 6.28973307 2.3945 1 P 0 ;0,1=648,2=0.000000
L 6.28973307 2.3945 6.2927998 2.39553307 1 P 0 ;0,1=648,2=0.000000
L 6.2927998 2.39553307 6.29548327 2.39863238 1 P 0 ;0,1=648,2=0.000000
L 6.29548327 2.39863238 6.2974002 2.40328327 1 P 0 ;0,1=648,2=0.000000
L 6.2974002 2.40328327 6.29816673 2.40793327 1 P 0 ;0,1=648,2=0.000000
L 6.29816673 2.40793327 6.29816673 2.41361634 1 P 0 ;0,1=648,2=0.000000
L 6.29816673 2.41361634 6.2974002 2.41826624 1 P 0 ;0,1=648,2=0.000000
L 6.2974002 2.41826624 6.29548327 2.4223997 1 P 0 ;0,1=648,2=0.000000
L 6.29548327 2.4223997 6.29318307 2.42446683 1 P 0 ;0,1=648,2=0.000000
L 6.29318307 2.42446683 6.29049961 2.4255 1 P 0 ;0,1=648,2=0.000000
L 6.29049961 2.4255 6.28743287 2.42446683 1 P 0 ;0,1=648,2=0.000000
L 6.28743287 2.42446683 6.28513337 2.4223997 1 P 0 ;0,1=648,2=0.000000
L 6.28513337 2.4223997 6.2835997 2.4193003 1 P 0 ;0,1=648,2=0.000000
L 6.2835997 2.4193003 6.28283317 2.41516594 1 P 0 ;0,1=648,2=0.000000
L 6.28283317 2.41516594 6.2835997 2.4115501 1 P 0 ;0,1=648,2=0.000000
L 6.2835997 2.4115501 6.28551663 2.40793327 1 P 0 ;0,1=648,2=0.000000
L 6.28551663 2.40793327 6.28781683 2.40586604 1 P 0 ;0,1=648,2=0.000000
L 6.28781683 2.40586604 6.29049961 2.40534951 1 P 0 ;0,1=648,2=0.000000
L 6.29049961 2.40534951 6.29356634 2.40638268 1 P 0 ;0,1=648,2=0.000000
L 6.29356634 2.40638268 6.29586654 2.40896634 1 P 0 ;0,1=648,2=0.000000
L 6.29586654 2.40896634 6.29816673 2.41361634 1 P 0 ;0,1=648,2=0.000000
L 6.18156663 2.33943957 6.18386614 2.33582274 1 P 0 ;0,1=10,2=0.000000
L 6.18386614 2.33582274 6.18693287 2.3337565 1 P 0 ;0,1=10,2=0.000000
L 6.18693287 2.3337565 6.19038356 2.33323996 1 P 0 ;0,1=10,2=0.000000
L 6.19038356 2.33323996 6.1934503 2.3337565 1 P 0 ;0,1=10,2=0.000000
L 6.1934503 2.3337565 6.19651703 2.33633927 1 P 0 ;0,1=10,2=0.000000
L 6.19651703 2.33633927 6.19843327 2.33943957 1 P 0 ;0,1=10,2=0.000000
L 6.19843327 2.33943957 6.19881654 2.34253986 1 P 0 ;0,1=10,2=0.000000
L 6.19881654 2.34253986 6.19805 2.34615571 1 P 0 ;0,1=10,2=0.000000
L 6.19805 2.34615571 6.19536654 2.34873947 1 P 0 ;0,1=10,2=0.000000
L 6.19536654 2.34873947 6.19268307 2.34977352 1 P 0 ;0,1=10,2=0.000000
L 6.19268307 2.34977352 6.18923307 2.34977352 1 P 0 ;0,1=10,2=0.000000
L 6.19268307 2.34977352 6.19498327 2.35132313 1 P 0 ;0,1=10,2=0.000000
L 6.19498327 2.35132313 6.1969002 2.35390591 1 P 0 ;0,1=10,2=0.000000
L 6.1969002 2.35390591 6.19766673 2.3570062 1 P 0 ;0,1=10,2=0.000000
L 6.19766673 2.3570062 6.1969002 2.3601065 1 P 0 ;0,1=10,2=0.000000
L 6.1969002 2.3601065 6.19498327 2.36268927 1 P 0 ;0,1=10,2=0.000000
L 6.19498327 2.36268927 6.19153327 2.36423996 1 P 0 ;0,1=10,2=0.000000
L 6.19153327 2.36423996 6.18808337 2.36372333 1 P 0 ;0,1=10,2=0.000000
L 6.18808337 2.36372333 6.18463337 2.3616562 1 P 0 ;0,1=10,2=0.000000
L 6.2196 2.12323996 6.2196 2.15423996 1 P 0 ;0,1=11,2=0.000000
L 6.2196 2.15423996 6.20541624 2.13202323 1 P 0 ;0,1=11,2=0.000000
L 6.20541624 2.13202323 6.22458366 2.13202323 1 P 0 ;0,1=11,2=0.000000
L 6.3035 3.067 6.3035 2.563 1 P 0 
L 5.9385 3.067 6.3035 3.067 1 P 0 
L 6.3035 2.563 5.9385 2.563 1 P 0 
L 5.9385 2.563 5.9385 3.067 1 P 0 
L 6.32848287 3.04311585 6.33116634 3.04053307 1 P 0 ;0,1=14,2=0.000000
L 6.33116634 3.04053307 6.33423307 3.0395 1 P 0 ;0,1=14,2=0.000000
L 6.33423307 3.0395 6.3372998 3.04053307 1 P 0 ;0,1=14,2=0.000000
L 6.3372998 3.04053307 6.33998327 3.04363238 1 P 0 ;0,1=14,2=0.000000
L 6.33998327 3.04363238 6.3419002 3.04828327 1 P 0 ;0,1=14,2=0.000000
L 6.3419002 3.04828327 6.34266673 3.05293327 1 P 0 ;0,1=14,2=0.000000
L 6.34266673 3.05293327 6.34266673 3.05861634 1 P 0 ;0,1=14,2=0.000000
L 6.34266673 3.05861634 6.3419002 3.06326624 1 P 0 ;0,1=14,2=0.000000
L 6.3419002 3.06326624 6.33998327 3.0673997 1 P 0 ;0,1=14,2=0.000000
L 6.33998327 3.0673997 6.33768307 3.06946683 1 P 0 ;0,1=14,2=0.000000
L 6.33768307 3.06946683 6.33499961 3.0705 1 P 0 ;0,1=14,2=0.000000
L 6.33499961 3.0705 6.33193287 3.06946683 1 P 0 ;0,1=14,2=0.000000
L 6.33193287 3.06946683 6.32963337 3.0673997 1 P 0 ;0,1=14,2=0.000000
L 6.32963337 3.0673997 6.3280997 3.0643003 1 P 0 ;0,1=14,2=0.000000
L 6.3280997 3.0643003 6.32733317 3.06016594 1 P 0 ;0,1=14,2=0.000000
L 6.32733317 3.06016594 6.3280997 3.0565501 1 P 0 ;0,1=14,2=0.000000
L 6.3280997 3.0565501 6.33001663 3.05293327 1 P 0 ;0,1=14,2=0.000000
L 6.33001663 3.05293327 6.33231683 3.05086604 1 P 0 ;0,1=14,2=0.000000
L 6.33231683 3.05086604 6.33499961 3.05034951 1 P 0 ;0,1=14,2=0.000000
L 6.33499961 3.05034951 6.33806634 3.05138268 1 P 0 ;0,1=14,2=0.000000
L 6.33806634 3.05138268 6.34036654 3.05396634 1 P 0 ;0,1=14,2=0.000000
L 6.34036654 3.05396634 6.34266673 3.05861634 1 P 0 ;0,1=14,2=0.000000
L 6.32999961 2.5895 6.32999961 2.6205 1 P 0 ;0,1=2,2=0.000000
L 6.32999961 2.6205 6.3253999 2.6143003 1 P 0 ;0,1=2,2=0.000000
L 6.3253999 2.5895 6.33459931 2.5895 1 P 0 ;0,1=2,2=0.000000
L 6.09133317 3.08569961 6.0932501 3.08259931 1 P 0 ;0,1=649,2=0.000000
L 6.0932501 3.08259931 6.09554961 3.08053307 1 P 0 ;0,1=649,2=0.000000
L 6.09554961 3.08053307 6.09823307 3.0795 1 P 0 ;0,1=649,2=0.000000
L 6.09823307 3.0795 6.1012998 3.08053307 1 P 0 ;0,1=649,2=0.000000
L 6.1012998 3.08053307 6.1036 3.08259931 1 P 0 ;0,1=649,2=0.000000
L 6.1036 3.08259931 6.1059002 3.08569961 1 P 0 ;0,1=649,2=0.000000
L 6.1059002 3.08569961 6.10666673 3.08983297 1 P 0 ;0,1=649,2=0.000000
L 6.10666673 3.08983297 6.10666673 3.1105 1 P 0 ;0,1=649,2=0.000000
L 6.12999961 3.0795 6.12999961 3.1105 1 P 0 ;0,1=649,2=0.000000
L 6.12999961 3.1105 6.1253999 3.1043003 1 P 0 ;0,1=649,2=0.000000
L 6.1253999 3.0795 6.13459931 3.0795 1 P 0 ;0,1=649,2=0.000000
L 6.16099961 3.1105 6.15793287 3.10946683 1 P 0 ;0,1=649,2=0.000000
L 6.15793287 3.10946683 6.15563337 3.10688307 1 P 0 ;0,1=649,2=0.000000
L 6.15563337 3.10688307 6.1540997 3.10378376 1 P 0 ;0,1=649,2=0.000000
L 6.1540997 3.10378376 6.1529499 3.09964941 1 P 0 ;0,1=649,2=0.000000
L 6.1529499 3.09964941 6.15256663 3.09499951 1 P 0 ;0,1=649,2=0.000000
L 6.15256663 3.09499951 6.1529499 3.09034951 1 P 0 ;0,1=649,2=0.000000
L 6.1529499 3.09034951 6.1540997 3.08621614 1 P 0 ;0,1=649,2=0.000000
L 6.1540997 3.08621614 6.15563337 3.08311585 1 P 0 ;0,1=649,2=0.000000
L 6.15563337 3.08311585 6.15793287 3.08053307 1 P 0 ;0,1=649,2=0.000000
L 6.15793287 3.08053307 6.16099961 3.0795 1 P 0 ;0,1=649,2=0.000000
L 6.16099961 3.0795 6.16406634 3.08053307 1 P 0 ;0,1=649,2=0.000000
L 6.16406634 3.08053307 6.16636654 3.08311585 1 P 0 ;0,1=649,2=0.000000
L 6.16636654 3.08311585 6.1679002 3.08621614 1 P 0 ;0,1=649,2=0.000000
L 6.1679002 3.08621614 6.16905 3.09034951 1 P 0 ;0,1=649,2=0.000000
L 6.16905 3.09034951 6.16943327 3.09499951 1 P 0 ;0,1=649,2=0.000000
L 6.16943327 3.09499951 6.16905 3.09964941 1 P 0 ;0,1=649,2=0.000000
L 6.16905 3.09964941 6.1679002 3.10378376 1 P 0 ;0,1=649,2=0.000000
L 6.1679002 3.10378376 6.16636654 3.10688307 1 P 0 ;0,1=649,2=0.000000
L 6.16636654 3.10688307 6.16406634 3.10946683 1 P 0 ;0,1=649,2=0.000000
L 6.16406634 3.10946683 6.16099961 3.1105 1 P 0 ;0,1=649,2=0.000000
L 5.9155 3.04449961 5.8845 3.04449961 1 P 0 ;0,1=133,2=270.000000
L 5.8845 3.04449961 5.8906997 3.0398999 1 P 0 ;0,1=133,2=270.000000
L 5.9155 3.0398999 5.9155 3.04909931 1 P 0 ;0,1=133,2=270.000000
L 5.8845 3.07549961 5.88553317 3.07243287 1 P 0 ;0,1=133,2=270.000000
L 5.88553317 3.07243287 5.88811693 3.07013337 1 P 0 ;0,1=133,2=270.000000
L 5.88811693 3.07013337 5.89121624 3.0685997 1 P 0 ;0,1=133,2=270.000000
L 5.89121624 3.0685997 5.89535059 3.0674499 1 P 0 ;0,1=133,2=270.000000
L 5.89535059 3.0674499 5.90000049 3.06706663 1 P 0 ;0,1=133,2=270.000000
L 5.90000049 3.06706663 5.90465049 3.0674499 1 P 0 ;0,1=133,2=270.000000
L 5.90465049 3.0674499 5.90878386 3.0685997 1 P 0 ;0,1=133,2=270.000000
L 5.90878386 3.0685997 5.91188415 3.07013337 1 P 0 ;0,1=133,2=270.000000
L 5.91188415 3.07013337 5.91446693 3.07243287 1 P 0 ;0,1=133,2=270.000000
L 5.91446693 3.07243287 5.9155 3.07549961 1 P 0 ;0,1=133,2=270.000000
L 5.9155 3.07549961 5.91446693 3.07856634 1 P 0 ;0,1=133,2=270.000000
L 5.91446693 3.07856634 5.91188415 3.08086654 1 P 0 ;0,1=133,2=270.000000
L 5.91188415 3.08086654 5.90878386 3.0824002 1 P 0 ;0,1=133,2=270.000000
L 5.90878386 3.0824002 5.90465049 3.08355 1 P 0 ;0,1=133,2=270.000000
L 5.90465049 3.08355 5.90000049 3.08393327 1 P 0 ;0,1=133,2=270.000000
L 5.90000049 3.08393327 5.89535059 3.08355 1 P 0 ;0,1=133,2=270.000000
L 5.89535059 3.08355 5.89121624 3.0824002 1 P 0 ;0,1=133,2=270.000000
L 5.89121624 3.0824002 5.88811693 3.08086654 1 P 0 ;0,1=133,2=270.000000
L 5.88811693 3.08086654 5.88553317 3.07856634 1 P 0 ;0,1=133,2=270.000000
L 5.88553317 3.07856634 5.8845 3.07549961 1 P 0 ;0,1=133,2=270.000000
L 5.90771644 2.59533346 5.91001663 2.59843278 1 P 0 ;0,1=4,2=0.000000
L 5.91001663 2.59843278 5.9127001 2.59998337 1 P 0 ;0,1=4,2=0.000000
L 5.9127001 2.59998337 5.91576683 2.6005 1 P 0 ;0,1=4,2=0.000000
L 5.91576683 2.6005 5.9196 2.59946683 1 P 0 ;0,1=4,2=0.000000
L 5.9196 2.59946683 5.92228346 2.59688307 1 P 0 ;0,1=4,2=0.000000
L 5.92228346 2.59688307 5.92305 2.59378376 1 P 0 ;0,1=4,2=0.000000
L 5.92305 2.59378376 5.92266673 2.59068258 1 P 0 ;0,1=4,2=0.000000
L 5.92266673 2.59068258 5.92113307 2.5880998 1 P 0 ;0,1=4,2=0.000000
L 5.92113307 2.5880998 5.91346663 2.58293327 1 P 0 ;0,1=4,2=0.000000
L 5.91346663 2.58293327 5.91001663 2.57931644 1 P 0 ;0,1=4,2=0.000000
L 5.91001663 2.57931644 5.90771644 2.57414892 1 P 0 ;0,1=4,2=0.000000
L 5.90771644 2.57414892 5.9069499 2.5695 1 P 0 ;0,1=4,2=0.000000
L 5.9069499 2.5695 5.92305 2.5695 1 P 0 ;0,1=4,2=0.000000
L 5.7905 3.073 5.7905 2.569 1 P 0 
L 5.4255 3.073 5.7905 3.073 1 P 0 
L 5.7905 2.569 5.4255 2.569 1 P 0 
L 5.4255 2.569 5.4255 3.073 1 P 0 
L 5.81848287 3.04311585 5.82116634 3.04053307 1 P 0 ;0,1=14,2=0.000000
L 5.82116634 3.04053307 5.82423307 3.0395 1 P 0 ;0,1=14,2=0.000000
L 5.82423307 3.0395 5.8272998 3.04053307 1 P 0 ;0,1=14,2=0.000000
L 5.8272998 3.04053307 5.82998327 3.04363238 1 P 0 ;0,1=14,2=0.000000
L 5.82998327 3.04363238 5.8319002 3.04828327 1 P 0 ;0,1=14,2=0.000000
L 5.8319002 3.04828327 5.83266673 3.05293327 1 P 0 ;0,1=14,2=0.000000
L 5.83266673 3.05293327 5.83266673 3.05861634 1 P 0 ;0,1=14,2=0.000000
L 5.83266673 3.05861634 5.8319002 3.06326624 1 P 0 ;0,1=14,2=0.000000
L 5.8319002 3.06326624 5.82998327 3.0673997 1 P 0 ;0,1=14,2=0.000000
L 5.82998327 3.0673997 5.82768307 3.06946683 1 P 0 ;0,1=14,2=0.000000
L 5.82768307 3.06946683 5.82499961 3.0705 1 P 0 ;0,1=14,2=0.000000
L 5.82499961 3.0705 5.82193287 3.06946683 1 P 0 ;0,1=14,2=0.000000
L 5.82193287 3.06946683 5.81963337 3.0673997 1 P 0 ;0,1=14,2=0.000000
L 5.81963337 3.0673997 5.8180997 3.0643003 1 P 0 ;0,1=14,2=0.000000
L 5.8180997 3.0643003 5.81733317 3.06016594 1 P 0 ;0,1=14,2=0.000000
L 5.81733317 3.06016594 5.8180997 3.0565501 1 P 0 ;0,1=14,2=0.000000
L 5.8180997 3.0565501 5.82001663 3.05293327 1 P 0 ;0,1=14,2=0.000000
L 5.82001663 3.05293327 5.82231683 3.05086604 1 P 0 ;0,1=14,2=0.000000
L 5.82231683 3.05086604 5.82499961 3.05034951 1 P 0 ;0,1=14,2=0.000000
L 5.82499961 3.05034951 5.82806634 3.05138268 1 P 0 ;0,1=14,2=0.000000
L 5.82806634 3.05138268 5.83036654 3.05396634 1 P 0 ;0,1=14,2=0.000000
L 5.83036654 3.05396634 5.83266673 3.05861634 1 P 0 ;0,1=14,2=0.000000
L 5.83499961 2.6045 5.83499961 2.6355 1 P 0 ;0,1=2,2=0.000000
L 5.83499961 2.6355 5.8303999 2.6293003 1 P 0 ;0,1=2,2=0.000000
L 5.8303999 2.6045 5.83959931 2.6045 1 P 0 ;0,1=2,2=0.000000
L 5.58633317 3.09569961 5.5882501 3.09259931 1 P 0 ;0,1=650,2=0.000000
L 5.5882501 3.09259931 5.59054961 3.09053307 1 P 0 ;0,1=650,2=0.000000
L 5.59054961 3.09053307 5.59323307 3.0895 1 P 0 ;0,1=650,2=0.000000
L 5.59323307 3.0895 5.5962998 3.09053307 1 P 0 ;0,1=650,2=0.000000
L 5.5962998 3.09053307 5.5986 3.09259931 1 P 0 ;0,1=650,2=0.000000
L 5.5986 3.09259931 5.6009002 3.09569961 1 P 0 ;0,1=650,2=0.000000
L 5.6009002 3.09569961 5.60166673 3.09983297 1 P 0 ;0,1=650,2=0.000000
L 5.60166673 3.09983297 5.60166673 3.1205 1 P 0 ;0,1=650,2=0.000000
L 5.62499961 3.0895 5.62499961 3.1205 1 P 0 ;0,1=650,2=0.000000
L 5.62499961 3.1205 5.6203999 3.1143003 1 P 0 ;0,1=650,2=0.000000
L 5.6203999 3.0895 5.62959931 3.0895 1 P 0 ;0,1=650,2=0.000000
L 5.6606 3.0895 5.6606 3.1205 1 P 0 ;0,1=650,2=0.000000
L 5.6606 3.1205 5.64641624 3.09828327 1 P 0 ;0,1=650,2=0.000000
L 5.64641624 3.09828327 5.66558366 3.09828327 1 P 0 ;0,1=650,2=0.000000
L 5.42271644 2.56033346 5.42501663 2.56343278 1 P 0 ;0,1=4,2=0.000000
L 5.42501663 2.56343278 5.4277001 2.56498337 1 P 0 ;0,1=4,2=0.000000
L 5.4277001 2.56498337 5.43076683 2.5655 1 P 0 ;0,1=4,2=0.000000
L 5.43076683 2.5655 5.4346 2.56446683 1 P 0 ;0,1=4,2=0.000000
L 5.4346 2.56446683 5.43728346 2.56188307 1 P 0 ;0,1=4,2=0.000000
L 5.43728346 2.56188307 5.43805 2.55878376 1 P 0 ;0,1=4,2=0.000000
L 5.43805 2.55878376 5.43766673 2.55568258 1 P 0 ;0,1=4,2=0.000000
L 5.43766673 2.55568258 5.43613307 2.5530998 1 P 0 ;0,1=4,2=0.000000
L 5.43613307 2.5530998 5.42846663 2.54793327 1 P 0 ;0,1=4,2=0.000000
L 5.42846663 2.54793327 5.42501663 2.54431644 1 P 0 ;0,1=4,2=0.000000
L 5.42501663 2.54431644 5.42271644 2.53914892 1 P 0 ;0,1=4,2=0.000000
L 5.42271644 2.53914892 5.4219499 2.5345 1 P 0 ;0,1=4,2=0.000000
L 5.4219499 2.5345 5.43805 2.5345 1 P 0 ;0,1=4,2=0.000000
L 5.37949961 3.0545 5.37949961 3.0855 1 P 0 ;0,1=133,2=0.000000
L 5.37949961 3.0855 5.3748999 3.0793003 1 P 0 ;0,1=133,2=0.000000
L 5.3748999 3.0545 5.38409931 3.0545 1 P 0 ;0,1=133,2=0.000000
L 5.41049961 3.0855 5.40743287 3.08446683 1 P 0 ;0,1=133,2=0.000000
L 5.40743287 3.08446683 5.40513337 3.08188307 1 P 0 ;0,1=133,2=0.000000
L 5.40513337 3.08188307 5.4035997 3.07878376 1 P 0 ;0,1=133,2=0.000000
L 5.4035997 3.07878376 5.4024499 3.07464941 1 P 0 ;0,1=133,2=0.000000
L 5.4024499 3.07464941 5.40206663 3.06999951 1 P 0 ;0,1=133,2=0.000000
L 5.40206663 3.06999951 5.4024499 3.06534951 1 P 0 ;0,1=133,2=0.000000
L 5.4024499 3.06534951 5.4035997 3.06121614 1 P 0 ;0,1=133,2=0.000000
L 5.4035997 3.06121614 5.40513337 3.05811585 1 P 0 ;0,1=133,2=0.000000
L 5.40513337 3.05811585 5.40743287 3.05553307 1 P 0 ;0,1=133,2=0.000000
L 5.40743287 3.05553307 5.41049961 3.0545 1 P 0 ;0,1=133,2=0.000000
L 5.41049961 3.0545 5.41356634 3.05553307 1 P 0 ;0,1=133,2=0.000000
L 5.41356634 3.05553307 5.41586654 3.05811585 1 P 0 ;0,1=133,2=0.000000
L 5.41586654 3.05811585 5.4174002 3.06121614 1 P 0 ;0,1=133,2=0.000000
L 5.4174002 3.06121614 5.41855 3.06534951 1 P 0 ;0,1=133,2=0.000000
L 5.41855 3.06534951 5.41893327 3.06999951 1 P 0 ;0,1=133,2=0.000000
L 5.41893327 3.06999951 5.41855 3.07464941 1 P 0 ;0,1=133,2=0.000000
L 5.41855 3.07464941 5.4174002 3.07878376 1 P 0 ;0,1=133,2=0.000000
L 5.4174002 3.07878376 5.41586654 3.08188307 1 P 0 ;0,1=133,2=0.000000
L 5.41586654 3.08188307 5.41356634 3.08446683 1 P 0 ;0,1=133,2=0.000000
L 5.41356634 3.08446683 5.41049961 3.0855 1 P 0 ;0,1=133,2=0.000000
L 6.61636998 2.28166004 6.61636998 1.93881998 1 P 0 
L 6.37101998 2.28166004 6.61636998 2.28166004 1 P 0 
L 6.61636998 1.93881998 6.37101998 1.93881998 1 P 0 
L 6.37101998 1.93881998 6.37101998 2.28166004 1 P 0 
L 6.53000049 2.30503976 6.53000049 2.31270689 1 P 0 ;0,1=122,2=270.000000
L 6.53000049 2.31270689 6.53930039 2.31270689 1 P 0 ;0,1=122,2=270.000000
L 6.53930039 2.31270689 6.54240069 2.31040669 1 P 0 ;0,1=122,2=270.000000
L 6.54240069 2.31040669 6.54446693 2.30772323 1 P 0 ;0,1=122,2=270.000000
L 6.54446693 2.30772323 6.5455 2.30389006 1 P 0 ;0,1=122,2=270.000000
L 6.5455 2.30389006 6.54446693 2.30005679 1 P 0 ;0,1=122,2=270.000000
L 6.54446693 2.30005679 6.54240069 2.29737333 1 P 0 ;0,1=122,2=270.000000
L 6.54240069 2.29737333 6.53930039 2.29507313 1 P 0 ;0,1=122,2=270.000000
L 6.53930039 2.29507313 6.53568356 2.29353947 1 P 0 ;0,1=122,2=270.000000
L 6.53568356 2.29353947 6.5315502 2.29277293 1 P 0 ;0,1=122,2=270.000000
L 6.5315502 2.29277293 6.52793337 2.29277293 1 P 0 ;0,1=122,2=270.000000
L 6.52793337 2.29277293 6.52483406 2.29353947 1 P 0 ;0,1=122,2=270.000000
L 6.52483406 2.29353947 6.52121624 2.29507313 1 P 0 ;0,1=122,2=270.000000
L 6.52121624 2.29507313 6.51811693 2.29737333 1 P 0 ;0,1=122,2=270.000000
L 6.51811693 2.29737333 6.51605069 2.29967283 1 P 0 ;0,1=122,2=270.000000
L 6.51605069 2.29967283 6.5145 2.30273957 1 P 0 ;0,1=122,2=270.000000
L 6.5145 2.30273957 6.5145 2.30542303 1 P 0 ;0,1=122,2=270.000000
L 6.5145 2.30542303 6.51553317 2.30848976 1 P 0 ;0,1=122,2=270.000000
L 6.51553317 2.30848976 6.5176003 2.31078996 1 P 0 ;0,1=122,2=270.000000
L 6.5455 2.32568986 6.5145 2.32568986 1 P 0 ;0,1=122,2=270.000000
L 6.5145 2.34178996 6.5455 2.34178996 1 P 0 ;0,1=122,2=270.000000
L 6.53000049 2.34178996 6.53000049 2.32568986 1 P 0 ;0,1=122,2=270.000000
L 6.5455 2.36933996 6.5145 2.36933996 1 P 0 ;0,1=122,2=270.000000
L 6.5145 2.36933996 6.53671673 2.3551562 1 P 0 ;0,1=122,2=270.000000
L 6.53671673 2.3551562 6.53671673 2.37432362 1 P 0 ;0,1=122,2=270.000000
L 6.52000049 1.8662998 6.52000049 1.87396693 1 P 0 ;0,1=124,2=270.000000
L 6.52000049 1.87396693 6.52930039 1.87396693 1 P 0 ;0,1=124,2=270.000000
L 6.52930039 1.87396693 6.53240069 1.87166673 1 P 0 ;0,1=124,2=270.000000
L 6.53240069 1.87166673 6.53446693 1.86898327 1 P 0 ;0,1=124,2=270.000000
L 6.53446693 1.86898327 6.5355 1.8651501 1 P 0 ;0,1=124,2=270.000000
L 6.5355 1.8651501 6.53446693 1.86131683 1 P 0 ;0,1=124,2=270.000000
L 6.53446693 1.86131683 6.53240069 1.85863337 1 P 0 ;0,1=124,2=270.000000
L 6.53240069 1.85863337 6.52930039 1.85633317 1 P 0 ;0,1=124,2=270.000000
L 6.52930039 1.85633317 6.52568356 1.85479951 1 P 0 ;0,1=124,2=270.000000
L 6.52568356 1.85479951 6.5215502 1.85403297 1 P 0 ;0,1=124,2=270.000000
L 6.5215502 1.85403297 6.51793337 1.85403297 1 P 0 ;0,1=124,2=270.000000
L 6.51793337 1.85403297 6.51483406 1.85479951 1 P 0 ;0,1=124,2=270.000000
L 6.51483406 1.85479951 6.51121624 1.85633317 1 P 0 ;0,1=124,2=270.000000
L 6.51121624 1.85633317 6.50811693 1.85863337 1 P 0 ;0,1=124,2=270.000000
L 6.50811693 1.85863337 6.50605069 1.86093287 1 P 0 ;0,1=124,2=270.000000
L 6.50605069 1.86093287 6.5045 1.86399961 1 P 0 ;0,1=124,2=270.000000
L 6.5045 1.86399961 6.5045 1.86668307 1 P 0 ;0,1=124,2=270.000000
L 6.5045 1.86668307 6.50553317 1.8697498 1 P 0 ;0,1=124,2=270.000000
L 6.50553317 1.8697498 6.5076003 1.87205 1 P 0 ;0,1=124,2=270.000000
L 6.5355 1.8869499 6.5045 1.8869499 1 P 0 ;0,1=124,2=270.000000
L 6.5045 1.90305 6.5355 1.90305 1 P 0 ;0,1=124,2=270.000000
L 6.52000049 1.90305 6.52000049 1.8869499 1 P 0 ;0,1=124,2=270.000000
L 6.52930039 1.91756663 6.53291722 1.91986614 1 P 0 ;0,1=124,2=270.000000
L 6.53291722 1.91986614 6.53498346 1.92293287 1 P 0 ;0,1=124,2=270.000000
L 6.53498346 1.92293287 6.5355 1.92638356 1 P 0 ;0,1=124,2=270.000000
L 6.5355 1.92638356 6.53498346 1.9294503 1 P 0 ;0,1=124,2=270.000000
L 6.53498346 1.9294503 6.53240069 1.93251703 1 P 0 ;0,1=124,2=270.000000
L 6.53240069 1.93251703 6.52930039 1.93443327 1 P 0 ;0,1=124,2=270.000000
L 6.52930039 1.93443327 6.5262001 1.93481654 1 P 0 ;0,1=124,2=270.000000
L 6.5262001 1.93481654 6.52258425 1.93405 1 P 0 ;0,1=124,2=270.000000
L 6.52258425 1.93405 6.52000049 1.93136654 1 P 0 ;0,1=124,2=270.000000
L 6.52000049 1.93136654 6.51896644 1.92868307 1 P 0 ;0,1=124,2=270.000000
L 6.51896644 1.92868307 6.51896644 1.92523307 1 P 0 ;0,1=124,2=270.000000
L 6.51896644 1.92868307 6.51741683 1.93098327 1 P 0 ;0,1=124,2=270.000000
L 6.51741683 1.93098327 6.51483406 1.9329002 1 P 0 ;0,1=124,2=270.000000
L 6.51483406 1.9329002 6.51173376 1.93366673 1 P 0 ;0,1=124,2=270.000000
L 6.51173376 1.93366673 6.50863346 1.9329002 1 P 0 ;0,1=124,2=270.000000
L 6.50863346 1.9329002 6.50605069 1.93098327 1 P 0 ;0,1=124,2=270.000000
L 6.50605069 1.93098327 6.5045 1.92753327 1 P 0 ;0,1=124,2=270.000000
L 6.5045 1.92753327 6.50501663 1.92408337 1 P 0 ;0,1=124,2=270.000000
L 6.50501663 1.92408337 6.50708376 1.92063337 1 P 0 ;0,1=124,2=270.000000
L 6.42633317 2.30443957 6.4282501 2.30133927 1 P 0 ;0,1=651,2=0.000000
L 6.4282501 2.30133927 6.43054961 2.29927303 1 P 0 ;0,1=651,2=0.000000
L 6.43054961 2.29927303 6.43323307 2.29823996 1 P 0 ;0,1=651,2=0.000000
L 6.43323307 2.29823996 6.4362998 2.29927303 1 P 0 ;0,1=651,2=0.000000
L 6.4362998 2.29927303 6.4386 2.30133927 1 P 0 ;0,1=651,2=0.000000
L 6.4386 2.30133927 6.4409002 2.30443957 1 P 0 ;0,1=651,2=0.000000
L 6.4409002 2.30443957 6.44166673 2.30857293 1 P 0 ;0,1=651,2=0.000000
L 6.44166673 2.30857293 6.44166673 2.32923996 1 P 0 ;0,1=651,2=0.000000
L 6.46499961 2.29823996 6.46499961 2.32923996 1 P 0 ;0,1=651,2=0.000000
L 6.46499961 2.32923996 6.4603999 2.32304026 1 P 0 ;0,1=651,2=0.000000
L 6.4603999 2.29823996 6.46959931 2.29823996 1 P 0 ;0,1=651,2=0.000000
L 6.49599961 2.29823996 6.49599961 2.32923996 1 P 0 ;0,1=651,2=0.000000
L 6.49599961 2.32923996 6.4913999 2.32304026 1 P 0 ;0,1=651,2=0.000000
L 6.4913999 2.29823996 6.50059931 2.29823996 1 P 0 ;0,1=651,2=0.000000
L 6.38500049 2.30503976 6.38500049 2.31270689 1 P 0 ;0,1=121,2=270.000000
L 6.38500049 2.31270689 6.39430039 2.31270689 1 P 0 ;0,1=121,2=270.000000
L 6.39430039 2.31270689 6.39740069 2.31040669 1 P 0 ;0,1=121,2=270.000000
L 6.39740069 2.31040669 6.39946693 2.30772323 1 P 0 ;0,1=121,2=270.000000
L 6.39946693 2.30772323 6.4005 2.30389006 1 P 0 ;0,1=121,2=270.000000
L 6.4005 2.30389006 6.39946693 2.30005679 1 P 0 ;0,1=121,2=270.000000
L 6.39946693 2.30005679 6.39740069 2.29737333 1 P 0 ;0,1=121,2=270.000000
L 6.39740069 2.29737333 6.39430039 2.29507313 1 P 0 ;0,1=121,2=270.000000
L 6.39430039 2.29507313 6.39068356 2.29353947 1 P 0 ;0,1=121,2=270.000000
L 6.39068356 2.29353947 6.3865502 2.29277293 1 P 0 ;0,1=121,2=270.000000
L 6.3865502 2.29277293 6.38293337 2.29277293 1 P 0 ;0,1=121,2=270.000000
L 6.38293337 2.29277293 6.37983406 2.29353947 1 P 0 ;0,1=121,2=270.000000
L 6.37983406 2.29353947 6.37621624 2.29507313 1 P 0 ;0,1=121,2=270.000000
L 6.37621624 2.29507313 6.37311693 2.29737333 1 P 0 ;0,1=121,2=270.000000
L 6.37311693 2.29737333 6.37105069 2.29967283 1 P 0 ;0,1=121,2=270.000000
L 6.37105069 2.29967283 6.3695 2.30273957 1 P 0 ;0,1=121,2=270.000000
L 6.3695 2.30273957 6.3695 2.30542303 1 P 0 ;0,1=121,2=270.000000
L 6.3695 2.30542303 6.37053317 2.30848976 1 P 0 ;0,1=121,2=270.000000
L 6.37053317 2.30848976 6.3726003 2.31078996 1 P 0 ;0,1=121,2=270.000000
L 6.4005 2.32568986 6.3695 2.32568986 1 P 0 ;0,1=121,2=270.000000
L 6.3695 2.34178996 6.4005 2.34178996 1 P 0 ;0,1=121,2=270.000000
L 6.38500049 2.34178996 6.38500049 2.32568986 1 P 0 ;0,1=121,2=270.000000
L 6.37466654 2.3574564 6.37156722 2.35975659 1 P 0 ;0,1=121,2=270.000000
L 6.37156722 2.35975659 6.37001663 2.36244006 1 P 0 ;0,1=121,2=270.000000
L 6.37001663 2.36244006 6.3695 2.36550679 1 P 0 ;0,1=121,2=270.000000
L 6.3695 2.36550679 6.37053317 2.36933996 1 P 0 ;0,1=121,2=270.000000
L 6.37053317 2.36933996 6.37311693 2.37202343 1 P 0 ;0,1=121,2=270.000000
L 6.37311693 2.37202343 6.37621624 2.37278996 1 P 0 ;0,1=121,2=270.000000
L 6.37621624 2.37278996 6.37931742 2.37240669 1 P 0 ;0,1=121,2=270.000000
L 6.37931742 2.37240669 6.3819002 2.37087303 1 P 0 ;0,1=121,2=270.000000
L 6.3819002 2.37087303 6.38706673 2.36320659 1 P 0 ;0,1=121,2=270.000000
L 6.38706673 2.36320659 6.39068356 2.35975659 1 P 0 ;0,1=121,2=270.000000
L 6.39068356 2.35975659 6.39585108 2.3574564 1 P 0 ;0,1=121,2=270.000000
L 6.39585108 2.3574564 6.4005 2.35668986 1 P 0 ;0,1=121,2=270.000000
L 6.4005 2.35668986 6.4005 2.37278996 1 P 0 ;0,1=121,2=270.000000
L 6.34656663 2.17914892 6.34886614 2.17656614 1 P 0 ;0,1=20,2=0.000000
L 6.34886614 2.17656614 6.35154961 2.17501654 1 P 0 ;0,1=20,2=0.000000
L 6.35154961 2.17501654 6.35499961 2.1745 1 P 0 ;0,1=20,2=0.000000
L 6.35499961 2.1745 6.3584503 2.17553307 1 P 0 ;0,1=20,2=0.000000
L 6.3584503 2.17553307 6.36113307 2.17759931 1 P 0 ;0,1=20,2=0.000000
L 6.36113307 2.17759931 6.36305 2.18121614 1 P 0 ;0,1=20,2=0.000000
L 6.36305 2.18121614 6.36343327 2.18534951 1 P 0 ;0,1=20,2=0.000000
L 6.36343327 2.18534951 6.36266673 2.18948287 1 P 0 ;0,1=20,2=0.000000
L 6.36266673 2.18948287 6.3607498 2.19206663 1 P 0 ;0,1=20,2=0.000000
L 6.3607498 2.19206663 6.35806634 2.19413287 1 P 0 ;0,1=20,2=0.000000
L 6.35806634 2.19413287 6.35538356 2.19464941 1 P 0 ;0,1=20,2=0.000000
L 6.35538356 2.19464941 6.3527001 2.19413287 1 P 0 ;0,1=20,2=0.000000
L 6.3527001 2.19413287 6.3492501 2.19206663 1 P 0 ;0,1=20,2=0.000000
L 6.3492501 2.19206663 6.3503999 2.2055 1 P 0 ;0,1=20,2=0.000000
L 6.3503999 2.2055 6.3607498 2.2055 1 P 0 ;0,1=20,2=0.000000
L 6.34999961 2.0395 6.34999961 2.0705 1 P 0 ;0,1=2,2=0.000000
L 6.34999961 2.0705 6.3453999 2.0643003 1 P 0 ;0,1=2,2=0.000000
L 6.3453999 2.0395 6.35459931 2.0395 1 P 0 ;0,1=2,2=0.000000
L 6.39000049 1.8662998 6.39000049 1.87396693 1 P 0 ;0,1=123,2=270.000000
L 6.39000049 1.87396693 6.39930039 1.87396693 1 P 0 ;0,1=123,2=270.000000
L 6.39930039 1.87396693 6.40240069 1.87166673 1 P 0 ;0,1=123,2=270.000000
L 6.40240069 1.87166673 6.40446693 1.86898327 1 P 0 ;0,1=123,2=270.000000
L 6.40446693 1.86898327 6.4055 1.8651501 1 P 0 ;0,1=123,2=270.000000
L 6.4055 1.8651501 6.40446693 1.86131683 1 P 0 ;0,1=123,2=270.000000
L 6.40446693 1.86131683 6.40240069 1.85863337 1 P 0 ;0,1=123,2=270.000000
L 6.40240069 1.85863337 6.39930039 1.85633317 1 P 0 ;0,1=123,2=270.000000
L 6.39930039 1.85633317 6.39568356 1.85479951 1 P 0 ;0,1=123,2=270.000000
L 6.39568356 1.85479951 6.3915502 1.85403297 1 P 0 ;0,1=123,2=270.000000
L 6.3915502 1.85403297 6.38793337 1.85403297 1 P 0 ;0,1=123,2=270.000000
L 6.38793337 1.85403297 6.38483406 1.85479951 1 P 0 ;0,1=123,2=270.000000
L 6.38483406 1.85479951 6.38121624 1.85633317 1 P 0 ;0,1=123,2=270.000000
L 6.38121624 1.85633317 6.37811693 1.85863337 1 P 0 ;0,1=123,2=270.000000
L 6.37811693 1.85863337 6.37605069 1.86093287 1 P 0 ;0,1=123,2=270.000000
L 6.37605069 1.86093287 6.3745 1.86399961 1 P 0 ;0,1=123,2=270.000000
L 6.3745 1.86399961 6.3745 1.86668307 1 P 0 ;0,1=123,2=270.000000
L 6.3745 1.86668307 6.37553317 1.8697498 1 P 0 ;0,1=123,2=270.000000
L 6.37553317 1.8697498 6.3776003 1.87205 1 P 0 ;0,1=123,2=270.000000
L 6.4055 1.8869499 6.3745 1.8869499 1 P 0 ;0,1=123,2=270.000000
L 6.3745 1.90305 6.4055 1.90305 1 P 0 ;0,1=123,2=270.000000
L 6.39000049 1.90305 6.39000049 1.8869499 1 P 0 ;0,1=123,2=270.000000
L 6.4055 1.92599961 6.3745 1.92599961 1 P 0 ;0,1=123,2=270.000000
L 6.3745 1.92599961 6.3806997 1.9213999 1 P 0 ;0,1=123,2=270.000000
L 6.4055 1.9213999 6.4055 1.93059931 1 P 0 ;0,1=123,2=270.000000
L 3.3225 3.4235 3.3225 3.2065 1 P 0 
L 3.0015 3.4235 3.3225 3.4235 1 P 0 
L 3.3225 3.2065 3.0015 3.2065 1 P 0 
L 3.0015 3.2065 3.0015 3.4235 1 P 0 
S P 0
OB 3.3645 3.2275 I
OC 3.3645 3.2275 3.3495 3.2275 Y
OE
SE
L 3.34499961 3.3845 3.34768307 3.38501654 1 P 0 ;0,1=16,2=0.000000
L 3.34768307 3.38501654 3.3507498 3.38656614 1 P 0 ;0,1=16,2=0.000000
L 3.3507498 3.38656614 3.35266673 3.38914892 1 P 0 ;0,1=16,2=0.000000
L 3.35266673 3.38914892 3.35343327 3.39276673 1 P 0 ;0,1=16,2=0.000000
L 3.35343327 3.39276673 3.35266673 3.39638268 1 P 0 ;0,1=16,2=0.000000
L 3.35266673 3.39638268 3.35036654 3.39948287 1 P 0 ;0,1=16,2=0.000000
L 3.35036654 3.39948287 3.34691654 3.40103356 1 P 0 ;0,1=16,2=0.000000
L 3.34691654 3.40103356 3.34308337 3.40103356 1 P 0 ;0,1=16,2=0.000000
L 3.34308337 3.40103356 3.34078317 3.40206663 1 P 0 ;0,1=16,2=0.000000
L 3.34078317 3.40206663 3.33886614 3.40464941 1 P 0 ;0,1=16,2=0.000000
L 3.33886614 3.40464941 3.3380997 3.40826624 1 P 0 ;0,1=16,2=0.000000
L 3.3380997 3.40826624 3.3392501 3.41188307 1 P 0 ;0,1=16,2=0.000000
L 3.3392501 3.41188307 3.34193287 3.41446683 1 P 0 ;0,1=16,2=0.000000
L 3.34193287 3.41446683 3.34499961 3.4155 1 P 0 ;0,1=16,2=0.000000
L 3.34499961 3.4155 3.34806634 3.41446683 1 P 0 ;0,1=16,2=0.000000
L 3.34806634 3.41446683 3.3507498 3.41188307 1 P 0 ;0,1=16,2=0.000000
L 3.3507498 3.41188307 3.3519002 3.40826624 1 P 0 ;0,1=16,2=0.000000
L 3.3519002 3.40826624 3.35113307 3.40464941 1 P 0 ;0,1=16,2=0.000000
L 3.35113307 3.40464941 3.34921673 3.40206663 1 P 0 ;0,1=16,2=0.000000
L 3.34921673 3.40206663 3.34691654 3.40103356 1 P 0 ;0,1=16,2=0.000000
L 3.34691654 3.40103356 3.34308337 3.40103356 1 P 0 ;0,1=16,2=0.000000
L 3.34308337 3.40103356 3.33963337 3.39948287 1 P 0 ;0,1=16,2=0.000000
L 3.33963337 3.39948287 3.33733317 3.39638268 1 P 0 ;0,1=16,2=0.000000
L 3.33733317 3.39638268 3.33656663 3.39276673 1 P 0 ;0,1=16,2=0.000000
L 3.33656663 3.39276673 3.33733317 3.38914892 1 P 0 ;0,1=16,2=0.000000
L 3.33733317 3.38914892 3.3392501 3.38656614 1 P 0 ;0,1=16,2=0.000000
L 3.3392501 3.38656614 3.34231683 3.38501654 1 P 0 ;0,1=16,2=0.000000
L 3.34231683 3.38501654 3.34499961 3.3845 1 P 0 ;0,1=16,2=0.000000
L 2.98951713 3.41638415 2.98683366 3.41896693 1 P 0 ;0,1=14,2=180.000000
L 2.98683366 3.41896693 2.98376693 3.42 1 P 0 ;0,1=14,2=180.000000
L 2.98376693 3.42 2.9807002 3.41896693 1 P 0 ;0,1=14,2=180.000000
L 2.9807002 3.41896693 2.97801673 3.41586762 1 P 0 ;0,1=14,2=180.000000
L 2.97801673 3.41586762 2.9760998 3.41121673 1 P 0 ;0,1=14,2=180.000000
L 2.9760998 3.41121673 2.97533327 3.40656673 1 P 0 ;0,1=14,2=180.000000
L 2.97533327 3.40656673 2.97533327 3.40088366 1 P 0 ;0,1=14,2=180.000000
L 2.97533327 3.40088366 2.9760998 3.39623376 1 P 0 ;0,1=14,2=180.000000
L 2.9760998 3.39623376 2.97801673 3.3921003 1 P 0 ;0,1=14,2=180.000000
L 2.97801673 3.3921003 2.98031693 3.39003317 1 P 0 ;0,1=14,2=180.000000
L 2.98031693 3.39003317 2.98300039 3.389 1 P 0 ;0,1=14,2=180.000000
L 2.98300039 3.389 2.98606713 3.39003317 1 P 0 ;0,1=14,2=180.000000
L 2.98606713 3.39003317 2.98836663 3.3921003 1 P 0 ;0,1=14,2=180.000000
L 2.98836663 3.3921003 2.9899003 3.3951997 1 P 0 ;0,1=14,2=180.000000
L 2.9899003 3.3951997 2.99066683 3.39933406 1 P 0 ;0,1=14,2=180.000000
L 2.99066683 3.39933406 2.9899003 3.4029499 1 P 0 ;0,1=14,2=180.000000
L 2.9899003 3.4029499 2.98798337 3.40656673 1 P 0 ;0,1=14,2=180.000000
L 2.98798337 3.40656673 2.98568317 3.40863396 1 P 0 ;0,1=14,2=180.000000
L 2.98568317 3.40863396 2.98300039 3.40915049 1 P 0 ;0,1=14,2=180.000000
L 2.98300039 3.40915049 2.97993366 3.40811732 1 P 0 ;0,1=14,2=180.000000
L 2.97993366 3.40811732 2.97763346 3.40553366 1 P 0 ;0,1=14,2=180.000000
L 2.97763346 3.40553366 2.97533327 3.40088366 1 P 0 ;0,1=14,2=180.000000
L 3.12606663 3.471 3.12606663 3.44878327 1 P 0 ;0,1=652,2=0.000000
L 3.12606663 3.44878327 3.1275997 3.44413238 1 P 0 ;0,1=652,2=0.000000
L 3.1275997 3.44413238 3.13066634 3.44103307 1 P 0 ;0,1=652,2=0.000000
L 3.13066634 3.44103307 3.13449961 3.44 1 P 0 ;0,1=652,2=0.000000
L 3.13449961 3.44 3.13833356 3.44103307 1 P 0 ;0,1=652,2=0.000000
L 3.13833356 3.44103307 3.1414002 3.44413238 1 P 0 ;0,1=652,2=0.000000
L 3.1414002 3.44413238 3.14293327 3.44878327 1 P 0 ;0,1=652,2=0.000000
L 3.14293327 3.44878327 3.14293327 3.471 1 P 0 ;0,1=652,2=0.000000
L 3.1701 3.44 3.1701 3.471 1 P 0 ;0,1=652,2=0.000000
L 3.1701 3.471 3.15591624 3.44878327 1 P 0 ;0,1=652,2=0.000000
L 3.15591624 3.44878327 3.17508366 3.44878327 1 P 0 ;0,1=652,2=0.000000
L 3.03449961 3.1545 3.03449961 3.1855 1 P 0 ;0,1=13,2=0.000000
L 3.03449961 3.1855 3.0298999 3.1793003 1 P 0 ;0,1=13,2=0.000000
L 3.0298999 3.1545 3.03909931 3.1545 1 P 0 ;0,1=13,2=0.000000
L 3.05821644 3.16741575 3.0608999 3.17103356 1 P 0 ;0,1=13,2=0.000000
L 3.0608999 3.17103356 3.0632001 3.1730998 1 P 0 ;0,1=13,2=0.000000
L 3.0632001 3.1730998 3.06626683 3.17413287 1 P 0 ;0,1=13,2=0.000000
L 3.06626683 3.17413287 3.0689503 3.1730998 1 P 0 ;0,1=13,2=0.000000
L 3.0689503 3.1730998 3.07086654 3.17103356 1 P 0 ;0,1=13,2=0.000000
L 3.07086654 3.17103356 3.0724002 3.16793327 1 P 0 ;0,1=13,2=0.000000
L 3.0724002 3.16793327 3.07278346 3.16431644 1 P 0 ;0,1=13,2=0.000000
L 3.07278346 3.16431644 3.0724002 3.16121614 1 P 0 ;0,1=13,2=0.000000
L 3.0724002 3.16121614 3.07086654 3.15811585 1 P 0 ;0,1=13,2=0.000000
L 3.07086654 3.15811585 3.06856634 3.15553307 1 P 0 ;0,1=13,2=0.000000
L 3.06856634 3.15553307 3.06588356 3.1545 1 P 0 ;0,1=13,2=0.000000
L 3.06588356 3.1545 3.06281683 3.15553307 1 P 0 ;0,1=13,2=0.000000
L 3.06281683 3.15553307 3.06013337 3.15863238 1 P 0 ;0,1=13,2=0.000000
L 3.06013337 3.15863238 3.0585997 3.16328327 1 P 0 ;0,1=13,2=0.000000
L 3.0585997 3.16328327 3.05821644 3.1684498 1 P 0 ;0,1=13,2=0.000000
L 3.05821644 3.1684498 3.05898287 3.17516594 1 P 0 ;0,1=13,2=0.000000
L 3.05898287 3.17516594 3.06013337 3.17878376 1 P 0 ;0,1=13,2=0.000000
L 3.06013337 3.17878376 3.06204961 3.1823997 1 P 0 ;0,1=13,2=0.000000
L 3.06204961 3.1823997 3.06473307 3.18498337 1 P 0 ;0,1=13,2=0.000000
L 3.06473307 3.18498337 3.06741654 3.1855 1 P 0 ;0,1=13,2=0.000000
L 3.06741654 3.1855 3.0701 3.18446683 1 P 0 ;0,1=13,2=0.000000
L 3.0701 3.18446683 3.07201703 3.18188307 1 P 0 ;0,1=13,2=0.000000
L 1.90256634 0.40103356 1.9041 0.40258317 1 P 0 ;0,1=653,2=0.000000
L 1.9041 0.40258317 1.9052498 0.40516594 1 P 0 ;0,1=653,2=0.000000
L 1.9052498 0.40516594 1.90601703 0.40878376 1 P 0 ;0,1=653,2=0.000000
L 1.90601703 0.40878376 1.9052498 0.41188307 1 P 0 ;0,1=653,2=0.000000
L 1.9052498 0.41188307 1.90371673 0.41394931 1 P 0 ;0,1=653,2=0.000000
L 1.90371673 0.41394931 1.90103327 0.4155 1 P 0 ;0,1=653,2=0.000000
L 1.90103327 0.4155 1.89068337 0.4155 1 P 0 ;0,1=653,2=0.000000
L 1.89068337 0.4155 1.89068337 0.3845 1 P 0 ;0,1=653,2=0.000000
L 1.89068337 0.3845 1.90333356 0.3845 1 P 0 ;0,1=653,2=0.000000
L 1.90333356 0.3845 1.90601703 0.38656614 1 P 0 ;0,1=653,2=0.000000
L 1.90601703 0.38656614 1.90755 0.38966644 1 P 0 ;0,1=653,2=0.000000
L 1.90755 0.38966644 1.90831654 0.39328327 1 P 0 ;0,1=653,2=0.000000
L 1.90831654 0.39328327 1.90755 0.39689921 1 P 0 ;0,1=653,2=0.000000
L 1.90755 0.39689921 1.9052498 0.39999951 1 P 0 ;0,1=653,2=0.000000
L 1.9052498 0.39999951 1.90256634 0.40103356 1 P 0 ;0,1=653,2=0.000000
L 1.90256634 0.40103356 1.89068337 0.40103356 1 P 0 ;0,1=653,2=0.000000
L 1.93049961 0.3845 1.93049961 0.4155 1 P 0 ;0,1=653,2=0.000000
L 1.93049961 0.4155 1.9258999 0.4093003 1 P 0 ;0,1=653,2=0.000000
L 1.9258999 0.3845 1.93509931 0.3845 1 P 0 ;0,1=653,2=0.000000
L 2.3112998 0.34999951 2.31896693 0.34999951 1 P 0 ;0,1=654,2=0.000000
L 2.31896693 0.34999951 2.31896693 0.34069961 1 P 0 ;0,1=654,2=0.000000
L 2.31896693 0.34069961 2.31666673 0.33759931 1 P 0 ;0,1=654,2=0.000000
L 2.31666673 0.33759931 2.31398327 0.33553307 1 P 0 ;0,1=654,2=0.000000
L 2.31398327 0.33553307 2.3101501 0.3345 1 P 0 ;0,1=654,2=0.000000
L 2.3101501 0.3345 2.30631683 0.33553307 1 P 0 ;0,1=654,2=0.000000
L 2.30631683 0.33553307 2.30363337 0.33759931 1 P 0 ;0,1=654,2=0.000000
L 2.30363337 0.33759931 2.30133317 0.34069961 1 P 0 ;0,1=654,2=0.000000
L 2.30133317 0.34069961 2.29979951 0.34431644 1 P 0 ;0,1=654,2=0.000000
L 2.29979951 0.34431644 2.29903297 0.3484498 1 P 0 ;0,1=654,2=0.000000
L 2.29903297 0.3484498 2.29903297 0.35206663 1 P 0 ;0,1=654,2=0.000000
L 2.29903297 0.35206663 2.29979951 0.35516594 1 P 0 ;0,1=654,2=0.000000
L 2.29979951 0.35516594 2.30133317 0.35878376 1 P 0 ;0,1=654,2=0.000000
L 2.30133317 0.35878376 2.30363337 0.36188307 1 P 0 ;0,1=654,2=0.000000
L 2.30363337 0.36188307 2.30593287 0.36394931 1 P 0 ;0,1=654,2=0.000000
L 2.30593287 0.36394931 2.30899961 0.3655 1 P 0 ;0,1=654,2=0.000000
L 2.30899961 0.3655 2.31168307 0.3655 1 P 0 ;0,1=654,2=0.000000
L 2.31168307 0.3655 2.3147498 0.36446683 1 P 0 ;0,1=654,2=0.000000
L 2.3147498 0.36446683 2.31705 0.3623997 1 P 0 ;0,1=654,2=0.000000
L 2.33271644 0.3345 2.33271644 0.3655 1 P 0 ;0,1=654,2=0.000000
L 2.33271644 0.3655 2.34728346 0.3655 1 P 0 ;0,1=654,2=0.000000
L 2.34191654 0.35051703 2.33271644 0.35051703 1 P 0 ;0,1=654,2=0.000000
L 2.37099961 0.3345 2.37099961 0.3655 1 P 0 ;0,1=654,2=0.000000
L 2.37099961 0.3655 2.3663999 0.3593003 1 P 0 ;0,1=654,2=0.000000
L 2.3663999 0.3345 2.37559931 0.3345 1 P 0 ;0,1=654,2=0.000000
L 2.99706634 0.32103356 2.9986 0.32258317 1 P 0 ;0,1=655,2=0.000000
L 2.9986 0.32258317 2.9997498 0.32516594 1 P 0 ;0,1=655,2=0.000000
L 2.9997498 0.32516594 3.00051703 0.32878376 1 P 0 ;0,1=655,2=0.000000
L 3.00051703 0.32878376 2.9997498 0.33188307 1 P 0 ;0,1=655,2=0.000000
L 2.9997498 0.33188307 2.99821673 0.33394931 1 P 0 ;0,1=655,2=0.000000
L 2.99821673 0.33394931 2.99553327 0.3355 1 P 0 ;0,1=655,2=0.000000
L 2.99553327 0.3355 2.98518337 0.3355 1 P 0 ;0,1=655,2=0.000000
L 2.98518337 0.3355 2.98518337 0.3045 1 P 0 ;0,1=655,2=0.000000
L 2.98518337 0.3045 2.99783356 0.3045 1 P 0 ;0,1=655,2=0.000000
L 2.99783356 0.3045 3.00051703 0.30656614 1 P 0 ;0,1=655,2=0.000000
L 3.00051703 0.30656614 3.00205 0.30966644 1 P 0 ;0,1=655,2=0.000000
L 3.00205 0.30966644 3.00281654 0.31328327 1 P 0 ;0,1=655,2=0.000000
L 3.00281654 0.31328327 3.00205 0.31689921 1 P 0 ;0,1=655,2=0.000000
L 3.00205 0.31689921 2.9997498 0.31999951 1 P 0 ;0,1=655,2=0.000000
L 2.9997498 0.31999951 2.99706634 0.32103356 1 P 0 ;0,1=655,2=0.000000
L 2.99706634 0.32103356 2.98518337 0.32103356 1 P 0 ;0,1=655,2=0.000000
L 3.01656663 0.31069961 3.01886614 0.30708278 1 P 0 ;0,1=655,2=0.000000
L 3.01886614 0.30708278 3.02193287 0.30501654 1 P 0 ;0,1=655,2=0.000000
L 3.02193287 0.30501654 3.02538356 0.3045 1 P 0 ;0,1=655,2=0.000000
L 3.02538356 0.3045 3.0284503 0.30501654 1 P 0 ;0,1=655,2=0.000000
L 3.0284503 0.30501654 3.03151703 0.30759931 1 P 0 ;0,1=655,2=0.000000
L 3.03151703 0.30759931 3.03343327 0.31069961 1 P 0 ;0,1=655,2=0.000000
L 3.03343327 0.31069961 3.03381654 0.3137999 1 P 0 ;0,1=655,2=0.000000
L 3.03381654 0.3137999 3.03305 0.31741575 1 P 0 ;0,1=655,2=0.000000
L 3.03305 0.31741575 3.03036654 0.31999951 1 P 0 ;0,1=655,2=0.000000
L 3.03036654 0.31999951 3.02768307 0.32103356 1 P 0 ;0,1=655,2=0.000000
L 3.02768307 0.32103356 3.02423307 0.32103356 1 P 0 ;0,1=655,2=0.000000
L 3.02768307 0.32103356 3.02998327 0.32258317 1 P 0 ;0,1=655,2=0.000000
L 3.02998327 0.32258317 3.0319002 0.32516594 1 P 0 ;0,1=655,2=0.000000
L 3.0319002 0.32516594 3.03266673 0.32826624 1 P 0 ;0,1=655,2=0.000000
L 3.03266673 0.32826624 3.0319002 0.33136654 1 P 0 ;0,1=655,2=0.000000
L 3.0319002 0.33136654 3.02998327 0.33394931 1 P 0 ;0,1=655,2=0.000000
L 3.02998327 0.33394931 3.02653327 0.3355 1 P 0 ;0,1=655,2=0.000000
L 3.02653327 0.3355 3.02308337 0.33498337 1 P 0 ;0,1=655,2=0.000000
L 3.02308337 0.33498337 3.01963337 0.33291624 1 P 0 ;0,1=655,2=0.000000
L 3.04871644 0.33033346 3.05101663 0.33343278 1 P 0 ;0,1=655,2=0.000000
L 3.05101663 0.33343278 3.0537001 0.33498337 1 P 0 ;0,1=655,2=0.000000
L 3.0537001 0.33498337 3.05676683 0.3355 1 P 0 ;0,1=655,2=0.000000
L 3.05676683 0.3355 3.0606 0.33446683 1 P 0 ;0,1=655,2=0.000000
L 3.0606 0.33446683 3.06328346 0.33188307 1 P 0 ;0,1=655,2=0.000000
L 3.06328346 0.33188307 3.06405 0.32878376 1 P 0 ;0,1=655,2=0.000000
L 3.06405 0.32878376 3.06366673 0.32568258 1 P 0 ;0,1=655,2=0.000000
L 3.06366673 0.32568258 3.06213307 0.3230998 1 P 0 ;0,1=655,2=0.000000
L 3.06213307 0.3230998 3.05446663 0.31793327 1 P 0 ;0,1=655,2=0.000000
L 3.05446663 0.31793327 3.05101663 0.31431644 1 P 0 ;0,1=655,2=0.000000
L 3.05101663 0.31431644 3.04871644 0.30914892 1 P 0 ;0,1=655,2=0.000000
L 3.04871644 0.30914892 3.0479499 0.3045 1 P 0 ;0,1=655,2=0.000000
L 3.0479499 0.3045 3.06405 0.3045 1 P 0 ;0,1=655,2=0.000000

### steps/pcb/layers/top/features
#
#Num Features
#
F 9918

#
#Units
#
U INCH

#
#Feature symbol names
#
$0 r3.9
$1 r4.7
$2 r5
$3 r5.7
$4 r6
$5 r8
$6 r10
$7 r12
$8 r15
$9 r18
$10 r19.7
$11 r20
$12 r24
$13 r40
$14 r57
$15 r86
$16 r90
$17 r100
$18 r104
$19 r108
$20 r115
$21 r244
$22 s1
$23 s20
$24 s31
$25 s104
$26 s115
$27 oval75x35 I
$28 rect104x45 I
$29 rect106x8 I
$30 rect10x23 I
$31 rect10x24 I
$32 rect11x14 I
$33 rect12x15 I
$34 rect12x24 I
$35 rect12x38 I
$36 rect12x41 I
$37 rect12x45 I
$38 rect12x46 I
$39 rect12x49 I
$40 rect12x64 I
$41 rect138x116 I
$42 rect13x44 I
$43 rect140x50 I
$44 rect146x96 I
$45 rect14x11 I
$46 rect14x62 I
$47 rect15x12 I
$48 rect16x45 I
$49 rect17x24 I
$50 rect18x60 I
$51 rect20x18 I
$52 rect20x24 I
$53 rect20x47 I
$54 rect228x244 I
$55 rect24x10 I
$56 rect24x12 I
$57 rect24x20 I
$58 rect24x28 I
$59 rect25x35 I
$60 rect27x10 I
$61 rect28x126 I
$62 rect28x165 I
$63 rect28x24 I
$64 rect30x34 I
$65 rect33x12 I
$66 rect33x17 I
$67 rect34x30 I
$68 rect35x33 I
$69 rect37x8 I
$70 rect38x13 I
$71 rect38x54 I
$72 rect39x41 I
$73 rect39x55 I
$74 rect39x57 I
$75 rect41x12 I
$76 rect41x87 I
$77 rect43x57 I
$78 rect45x104 I
$79 rect45x12 I
$80 rect45x16 I
$81 rect46x12 I
$82 rect47x12 I
$83 rect47x20 I
$84 rect49x10 I
$85 rect49x12 I
$86 rect50x140 I
$87 rect53x16 I
$88 rect54x38 I
$89 rect55x33 I
$90 rect55x39 I
$91 rect55x47 I
$92 rect57x71 I
$93 rect60x18 I
$94 rect62x14 I
$95 rect63x118 I
$96 rect64x12 I
$97 rect65x20 I
$98 rect71x10 I
$99 rect71x39 I
$100 rect71x57 I
$101 rect71x96 I
$102 rect72x20 I
$103 rect74.8x70.86xr19.68x12 I
$104 rect74.8x70.86xr19.68x34 I
$105 rect75x59 I
$106 rect88x40 I
$107 rect88x56 I
$108 rect8x106 I
$109 rect8x53 I
$110 rect92x56 I
$111 rect94x130 I
$112 rect96x146 I
$113 sh041x021-l+1
$114 sh041x021-l+3
$115 sh041x021-l+5
$116 sh041x021-l+7
$117 sh041x021-r+1
$118 sh041x021-r+3
$119 sh041x021-r+5
$120 sh041x021-r+7
$121 sh052x046+1

#
#Feature attribute names
#
@0 .smd
@1 .nomenclature
@2 .geometry
@3 .string
@4 .pad_usage
@5 .string_angle

#
#Feature attribute text strings
#
&0 S049X012
&1 V010C020P_TP030B
&2 S028X024
&3 S046X012
&4 V008C018P-ANTI28-NSM
&5 S020C_CST_V2
&6 S020X047
&7 V010C020P
&8 TPV010CT020B030
&9 V008C018P_ANTI026_TP030B
&10 S014X062
&11 S024X017
&12 S035X025
&13 S039X055
&14 S012X015
&15 V008C018P_NATI28_TP030B_NSMT
&16 S020SQ
&17 016C024P
&18 S012X064
&19 S030X034
&20 S040X088
&21 S038X054
&22 S041X012
&23 SH041X021-R
&24 V008C018P_TP030B
&25 S094X130
&26 V008C018P
&27 S049X010-NSM
&28 SH052X046
&29 S001X001
&30 S228X244-NSM
&31 S062X014
&32 SH041X021-L
&33 S055X047
&34 S056X088
&35 S056X092
&36 S031SQ
&37 S050X140
&38 V008C018P_ANTI28
&39 S072X020
&40 S033X035
&41 S018X020
&42 S018X060
&43 S038X012
&44 059C086P
&45 S057X039
&46 S012X049
&47 S012X046
&48 S014X011
&49 S027X010
&50 S010X023
&51 S033X055
&52 S011X014
&53 S033X012
&54 S039X041
&55 S008X037
&56 S016X053
&57 S045X104
&58 S013X038
&59 S020X065
&60 S116X138
&61 S008X106
&62 S010X024
&63 S020X024
&64 S024X012
&65 S013X044
&66 S045X016
&67 V008C018P_ANTI026_NSM
&68 S053X008
&69 S096X146
&70 S047X012
&71 076S104P
&72 076C104P
&73 S063X118
&74 EFT028X165
&75 079C100P
&76 S010X071
&77 S033X017
&78 S071X096-NSM
&79 V010C020P_SM014-NTH
&80 EFT028X126
&81 S039X071-NSM
&82 V012C024-NTH
&83 S057X071-NSM
&84 S115SQ-NSM
&85 S057X043
&86 024X063OB035X075P
&87 S045X012
&88 S041X087
&89 166CT244CB198P
&90 S059X075
&91 024X051OB071X075P_R
&92 024X051OB071X075P_L
&93 033C057P
&94 063C090P
&95 TOP
&96 2022-02-25
&97 R4006-B0001-02_R01
&98 FID040
&99 MTH100C090N
&100 MTH125C115N
&101 MTH118C108N
&102 P/N : R4006-B0001-02
&103 Date: 2022-02-25
&104 Layer:
&105 Rev : 01

#
#Layer features
#
S P 0
OB 2.805669980315 1.121430019685 I
OC 2.805669980315 1.121430019685 2.685669980315 1.121430019685 Y
OE
OB 2.748169980315 1.121430019685 H
OC 2.748169980315 1.121430019685 2.685669980315 1.121430019685 N
OE
SE
L 4.31 4.065 4.31 4.039 1 P 0 
L 4.31 4.039 4.30236998 4.03136998 1 P 0 
L 4.30236998 4.03136998 4.2391 4.03136998 1 P 0 
P 4.2391 4.03136998 85 P 0 8 0;0,2=0,4=0
L 4.354 4.065 4.31 4.065 1 P 0 
P 4.31 4.065 11 P 0 8 0;2=1,4=1
P 4.354 4.065 63 P 0 8 0;0,2=2,4=0
P 4.2406 4.05106004 81 P 0 8 0;0,2=3,4=0
L 4.31 4.115 4.28 4.085 1 P 0 
L 4.28 4.085 4.28 4.07 1 P 0 
L 4.28 4.07 4.26106004 4.05106004 1 P 0 
L 4.26106004 4.05106004 4.2406 4.05106004 1 P 0 
L 4.354 4.115 4.31 4.115 1 P 0 
P 4.31 4.115 11 P 0 8 0;2=1,4=1
P 4.354 4.115 63 P 0 8 0;0,2=2,4=0
L 4.61 2.3 4.649 2.3 1 P 0 
L 4.649 2.3 4.65 2.299 1 P 0 
P 4.61 2.3 11 P 0 8 0;2=1,4=1
P 4.65 2.299 58 P 0 8 0;0,2=2,4=0
P 4.50185 2.05996004 9 P 0 8 0;2=4,4=1
L 4.48216998 2.04028002 4.50185 2.05996004 1 P 0 
P 4.48216998 2.04028002 10 P 0 8 0;0,2=5,4=0
L 4.4428 2.11901998 4.46 2.13621998 1 P 0 
L 4.46 2.13621998 4.46 2.2 1 P 0 
L 4.46 2.2 4.49 2.23 1 P 0 
L 4.49 2.23 4.49 2.275 1 P 0 
L 4.49 2.275 4.535 2.275 1 P 0 
L 4.535 2.275 4.565 2.305 1 P 0 
L 4.565 2.305 4.565 2.33238996 1 P 0 
L 4.565 2.33238996 4.59735 2.36473996 1 P 0 
L 4.59735 2.36473996 4.59735 2.39236004 1 P 0 
L 4.59735 2.39236004 4.62 2.41501004 1 P 0 
L 4.62 2.41501004 4.62 2.419 1 P 0 
P 4.49 2.275 11 P 0 8 0;2=1,4=1
P 4.62 2.419 58 P 0 8 0;0,2=2,4=0
P 4.4428 2.11901998 10 P 0 8 0;0,2=5,4=0
L 4.40343002 2.11901998 4.42 2.13558996 1 P 0 
L 4.42 2.13558996 4.42 2.295 1 P 0 
L 4.42 2.295 4.435 2.31 1 P 0 
L 4.435 2.31 4.435 2.315 1 P 0 
L 4.435 2.315 4.47 2.35 1 P 0 
L 4.47 2.35 4.505 2.35 1 P 0 
L 4.505 2.35 4.51 2.355 1 P 0 
L 4.51 2.355 4.51 2.399 1 P 0 
L 4.51 2.399 4.53 2.419 1 P 0 
P 4.435 2.315 11 P 0 8 0;2=1,4=1
P 4.53 2.419 58 P 0 8 0;0,2=2,4=0
P 4.40343002 2.11901998 10 P 0 8 0;0,2=5,4=0
L 4.49 2.325 4.46 2.295 1 P 0 
L 4.46 2.295 4.46 2.2322 1 P 0 
L 4.46 2.2322 4.4428 2.215 1 P 0 
L 4.4428 2.215 4.4428 2.15838996 1 P 0 
L 4.49 2.325 4.534 2.325 1 P 0 
L 4.534 2.325 4.535 2.324 1 P 0 
P 4.49 2.325 11 P 0 8 0;2=1,4=1
P 4.535 2.324 58 P 0 8 0;0,2=2,4=0
P 4.4428 2.15838996 10 P 0 8 0;0,2=5,4=0
L 4.435 2.365 4.44 2.365 1 P 0 
L 4.44 2.365 4.465 2.39 1 P 0 
L 4.465 2.39 4.465 2.399 1 P 0 
L 4.465 2.399 4.485 2.419 1 P 0 
L 4.40343002 2.15838996 4.40343002 2.23843002 1 P 0 
L 4.40343002 2.23843002 4.395 2.24686004 1 P 0 
L 4.395 2.24686004 4.395 2.325 1 P 0 
L 4.395 2.325 4.435 2.365 1 P 0 
P 4.435 2.365 11 P 0 8 0;2=1,4=1
P 4.485 2.419 58 P 0 8 0;0,2=2,4=0
P 4.40343002 2.15838996 10 P 0 8 0;0,2=5,4=0
L 3.655 2.465 3.655 2.475 1 P 0 
L 3.655 2.475 3.6576 2.4776 1 P 0 
L 3.6576 2.4776 3.6576 2.5135 1 P 0 
L 3.705 2.426 3.666 2.465 1 P 0 
L 3.666 2.465 3.655 2.465 1 P 0 
L 3.705 2.426 3.76 2.426 1 P 0 
P 3.76 2.426 58 P 0 8 0;0,2=2,4=0
P 3.655 2.465 11 P 0 8 0;2=1,4=1
P 3.6576 2.5135 53 P 0 8 0;0,2=6,4=0
P 3.705 2.426 58 P 0 8 0;0,2=2,4=0
L 2.997 0.621 2.997 0.57541004 1 P 0 
L 2.997 0.57541004 2.996 0.57441004 1 P 0 
P 2.996 0.57441004 63 P 0 8 0;0,2=2,4=0
L 3.125 1.605 3.205 1.525 1 P 0 
L 3.205 1.525 3.205 1.21 1 P 0 
L 3.205 1.21 3.23 1.185 1 P 0 
L 3.23 1.185 3.23 0.855 1 P 0 
L 3.23 0.855 2.997 0.622 1 P 0 
L 2.997 0.622 2.997 0.621 1 P 0 
P 2.997 0.621 63 P 0 8 0;0,2=2,4=0
P 3.125 1.605 11 P 0 8 0;2=1,4=1
L 3.65 2.68 3.6576 2.6724 1 P 0 
L 3.6576 2.6724 3.6576 2.6265 1 P 0 
P 3.65 2.68 11 P 0 8 0;2=7,4=1
P 3.6576 2.6265 53 P 0 8 0;0,2=6,4=0
P 3.12 2.645 11 P 0 8 0;2=7,4=1
L 3.765 2.69 3.745 2.71 1 P 0 
L 3.745 2.71 3.731 2.71 1 P 0 
P 4.1869 2.09933002 9 P 0 8 0;2=4,4=1
L 4.20658002 2.07965 4.1869 2.09933002 1 P 0 
P 4.20658002 2.07965 10 P 0 8 0;0,2=5,4=0
P 3.765 2.69 11 P 0 8 0;2=1,4=1
P 3.7324 2.6265 53 P 0 8 0;0,2=6,4=0
L 3.7324 2.6265 3.7324 2.7086 1 P 0 
L 3.7324 2.7086 3.731 2.71 1 P 0 
P 3.731 2.71 63 P 0 8 0;0,2=2,4=0
L 4.48216998 1.52846998 4.50185 1.50878996 1 P 0 
P 4.50185 1.50878996 9 P 0 8 0;2=4,4=1
P 4.48216998 1.52846998 10 P 0 8 0;0,2=5,4=0
P 4.2406 3.93293996 81 P 0 8 0;0,2=3,4=0
P 4.3 3.865 11 P 0 8 0;2=8,4=0
L 4.3 3.865 4.283 3.882 1 P 0 
L 4.283 3.882 4.283 3.918 1 P 0 
L 4.283 3.918 4.26806004 3.93293996 1 P 0 
L 4.26806004 3.93293996 4.2406 3.93293996 1 P 0 
P 4.354 3.865 63 P 0 8 0;0,2=2,4=0
L 4.354 3.865 4.3 3.865 1 P 0 
L 3.36525 3.305 3.36525 3.2865 1 P 0 
L 3.36525 3.2865 3.35536004 3.27661004 1 P 0 
L 3.35536004 3.27661004 3.2815 3.27661004 1 P 0 
P 3.36525 3.305 9 P 0 8 0;2=9,4=1
P 3.2815 3.27661004 94 P 0 8 0;0,2=10,4=0
P 3.37 3.44 11 P 0 8 0;2=8,4=0
L 4.736 0.915 4.736 0.965 1 P 0 
L 4.795 0.925 4.77236004 0.925 1 P 0 
L 4.77236004 0.925 4.76236004 0.915 1 P 0 
L 4.76236004 0.915 4.736 0.915 1 P 0 
L 4.795 0.925 4.83671004 0.925 1 P 0 
L 4.83671004 0.925 4.84213996 0.91956998 1 P 0 
L 4.84213996 0.91956998 4.8855 0.91956998 1 P 0 
P 4.795 0.925 11 P 0 8 0;2=8,4=0
P 4.8855 0.91956998 94 P 0 8 0;0,2=10,4=0
P 4.736 0.965 63 P 0 8 0;0,2=2,4=0
P 4.736 0.915 63 P 0 8 0;0,2=2,4=0
L 4.08 3.27 4.08 3.32 1 P 0 
L 4.08 3.32 4.09 3.33 1 P 0 
L 4.09 3.33 4.185 3.33 1 P 0 
L 4.185 3.33 4.20058996 3.34558996 1 P 0 
L 4.20058996 3.34558996 4.20058996 3.4076 1 P 0 
L 4.00558996 3.4056 4.00558996 3.3994 1 P 0 
L 4.00558996 3.3994 4.015 3.38998996 1 P 0 
L 4.015 3.38998996 4.015 3.291 1 P 0 
L 4.08 3.27 4.08 3.265 1 P 0 
L 4.08 3.265 4.055 3.24 1 P 0 
L 4.055 3.24 4.015 3.24 1 P 0 
L 4.08 3.27 4.105 3.27 1 P 0 
L 4.105 3.27 4.12943002 3.24556998 1 P 0 
L 4.12943002 3.24556998 4.1695 3.24556998 1 P 0 
L 4.015 3.24 4.015 3.291 1 P 0 
L 4.015 3.239 4.015 3.24 1 P 0 
P 4.08 3.27 11 P 0 8 0;2=8,4=0
P 4.20058996 3.4076 49 P 0 8 0;0,2=11,4=0
P 4.1695 3.24556998 94 P 0 8 0;0,2=10,4=0
P 4.015 3.291 63 P 0 8 0;0,2=2,4=0
P 4.015 3.239 63 P 0 8 0;0,2=2,4=0
P 4.00558996 3.4056 49 P 0 8 0;0,2=11,4=0
L 3.95 3.82 3.94 3.81 1 P 0 
L 3.94 3.81 3.881 3.81 1 P 0 
L 4.0355 3.76456998 4.00543002 3.76456998 1 P 0 
L 4.00543002 3.76456998 3.95 3.82 1 P 0 
P 3.95 3.82 11 P 0 8 0;2=8,4=0
P 4.0355 3.76456998 94 P 0 8 0;0,2=10,4=0
P 3.881 3.758 63 P 0 8 0;0,2=2,4=0
L 3.881 3.758 3.881 3.81 1 P 0 
P 3.881 3.81 63 P 0 8 0;0,2=2,4=0
P 3.746 1.782 11 P 0 8 0;2=8,4=0
L 4.08846998 1.60721004 4.06878996 1.58753002 1 P 0 
P 4.08846998 1.60721004 10 P 0 8 0;0,2=5,4=0
P 4.06878996 1.58753002 9 P 0 8 0;2=4,4=1
L 4.314 0.82366004 4.26366004 0.82366004 1 P 0 
L 4.26366004 0.82366004 4.26 0.82 1 P 0 
L 4.26 0.82 4.205 0.82 1 P 0 
L 4.205 0.879 4.205 0.82 1 P 0 
P 4.205 0.82 11 P 0 8 0;2=8,4=0
P 4.205 0.879 58 P 0 8 0;0,2=2,4=0
P 4.314 0.82366004 59 P 0 8 0;0,2=12,4=0
P 3.82286004 0.86213996 11 P 0 8 0;2=1,4=1
L 3.82286004 0.86213996 3.811 0.874 1 P 0 
L 3.811 0.874 3.77 0.874 1 P 0 
L 3.77 0.874 3.739 0.874 1 P 0 
L 3.739 0.874 3.705 0.84 1 P 0 
P 3.705 0.84 11 P 0 8 0;2=8,4=0
L 3.88 0.75216998 3.88 0.805 1 P 0 
L 3.88 0.805 3.82286004 0.86213996 1 P 0 
P 3.88 0.75216998 90 P 0 8 0;0,2=13,4=0
P 3.77 0.874 58 P 0 8 0;0,2=2,4=0
L 0.496 2.13455 0.496 2.16556998 1 P 0 
L 0.496 2.16556998 0.49556998 2.166 1 P 0 
P 0.49556998 2.166 33 P 0 8 0;0,2=14,4=0
P 0.496 2.13455 11 P 0 8 0;2=1,4=1
L 0.528 2.72 0.51743002 2.70943002 1 P 0 
L 0.51743002 2.70943002 0.51743002 2.68 1 P 0 
P 0.51743002 2.68 33 P 0 8 0;0,2=14,4=0
P 0.528 2.72 11 P 0 8 0;2=1,4=1
L 0.575 1.015 0.56 1 1 P 0 
L 0.56 1 0.52443002 1 1 P 0 
P 0.52443002 1 33 P 0 8 0;0,2=14,4=0
P 0.575 1.015 11 P 0 8 0;2=1,4=1
L 0.48956998 1.53618996 0.48956998 1.57 1 P 0 
P 0.48956998 1.57 33 P 0 8 0;0,2=14,4=0
P 0.48956998 1.53618996 11 P 0 8 0;2=1,4=1
P 4.63965 1.96153996 10 P 0 8 0;0,2=5,4=0
P 4.65933002 1.98121998 9 P 0 8 0;2=4,4=1
L 4.63965 1.96153996 4.65933002 1.98121998 1 P 0 
P 4.06878996 1.90248002 9 P 0 8 0;2=4,4=1
L 4.08846998 1.8828 4.06878996 1.90248002 1 P 0 
P 4.08846998 1.8828 10 P 0 8 0;0,2=5,4=0
P 4.48216998 1.41035 10 P 0 8 0;0,2=5,4=0
P 4.50185 1.39066998 9 P 0 8 0;2=4,4=1
L 4.48216998 1.41035 4.50185 1.39066998 1 P 0 
P 4.06878996 2.1387 9 P 0 8 0;2=4,4=1
L 4.08846998 2.11901998 4.06878996 2.1387 1 P 0 
P 4.08846998 2.11901998 10 P 0 8 0;0,2=5,4=0
P 3.93098002 2.00091004 10 P 0 8 0;0,2=5,4=0
P 3.93098002 1.96153996 10 P 0 8 0;0,2=5,4=0
P 4.22626998 2.05996004 9 P 0 8 0;2=4,4=1
L 4.24595 2.04028002 4.22626998 2.05996004 1 P 0 
P 4.24595 2.04028002 10 P 0 8 0;0,2=5,4=0
P 3.97035 2.04028002 10 P 0 8 0;0,2=5,4=0
P 3.95066998 2.05996004 9 P 0 8 0;2=4,4=1
L 3.97035 2.04028002 3.95066998 2.05996004 1 P 0 
P 4.22626998 2.02058996 9 P 0 8 0;2=4,4=1
L 4.24595 2.00091004 4.22626998 2.02058996 1 P 0 
P 4.24595 2.00091004 10 P 0 8 0;0,2=5,4=0
P 4.28531998 2.07965 10 P 0 8 0;0,2=5,4=0
P 4.26563996 2.09933002 9 P 0 8 0;2=4,4=1
L 4.28531998 2.07965 4.26563996 2.09933002 1 P 0 
P 4.28531998 2.04028002 10 P 0 8 0;0,2=5,4=0
P 4.26563996 2.05996004 9 P 0 8 0;2=4,4=1
L 4.28531998 2.04028002 4.26563996 2.05996004 1 P 0 
P 4.50185 1.90248002 9 P 0 8 0;2=4,4=1
L 4.50185 1.90248002 4.48216998 1.8828 1 P 0 
P 4.48216998 1.8828 10 P 0 8 0;0,2=5,4=0
P 4.73806998 2.09933002 9 P 0 8 0;2=4,4=1
L 4.71838996 2.07965 4.73806998 2.09933002 1 P 0 
P 4.71838996 2.07965 10 P 0 8 0;0,2=5,4=0
P 4.02941998 2.02058996 9 P 0 8 0;2=4,4=1
L 4.0491 2.00091004 4.02941998 2.02058996 1 P 0 
P 4.0491 2.00091004 10 P 0 8 0;0,2=5,4=0
P 4.48216998 1.84343002 10 P 0 8 0;0,2=5,4=0
P 4.50185 1.86311004 9 P 0 8 0;2=4,4=1
L 4.48216998 1.84343002 4.50185 1.86311004 1 P 0 
P 4.6987 2.05996004 9 P 0 8 0;2=4,4=1
L 4.67901998 2.04028002 4.6987 2.05996004 1 P 0 
P 4.67901998 2.04028002 10 P 0 8 0;0,2=5,4=0
P 4.60028002 1.92216998 10 P 0 8 0;0,2=5,4=0
P 4.61996004 1.94185 9 P 0 8 0;2=4,4=1
L 4.60028002 1.92216998 4.61996004 1.94185 1 P 0 
P 4.60028002 1.96153996 10 P 0 8 0;0,2=5,4=0
P 4.61996004 1.98121998 9 P 0 8 0;2=4,4=1
L 4.60028002 1.96153996 4.61996004 1.98121998 1 P 0 
P 4.26563996 2.02058996 9 P 0 8 0;2=4,4=1
L 4.28531998 2.00091004 4.26563996 2.02058996 1 P 0 
P 4.28531998 2.00091004 10 P 0 8 0;0,2=5,4=0
P 4.60028002 1.8828 10 P 0 8 0;0,2=5,4=0
P 4.61996004 1.90248002 9 P 0 8 0;2=4,4=1
L 4.60028002 1.8828 4.61996004 1.90248002 1 P 0 
P 4.56091004 1.96153996 10 P 0 8 0;0,2=5,4=0
P 4.58058996 1.98121998 9 P 0 8 0;2=4,4=1
L 4.56091004 1.96153996 4.58058996 1.98121998 1 P 0 
P 3.89161004 2.04028002 10 P 0 8 0;0,2=5,4=0
P 4.54121998 2.02058996 9 P 0 8 0;2=4,4=1
L 4.52153996 2.00091004 4.54121998 2.02058996 1 P 0 
P 4.52153996 2.00091004 10 P 0 8 0;0,2=5,4=0
P 4.34436998 2.09933002 9 P 0 8 0;2=4,4=1
L 4.32468996 2.07965 4.34436998 2.09933002 1 P 0 
P 4.32468996 2.07965 10 P 0 8 0;0,2=5,4=0
P 4.08846998 2.07965 10 P 0 8 0;0,2=5,4=0
P 4.06878996 2.09933002 9 P 0 8 0;2=15,4=1
L 4.08846998 2.07965 4.06878996 2.09933002 1 P 0 
P 4.6987 1.50878996 9 P 0 8 0;2=4,4=1
L 4.67901998 1.52846998 4.6987 1.50878996 1 P 0 
P 4.67901998 1.52846998 10 P 0 8 0;0,2=5,4=0
P 4.54121998 1.98121998 9 P 0 8 0;2=4,4=1
L 4.52153996 1.96153996 4.54121998 1.98121998 1 P 0 
P 4.52153996 1.96153996 10 P 0 8 0;0,2=5,4=0
P 4.08846998 2.04028002 10 P 0 8 0;0,2=5,4=0
P 4.06878996 2.05996004 9 P 0 8 0;2=4,4=1
L 4.08846998 2.04028002 4.06878996 2.05996004 1 P 0 
P 4.65933002 1.50878996 9 P 0 8 0;2=4,4=1
L 4.63965 1.52846998 4.65933002 1.50878996 1 P 0 
P 4.63965 1.52846998 10 P 0 8 0;0,2=5,4=0
P 3.97035 2.07965 10 P 0 8 0;0,2=5,4=0
P 3.95066998 2.09933002 9 P 0 8 0;2=4,4=1
L 3.97035 2.07965 3.95066998 2.09933002 1 P 0 
P 4.60028002 1.56783996 10 P 0 8 0;0,2=5,4=0
P 4.61996004 1.54816004 9 P 0 8 0;2=4,4=1
L 4.60028002 1.56783996 4.61996004 1.54816004 1 P 0 
P 4.00973002 2.07965 10 P 0 8 0;0,2=5,4=0
L 4.00973002 2.07965 3.99005 2.09933002 1 P 0 
P 3.99005 2.09933002 9 P 0 8 0;2=15,4=1
P 4.56091004 1.56783996 10 P 0 8 0;0,2=5,4=0
P 4.58058996 1.54816004 9 P 0 8 0;2=4,4=1
L 4.56091004 1.56783996 4.58058996 1.54816004 1 P 0 
P 4.6987 1.94185 9 P 0 8 0;2=4,4=1
L 4.67901998 1.92216998 4.6987 1.94185 1 P 0 
P 4.67901998 1.92216998 10 P 0 8 0;0,2=5,4=0
P 4.50185 2.02058996 9 P 0 8 0;2=4,4=1
L 4.48216998 2.00091004 4.50185 2.02058996 1 P 0 
P 4.48216998 2.00091004 10 P 0 8 0;0,2=5,4=0
P 4.46248002 2.02058996 9 P 0 8 0;2=4,4=1
L 4.4428 2.00091004 4.46248002 2.02058996 1 P 0 
P 4.4428 2.00091004 10 P 0 8 0;0,2=5,4=0
P 4.42311004 1.98121998 9 P 0 8 0;2=4,4=1
L 4.40343002 1.96153996 4.42311004 1.98121998 1 P 0 
P 4.40343002 1.96153996 10 P 0 8 0;0,2=5,4=0
P 4.4428 1.92216998 10 P 0 8 0;0,2=5,4=0
P 4.46248002 1.94185 9 P 0 8 0;2=4,4=1
L 4.4428 1.92216998 4.46248002 1.94185 1 P 0 
P 4.38373996 1.86311004 9 P 0 8 0;2=4,4=1
L 4.36406004 1.84343002 4.38373996 1.86311004 1 P 0 
P 4.36406004 1.84343002 10 P 0 8 0;0,2=5,4=0
P 4.38373996 1.82373996 9 P 0 8 0;2=4,4=1
L 4.36406004 1.80406004 4.38373996 1.82373996 1 P 0 
P 4.36406004 1.80406004 10 P 0 8 0;0,2=5,4=0
P 4.46248002 1.98121998 9 P 0 8 0;2=4,4=1
L 4.4428 1.96153996 4.46248002 1.98121998 1 P 0 
P 4.4428 1.96153996 10 P 0 8 0;0,2=5,4=0
P 4.12783996 1.92216998 10 P 0 8 0;0,2=5,4=0
P 4.10816004 1.94185 9 P 0 8 0;2=4,4=1
L 4.12783996 1.92216998 4.10816004 1.94185 1 P 0 
P 4.0491 1.96153996 10 P 0 8 0;0,2=5,4=0
P 4.02941998 1.98121998 9 P 0 8 0;2=4,4=1
L 4.0491 1.96153996 4.02941998 1.98121998 1 P 0 
P 4.58058996 2.17806998 9 P 0 8 0;2=4,4=1
L 4.56091004 2.15838996 4.58058996 2.17806998 1 P 0 
P 4.56091004 2.15838996 10 P 0 8 0;0,2=5,4=0
P 4.73806998 1.90248002 9 P 0 8 0;2=4,4=1
L 4.71838996 1.8828 4.73806998 1.90248002 1 P 0 
P 4.71838996 1.8828 10 P 0 8 0;0,2=5,4=0
P 4.54121998 2.1387 9 P 0 8 0;2=4,4=1
L 4.52153996 2.11901998 4.54121998 2.1387 1 P 0 
P 4.52153996 2.11901998 10 P 0 8 0;0,2=5,4=0
P 4.12783996 2.00091004 10 P 0 8 0;0,2=5,4=0
P 4.10816004 2.02058996 9 P 0 8 0;2=4,4=1
L 4.12783996 2.00091004 4.10816004 2.02058996 1 P 0 
P 4.50185 2.1387 9 P 0 8 0;2=4,4=1
L 4.48216998 2.11901998 4.50185 2.1387 1 P 0 
P 4.48216998 2.11901998 10 P 0 8 0;0,2=5,4=0
P 4.00973002 1.92216998 10 P 0 8 0;0,2=5,4=0
P 3.99005 1.94185 9 P 0 8 0;2=4,4=1
L 4.00973002 1.92216998 3.99005 1.94185 1 P 0 
P 4.0491 1.92216998 10 P 0 8 0;0,2=5,4=0
P 4.02941998 1.94185 9 P 0 8 0;2=4,4=1
L 4.0491 1.92216998 4.02941998 1.94185 1 P 0 
P 4.48216998 2.07965 10 P 0 8 0;0,2=5,4=0
P 4.50185 2.09933002 9 P 0 8 0;2=4,4=1
L 4.48216998 2.07965 4.50185 2.09933002 1 P 0 
P 4.16721004 2.00091004 10 P 0 8 0;0,2=5,4=0
P 4.14753002 2.02058996 9 P 0 8 0;2=4,4=1
L 4.16721004 2.00091004 4.14753002 2.02058996 1 P 0 
P 4.61996004 2.17806998 9 P 0 8 0;2=4,4=1
L 4.60028002 2.15838996 4.61996004 2.17806998 1 P 0 
P 4.60028002 2.15838996 10 P 0 8 0;0,2=5,4=0
P 3.93098002 1.92216998 10 P 0 8 0;0,2=5,4=0
P 3.93098002 1.8828 10 P 0 8 0;0,2=5,4=0
P 4.63965 2.15838996 10 P 0 8 0;0,2=5,4=0
P 3.89161004 1.92216998 10 P 0 8 0;0,2=5,4=0
P 4.63965 2.11901998 10 P 0 8 0;0,2=5,4=0
P 3.89161004 1.8828 10 P 0 8 0;0,2=5,4=0
P 4.02941998 1.86311004 9 P 0 8 0;2=4,4=1
L 4.0491 1.84343002 4.02941998 1.86311004 1 P 0 
P 4.0491 1.84343002 10 P 0 8 0;0,2=5,4=0
P 4.06878996 1.43005 9 P 0 8 0;2=4,4=1
L 4.08846998 1.44973002 4.06878996 1.43005 1 P 0 
P 4.08846998 1.44973002 10 P 0 8 0;0,2=5,4=0
P 4.54121998 1.54816004 9 P 0 8 0;2=4,4=1
L 4.52153996 1.56783996 4.54121998 1.54816004 1 P 0 
P 4.52153996 1.56783996 10 P 0 8 0;0,2=5,4=0
P 4.26563996 1.50878996 9 P 0 8 0;2=4,4=1
L 4.28531998 1.52846998 4.26563996 1.50878996 1 P 0 
P 4.28531998 1.52846998 10 P 0 8 0;0,2=5,4=0
P 4.20658002 1.92216998 10 P 0 8 0;0,2=5,4=0
P 4.1869 1.94185 9 P 0 8 0;2=4,4=1
L 4.20658002 1.92216998 4.1869 1.94185 1 P 0 
P 4.14753002 1.46941998 9 P 0 8 0;2=4,4=1
P 4.16721004 1.4891 10 P 0 8 0;0,2=5,4=0
L 4.16721004 1.4891 4.14753002 1.46941998 1 P 0 
P 4.20658002 1.4891 10 P 0 8 0;0,2=5,4=0
P 4.1869 1.46941998 9 P 0 8 0;2=4,4=1
L 4.20658002 1.4891 4.1869 1.46941998 1 P 0 
P 4.1869 2.1387 9 P 0 8 0;2=4,4=1
L 4.20658002 2.11901998 4.1869 2.1387 1 P 0 
P 4.20658002 2.11901998 10 P 0 8 0;0,2=5,4=0
P 4.6987 1.43005 9 P 0 8 0;2=4,4=1
L 4.67901998 1.44973002 4.6987 1.43005 1 P 0 
P 4.67901998 1.44973002 10 P 0 8 0;0,2=5,4=0
P 4.10816004 1.39066998 9 P 0 8 0;2=4,4=1
L 4.12783996 1.41035 4.10816004 1.39066998 1 P 0 
P 4.12783996 1.41035 10 P 0 8 0;0,2=5,4=0
P 4.65933002 1.43005 9 P 0 8 0;2=4,4=1
L 4.63965 1.44973002 4.65933002 1.43005 1 P 0 
P 4.63965 1.44973002 10 P 0 8 0;0,2=5,4=0
P 4.14753002 1.39066998 9 P 0 8 0;2=4,4=1
L 4.16721004 1.41035 4.14753002 1.39066998 1 P 0 
P 4.16721004 1.41035 10 P 0 8 0;0,2=5,4=0
P 4.60028002 1.44973002 10 P 0 8 0;0,2=5,4=0
P 4.61996004 1.43005 9 P 0 8 0;2=4,4=1
L 4.60028002 1.44973002 4.61996004 1.43005 1 P 0 
P 4.10816004 1.43005 9 P 0 8 0;2=4,4=1
L 4.12783996 1.44973002 4.10816004 1.43005 1 P 0 
P 4.12783996 1.44973002 10 P 0 8 0;0,2=5,4=0
P 4.56091004 1.44973002 10 P 0 8 0;0,2=5,4=0
P 4.58058996 1.43005 9 P 0 8 0;2=4,4=1
L 4.56091004 1.44973002 4.58058996 1.43005 1 P 0 
P 4.14753002 1.43005 9 P 0 8 0;2=4,4=1
L 4.16721004 1.44973002 4.14753002 1.43005 1 P 0 
P 4.16721004 1.44973002 10 P 0 8 0;0,2=5,4=0
P 4.20658002 1.44973002 10 P 0 8 0;0,2=5,4=0
P 4.1869 1.43005 9 P 0 8 0;2=4,4=1
L 4.20658002 1.44973002 4.1869 1.43005 1 P 0 
P 4.24595 1.44973002 10 P 0 8 0;0,2=5,4=0
P 4.22626998 1.43005 9 P 0 8 0;2=4,4=1
L 4.24595 1.44973002 4.22626998 1.43005 1 P 0 
P 4.54121998 1.46941998 9 P 0 8 0;2=4,4=1
L 4.52153996 1.4891 4.54121998 1.46941998 1 P 0 
P 4.52153996 1.4891 10 P 0 8 0;0,2=5,4=0
P 4.24595 1.41035 10 P 0 8 0;0,2=5,4=0
P 4.22626998 1.39066998 9 P 0 8 0;2=4,4=1
L 4.24595 1.41035 4.22626998 1.39066998 1 P 0 
P 4.50185 1.46941998 9 P 0 8 0;2=4,4=1
L 4.48216998 1.4891 4.50185 1.46941998 1 P 0 
P 4.48216998 1.4891 10 P 0 8 0;0,2=5,4=0
P 4.28531998 1.41035 10 P 0 8 0;0,2=5,4=0
P 4.26563996 1.39066998 9 P 0 8 0;2=4,4=1
L 4.28531998 1.41035 4.26563996 1.39066998 1 P 0 
P 4.61996004 1.46941998 9 P 0 8 0;2=4,4=1
L 4.60028002 1.4891 4.61996004 1.46941998 1 P 0 
P 4.60028002 1.4891 10 P 0 8 0;0,2=5,4=0
P 4.26563996 1.31193002 9 P 0 8 0;2=4,4=1
L 4.28531998 1.33161004 4.26563996 1.31193002 1 P 0 
P 4.28531998 1.33161004 10 P 0 8 0;0,2=5,4=0
P 4.60028002 1.52846998 10 P 0 8 0;0,2=5,4=0
P 4.61996004 1.50878996 9 P 0 8 0;2=4,4=1
L 4.60028002 1.52846998 4.61996004 1.50878996 1 P 0 
P 4.34436998 1.31193002 9 P 0 8 0;2=4,4=1
L 4.34436998 1.31193002 4.32468996 1.33161004 1 P 0 
P 4.32468996 1.33161004 10 P 0 8 0;0,2=5,4=0
P 4.58058996 1.46941998 9 P 0 8 0;2=4,4=1
L 4.56091004 1.4891 4.58058996 1.46941998 1 P 0 
P 4.56091004 1.4891 10 P 0 8 0;0,2=5,4=0
P 4.34436998 1.3513 9 P 0 8 0;2=4,4=1
L 4.34436998 1.3513 4.32468996 1.37098002 1 P 0 
P 4.32468996 1.37098002 10 P 0 8 0;0,2=5,4=0
P 4.54121998 1.50878996 9 P 0 8 0;2=4,4=1
L 4.52153996 1.52846998 4.54121998 1.50878996 1 P 0 
P 4.52153996 1.52846998 10 P 0 8 0;0,2=5,4=0
P 4.34436998 1.39066998 9 P 0 8 0;2=4,4=1
L 4.34436998 1.39066998 4.32468996 1.41035 1 P 0 
P 4.32468996 1.41035 10 P 0 8 0;0,2=5,4=0
P 4.20658002 1.52846998 10 P 0 8 0;0,2=5,4=0
P 4.1869 1.50878996 9 P 0 8 0;2=4,4=1
L 4.20658002 1.52846998 4.1869 1.50878996 1 P 0 
P 4.46248002 1.50878996 9 P 0 8 0;2=4,4=1
L 4.4428 1.52846998 4.46248002 1.50878996 1 P 0 
P 4.4428 1.52846998 10 P 0 8 0;0,2=5,4=0
P 4.24595 1.52846998 10 P 0 8 0;0,2=5,4=0
P 4.22626998 1.50878996 9 P 0 8 0;2=4,4=1
L 4.24595 1.52846998 4.22626998 1.50878996 1 P 0 
P 4.28531998 1.44973002 10 P 0 8 0;0,2=5,4=0
L 4.28531998 1.44973002 4.26563996 1.43005 1 P 0 
P 4.26563996 1.43005 9 P 0 8 0;2=15,4=1
P 4.28531998 1.4891 10 P 0 8 0;0,2=5,4=0
P 4.26563996 1.46941998 9 P 0 8 0;2=4,4=1
L 4.28531998 1.4891 4.26563996 1.46941998 1 P 0 
P 4.36406004 1.41035 10 P 0 8 0;0,2=5,4=0
P 4.38373996 1.39066998 9 P 0 8 0;2=4,4=1
L 4.36406004 1.41035 4.38373996 1.39066998 1 P 0 
P 4.36406004 1.44973002 10 P 0 8 0;0,2=5,4=0
P 4.38373996 1.43005 9 P 0 8 0;2=4,4=1
L 4.36406004 1.44973002 4.38373996 1.43005 1 P 0 
L 4.52153996 1.33161004 4.54121998 1.31193002 1 P 0 
P 4.54121998 1.31193002 9 P 0 8 0;2=4,4=1
P 4.52153996 1.33161004 10 P 0 8 0;0,2=5,4=0
P 3.89161004 1.33161004 10 P 0 8 0;0,2=5,4=0
P 4.49876004 1.31501998 9 P 0 8 0;2=4,4=1
L 4.49876004 1.31501998 4.48216998 1.33161004 1 P 0 
P 4.48216998 1.33161004 10 P 0 8 0;0,2=5,4=0
P 3.93098002 1.33161004 10 P 0 8 0;0,2=5,4=0
P 4.34436998 1.98121998 9 P 0 8 0;2=4,4=1
L 4.32468996 1.96153996 4.34436998 1.98121998 1 P 0 
P 4.32468996 1.96153996 10 P 0 8 0;0,2=5,4=0
P 4.57843996 1.35345 9 P 0 8 0;2=4,4=1
L 4.57843996 1.35345 4.56091004 1.37098002 1 P 0 
P 4.56091004 1.37098002 10 P 0 8 0;0,2=5,4=0
P 3.9113 1.3513 9 P 0 8 0;2=4,4=1
L 3.93098002 1.37098002 3.9113 1.3513 1 P 0 
P 3.93098002 1.37098002 10 P 0 8 0;0,2=5,4=0
L 4.52153996 1.37098002 4.54121998 1.3513 1 P 0 
P 4.54121998 1.3513 9 P 0 8 0;2=4,4=1
P 4.52153996 1.37098002 10 P 0 8 0;0,2=5,4=0
P 3.95066998 1.3513 9 P 0 8 0;2=4,4=1
L 3.95066998 1.3513 3.97035 1.37098002 1 P 0 
P 3.97035 1.37098002 10 P 0 8 0;0,2=5,4=0
P 4.45938996 1.35438996 9 P 0 8 0;2=4,4=1
L 4.45938996 1.35438996 4.4428 1.37098002 1 P 0 
P 4.4428 1.37098002 10 P 0 8 0;0,2=5,4=0
P 3.99 1.31188002 9 P 0 8 0;2=4,4=1
L 3.99 1.31188002 4.00973002 1.33161004 1 P 0 
P 4.00973002 1.33161004 10 P 0 8 0;0,2=5,4=0
P 4.4428 1.41035 10 P 0 8 0;0,2=5,4=0
P 4.46248002 1.39066998 9 P 0 8 0;2=4,4=1
L 4.4428 1.41035 4.46248002 1.39066998 1 P 0 
P 4.0491 1.33161004 10 P 0 8 0;0,2=5,4=0
P 4.65933002 1.3513 9 P 0 8 0;2=4,4=1
L 4.63965 1.37098002 4.65933002 1.3513 1 P 0 
P 4.63965 1.37098002 10 P 0 8 0;0,2=5,4=0
P 3.99 1.35125 9 P 0 8 0;2=4,4=1
L 3.99 1.35125 4.00973002 1.37098002 1 P 0 
P 4.00973002 1.37098002 10 P 0 8 0;0,2=5,4=0
P 4.61996004 1.3513 9 P 0 8 0;2=4,4=1
L 4.60028002 1.37098002 4.61996004 1.3513 1 P 0 
P 4.60028002 1.37098002 10 P 0 8 0;0,2=5,4=0
P 4.0491 1.37098002 10 P 0 8 0;0,2=5,4=0
P 4.6987 1.86311004 9 P 0 8 0;2=4,4=1
L 4.67901998 1.84343002 4.6987 1.86311004 1 P 0 
P 4.67901998 1.84343002 10 P 0 8 0;0,2=5,4=0
P 4.4428 2.04028002 10 P 0 8 0;0,2=5,4=0
P 4.46248002 2.05996004 9 P 0 8 0;2=4,4=1
L 4.4428 2.04028002 4.46248002 2.05996004 1 P 0 
P 4.06873996 1.31188002 9 P 0 8 0;2=4,4=1
L 4.06873996 1.31188002 4.08846998 1.33161004 1 P 0 
P 4.08846998 1.33161004 10 P 0 8 0;0,2=5,4=0
P 4.63965 1.80406004 10 P 0 8 0;0,2=5,4=0
P 4.65933002 1.82373996 9 P 0 8 0;2=4,4=1
L 4.63965 1.80406004 4.65933002 1.82373996 1 P 0 
P 4.40343002 2.04028002 10 P 0 8 0;0,2=5,4=0
P 4.42311004 2.05996004 9 P 0 8 0;2=4,4=1
L 4.40343002 2.04028002 4.42311004 2.05996004 1 P 0 
P 4.10811004 1.31188002 9 P 0 8 0;2=4,4=1
L 4.10811004 1.31188002 4.12783996 1.33161004 1 P 0 
P 4.12783996 1.33161004 10 P 0 8 0;0,2=5,4=0
P 4.56091004 1.41035 10 P 0 8 0;0,2=5,4=0
P 4.58058996 1.39066998 9 P 0 8 0;2=4,4=1
L 4.56091004 1.41035 4.58058996 1.39066998 1 P 0 
P 4.02941998 1.39066998 9 P 0 8 0;2=4,4=1
L 4.0491 1.41035 4.02941998 1.39066998 1 P 0 
P 4.0491 1.41035 10 P 0 8 0;0,2=5,4=0
P 4.52153996 1.41035 10 P 0 8 0;0,2=5,4=0
P 4.54121998 1.39066998 9 P 0 8 0;2=4,4=1
L 4.52153996 1.41035 4.54121998 1.39066998 1 P 0 
P 4.06878996 1.39066998 9 P 0 8 0;2=4,4=1
L 4.08846998 1.41035 4.06878996 1.39066998 1 P 0 
P 4.08846998 1.41035 10 P 0 8 0;0,2=5,4=0
P 4.73806998 1.78436998 9 P 0 8 0;2=4,4=1
L 4.71838996 1.76468996 4.73806998 1.78436998 1 P 0 
P 4.71838996 1.76468996 10 P 0 8 0;0,2=5,4=0
P 4.73806998 1.31193002 9 P 0 8 0;2=4,4=1
L 4.71838996 1.33161004 4.73806998 1.31193002 1 P 0 
P 4.71838996 1.33161004 10 P 0 8 0;0,2=5,4=0
P 4.1869 1.31193002 9 P 0 8 0;2=4,4=1
L 4.20658002 1.33161004 4.1869 1.31193002 1 P 0 
P 4.20658002 1.33161004 10 P 0 8 0;0,2=5,4=0
P 4.73806998 1.70563996 9 P 0 8 0;2=4,4=1
L 4.71838996 1.72531998 4.73806998 1.70563996 1 P 0 
P 4.71838996 1.72531998 10 P 0 8 0;0,2=5,4=0
P 4.6987 1.31193002 9 P 0 8 0;2=4,4=1
L 4.67901998 1.33161004 4.6987 1.31193002 1 P 0 
P 4.67901998 1.33161004 10 P 0 8 0;0,2=5,4=0
P 4.22626998 1.31193002 9 P 0 8 0;2=4,4=1
L 4.24595 1.33161004 4.22626998 1.31193002 1 P 0 
P 4.24595 1.33161004 10 P 0 8 0;0,2=5,4=0
P 4.10816004 1.3513 9 P 0 8 0;2=4,4=1
L 4.12783996 1.37098002 4.10816004 1.3513 1 P 0 
P 4.12783996 1.37098002 10 P 0 8 0;0,2=5,4=0
P 4.14753002 1.3513 9 P 0 8 0;2=4,4=1
L 4.16721004 1.37098002 4.14753002 1.3513 1 P 0 
P 4.16721004 1.37098002 10 P 0 8 0;0,2=5,4=0
P 4.6987 1.39066998 9 P 0 8 0;2=4,4=1
L 4.67901998 1.41035 4.6987 1.39066998 1 P 0 
P 4.67901998 1.41035 10 P 0 8 0;0,2=5,4=0
P 4.1869 1.3513 9 P 0 8 0;2=4,4=1
L 4.20658002 1.37098002 4.1869 1.3513 1 P 0 
P 4.20658002 1.37098002 10 P 0 8 0;0,2=5,4=0
P 4.65933002 1.39066998 9 P 0 8 0;2=4,4=1
L 4.63965 1.41035 4.65933002 1.39066998 1 P 0 
P 4.63965 1.41035 10 P 0 8 0;0,2=5,4=0
P 4.22626998 1.3513 9 P 0 8 0;2=4,4=1
L 4.24595 1.37098002 4.22626998 1.3513 1 P 0 
P 4.24595 1.37098002 10 P 0 8 0;0,2=5,4=0
P 4.73806998 2.17806998 9 P 0 8 0;2=4,4=1
L 4.71838996 2.15838996 4.73806998 2.17806998 1 P 0 
P 4.71838996 2.15838996 10 P 0 8 0;0,2=5,4=0
P 4.73806998 2.1387 9 P 0 8 0;2=4,4=1
L 4.71838996 2.11901998 4.73806998 2.1387 1 P 0 
P 4.71838996 2.11901998 10 P 0 8 0;0,2=5,4=0
P 4.56091004 2.07965 10 P 0 8 0;0,2=5,4=0
P 4.58058996 2.09933002 9 P 0 8 0;2=4,4=1
L 4.56091004 2.07965 4.58058996 2.09933002 1 P 0 
P 4.52153996 2.07965 10 P 0 8 0;0,2=5,4=0
P 4.54121998 2.09933002 9 P 0 8 0;2=4,4=1
L 4.52153996 2.07965 4.54121998 2.09933002 1 P 0 
P 4.58058996 1.86311004 9 P 0 8 0;2=4,4=1
L 4.56091004 1.84343002 4.58058996 1.86311004 1 P 0 
P 4.56091004 1.84343002 10 P 0 8 0;0,2=5,4=0
P 4.65933002 2.05996004 9 P 0 8 0;2=4,4=1
L 4.63965 2.04028002 4.65933002 2.05996004 1 P 0 
P 4.63965 2.04028002 10 P 0 8 0;0,2=5,4=0
P 4.58058996 2.05996004 9 P 0 8 0;2=4,4=1
L 4.56091004 2.04028002 4.58058996 2.05996004 1 P 0 
P 4.56091004 2.04028002 10 P 0 8 0;0,2=5,4=0
P 4.54121998 1.90248002 9 P 0 8 0;2=4,4=1
L 4.52153996 1.8828 4.54121998 1.90248002 1 P 0 
P 4.52153996 1.8828 10 P 0 8 0;0,2=5,4=0
P 4.58058996 2.02058996 9 P 0 8 0;2=4,4=1
L 4.56091004 2.00091004 4.58058996 2.02058996 1 P 0 
P 4.56091004 2.00091004 10 P 0 8 0;0,2=5,4=0
P 4.22626998 1.98121998 9 P 0 8 0;2=4,4=1
L 4.24595 1.96153996 4.22626998 1.98121998 1 P 0 
P 4.24595 1.96153996 10 P 0 8 0;0,2=5,4=0
P 4.26563996 1.94185 9 P 0 8 0;2=4,4=1
L 4.28531998 1.92216998 4.26563996 1.94185 1 P 0 
P 4.28531998 1.92216998 10 P 0 8 0;0,2=5,4=0
P 4.12783996 1.96153996 10 P 0 8 0;0,2=5,4=0
P 4.10816004 1.98121998 9 P 0 8 0;2=4,4=1
L 4.12783996 1.96153996 4.10816004 1.98121998 1 P 0 
P 4.16721004 1.96153996 10 P 0 8 0;0,2=5,4=0
P 4.14753002 1.98121998 9 P 0 8 0;2=4,4=1
L 4.16721004 1.96153996 4.14753002 1.98121998 1 P 0 
P 4.61996004 2.1387 9 P 0 8 0;2=4,4=1
L 4.60028002 2.11901998 4.61996004 2.1387 1 P 0 
P 4.60028002 2.11901998 10 P 0 8 0;0,2=5,4=0
P 4.6987 1.70563996 9 P 0 8 0;2=4,4=1
L 4.67901998 1.72531998 4.6987 1.70563996 1 P 0 
P 4.67901998 1.72531998 10 P 0 8 0;0,2=5,4=0
P 4.6987 1.66626998 9 P 0 8 0;2=4,4=1
L 4.6987 1.66626998 4.67901998 1.68595 1 P 0 
P 4.67901998 1.68595 10 P 0 8 0;0,2=5,4=0
S P 0
OB 1.55 3.215 I
OS 1.6 3.215
OS 1.615 3.2
OS 1.615 3.135
OS 1.61 3.13
OS 1.56831003937 3.13
OS 1.549519980315 3.14878996063
OS 1.549519980315 3.16778996063
OS 1.545 3.17231003937
OS 1.545 3.21
OS 1.55 3.215
OE
SE
P 1.45 3.59 11 P 0 8 0;2=1,4=1
P 1.56 3.165 11 P 0 8 0;2=7,4=1
P 1.56 3.205 11 P 0 8 0;2=1,4=1
P 1.59668996 3.17 23 P 0 8 0;0,2=16,4=0
L 0.72 3.5065 0.72 3.463 8 P 0 
P 0.72 3.5065 53 P 0 8 0;0,2=6,4=0
P 0.72 3.463 11 P 0 8 0;2=7,4=1
P 0.42326004 3.4315 12 P 0 8 0;2=17,4=0
P 0.40553996 3.4008 12 P 0 8 0;2=17,4=0
P 0.2815 3.4315 12 P 0 8 0;2=17,4=0
P 0.26378002 3.4008 12 P 0 8 0;2=17,4=0
P 0.71 3.305 11 P 0 8 0;2=8,4=0
L 1.14 3.52 1.13 3.52 6 P 0 
L 1.13 3.52 1.11316004 3.53683996 6 P 0 
L 1.11316004 3.53683996 1.11316004 3.578 6 P 0 
P 1.11316004 3.578 40 P 0 8 0;0,2=18,4=0
P 1.14 3.52 11 P 0 8 0;2=1,4=1
L 1.245 3.52 1.22501004 3.52 6 P 0 
L 1.22501004 3.52 1.21158002 3.53343002 6 P 0 
L 1.21158002 3.53343002 1.21158002 3.578 6 P 0 
P 1.245 3.52 11 P 0 8 0;2=1,4=1
P 1.21158002 3.578 40 P 0 8 0;0,2=18,4=0
S P 0
OB 4.639 3.845 I
OS 4.639 3.961
OS 4.645 3.967
OS 4.827 3.967
OS 4.83 3.964
OS 4.83 3.89
OS 4.826 3.886
OS 4.716 3.886
OS 4.675 3.845
OS 4.639 3.845
OE
SE
P 4.652 3.86 64 P 0 8 0;0,2=19,4=0
P 4.705 3.95 9 P 0 8 0;2=9,4=1
P 4.78656004 3.90826998 106 P 0 8 0;0,2=20,4=0
P 4.654 3.927 71 P 0 8 0;0,2=21,4=0
P 4.705 3.91 11 P 0 8 0;2=7,4=1
P 1.62033002 2.99531004 75 P 0 8 0;0,2=22,4=0
L 1.62033002 2.99531004 1.58531004 2.99531004 1 P 0 
L 1.58531004 2.99531004 1.566 2.976 1 P 0 
L 1.566 2.976 1.566 2.95 1 P 0 
P 1.566 2.95 11 P 0 8 0;2=1,4=1
P 1.055 3.731 58 P 0 8 0;0,2=2,4=0
P 1.045 3.77 11 P 0 8 0;2=7,4=1
L 1.055 3.731 1.045 3.741 1 P 0 
L 1.045 3.741 1.045 3.77 1 P 0 
P 1.515 3.58 11 P 0 8 0;2=7,4=1
P 6.145 4.035 11 P 0 8 0;2=1,4=1
P 1.37 3.64 11 P 0 8 0;2=7,4=1
P 1.667 3.438 11 P 0 8 0;2=7,4=1
P 1.591 3.546 11 P 0 8 0;2=7,4=1
P 1.13 3.445 11 P 0 8 0;2=7,4=1
L 0.894 3.43758002 0.94258002 3.43758002 6 P 0 
L 0.94258002 3.43758002 0.95 3.445 6 P 0 
P 0.894 3.43758002 96 P 0 8 0;0,2=18,4=0
P 0.95 3.445 11 P 0 8 0;2=7,4=1
P 2.19 3.488 11 P 0 8 0;2=7,4=1
P 2.192 3.388 11 P 0 8 0;2=7,4=1
P 1.41916004 3.33916004 11 P 0 8 0;2=7,4=1
L 1.352 3.33916004 1.41916004 3.33916004 6 P 0 
P 1.352 3.33916004 96 P 0 8 0;0,2=18,4=0
L 1.352 3.22105 1.38595 3.22105 6 P 0 
L 1.38595 3.22105 1.407 3.2 6 P 0 
P 1.352 3.22105 96 P 0 8 0;0,2=18,4=0
P 1.407 3.2 11 P 0 8 0;2=7,4=1
S P 0
OB 1.472 3.156980019685 I
OC 1.49113996063 3.17113996063 1.472 3.176995767717 N
OC 1.4935 3.1725 1.493051279528 3.170550984252 Y
OC 1.498 3.171980019685 1.498032874016 3.191996161417 N
OS 1.517019980315 3.171980019685
OS 1.5295 3.1595
OS 1.5295 3.1405
OS 1.5655 3.1045
OS 1.5845 3.1045
OS 1.5975 3.0915
OS 1.6235 3.0915
OS 1.641 3.074
OS 1.641 3.031
OS 1.64 3.03
OS 1.508 3.03
OS 1.50615 3.03185
OS 1.506 3.0323
OC 1.4933 3.045 1.487 3.026 N
OS 1.49285 3.04515
OS 1.487 3.051
OS 1.434 3.051
OS 1.42836003937 3.05663996063
OC 1.431019980315 3.069 1.400998818898 3.068994488189 N
OC 1.428519980315 3.08101003937 1.400996751969 3.069015649606 N
OS 1.428519980315 3.1426
OS 1.44191003937 3.156
OS 1.468 3.156
OS 1.468980019685 3.156980019685
OS 1.472 3.156980019685
OE
SE
P 1.495 3.11033996 11 P 0 8 0;2=7,4=1
P 1.62033002 3.03468996 75 P 0 8 0;0,2=22,4=0
P 1.62033002 3.05888002 117 P 0 8 0;0,2=23,4=0
P 1.455 3.138 67 P 0 8 0;0,2=19,4=0
P 1.46 3.073 88 P 0 8 0;0,2=21,4=0
P 1.51 3.164 58 P 0 8 0;0,2=2,4=0
P 1.535 3.105 11 P 0 8 0;2=8,4=0
P 1.53 3.046 58 P 0 8 0;0,2=2,4=0
P 1.15253002 3.06246998 11 P 0 8 0;2=7,4=1
L 1.15253002 3.12 1.15253002 3.06246998 6 P 0 
P 1.15253002 3.12 40 P 0 8 0;0,2=18,4=0
L 0.894 3.22105 0.94395 3.22105 6 P 0 
L 0.94395 3.22105 0.95 3.215 6 P 0 
P 0.95 3.215 11 P 0 8 0;2=7,4=1
P 0.894 3.22105 96 P 0 8 0;0,2=18,4=0
P 0.945 3.125 11 P 0 8 0;2=7,4=1
L 1.175 2.939 1.175 2.9 8 P 0 
P 1.175 2.9 11 P 0 8 0;2=7,4=1
P 1.175 2.939 58 P 0 8 0;0,2=2,4=0
L 1.025 2.981 1.025 3.02 8 P 0 
P 1.025 3.02 11 P 0 8 0;2=7,4=1
P 1.025 2.981 58 P 0 8 0;0,2=2,4=0
P 5.275 3.891 11 P 0 8 0;2=1,4=1
P 5.314 3.902 64 P 0 8 0;0,2=19,4=0
P 5.275 3.931 11 P 0 8 0;2=7,4=1
P 5.275 3.971 11 P 0 8 0;2=1,4=1
P 5.321 3.99 11 P 0 8 0;2=7,4=1
P 5.32 3.957 63 P 0 8 0;0,2=2,4=0
S P 0
OB 5.264 4.002 I
OS 5.323 4.002
OS 5.33 3.995
OS 5.33 3.97775
OC 5.327980019685 3.969 5.347997047244 3.968987106299 N
OS 5.327980019685 3.945
OC 5.33 3.93625 5.347997047244 3.945012893701 N
OS 5.33 3.924
OS 5.328 3.922
OS 5.328 3.886
OS 5.321 3.879
OS 5.265 3.879
OS 5.255 3.889
OS 5.255 3.993
OS 5.264 4.002
OE
SE
P 5.762 3.467 63 P 0 8 0;0,2=2,4=0
P 5.762 3.425 9 P 0 8 0;2=24,4=1
L 5.762 3.467 5.762 3.425 8 P 0 
P 5.567 3.203 11 P 0 8 0;2=7,4=1
P 5.617 3.203 11 P 0 8 0;2=1,4=1
P 5.55091998 3.306 111 P 0 8 0;0,2=25,4=0
P 5.62 3.316 11 P 0 8 0;2=7,4=1
P 5.625 3.261 11 P 0 8 0;2=1,4=1
P 5.625 3.361 11 P 0 8 0;2=7,4=1
P 5.533 3.569 64 P 0 8 0;0,2=19,4=0
P 5.6 3.421 11 P 0 8 0;2=1,4=1
P 5.552 3.71141004 9 P 0 8 0;2=26,4=1
P 5.595 3.569 63 P 0 8 0;0,2=2,4=0
P 5.552 3.74683996 9 P 0 8 0;2=26,4=1
P 5.552 3.78226998 9 P 0 8 0;2=26,4=1
P 5.552 3.67596998 9 P 0 8 0;2=26,4=1
P 5.536 3.69368996 84 P 0 8 0;0,2=27,4=0
P 5.536 3.72913002 84 P 0 8 0;0,2=27,4=0
P 5.536 3.64025 121 P 0 8 0;0,2=28,4=0
P 5.55606998 3.63305 22 P 0 8 0;0,2=29,4=0
P 5.536 3.76456004 84 P 0 8 0;0,2=27,4=0
P 5.536 3.79998996 84 P 0 8 0;0,2=27,4=0
P 5.52 3.78226998 9 P 0 8 0;2=26,4=1
P 5.52 3.74683996 9 P 0 8 0;2=26,4=1
P 5.52 3.71141004 9 P 0 8 0;2=26,4=1
P 5.52 3.67596998 9 P 0 8 0;2=26,4=1
S P 0
OB 5.517 3.807 I
OS 5.56 3.807
OS 5.563 3.804
OS 5.563 3.603
OS 5.568 3.598
OS 5.602 3.598
OS 5.60698996063 3.59301003937
OC 5.602980019685 3.581 5.622996948819 3.580991141732 N
OS 5.602980019685 3.557
OC 5.609 3.5427 5.622996161417 3.557009251969 N
OS 5.609 3.534830019685
OS 5.608869980315 3.53448996063
OC 5.606980019685 3.524 5.637001181102 3.524006397638 N
OC 5.609 3.513169980315 5.637000688976 3.523995964567 N
OS 5.609 3.489
OS 5.619 3.479
OS 5.62 3.479
OS 5.62998996063 3.46901003937
OS 5.630030019685 3.46825
OC 5.65 3.44168996063 5.660000885827 3.469996948819 N
OS 5.65 3.206
OS 5.63 3.186
OS 5.52 3.186
OS 5.51 3.196
OS 5.51 3.525
OS 5.515 3.53
OS 5.515 3.585
OS 5.51 3.59
OS 5.51 3.59523996063
OS 5.514019980315 3.59925
OS 5.514019980315 3.804019980315
OS 5.517 3.807
OE
SE
S P 0
OB 0.85656003937 4.156 I
OS 1.018 4.156
OS 1.033 4.141
OS 1.033 3.896
OS 1.023 3.886
OS 0.543 3.886
OS 0.538 3.891
OS 0.538 4.141
OS 0.553 4.156
OS 0.80343996063 4.156
OC 0.85656003937 4.156 0.83 4.170007283465 N
OE
SE
P 0.978 3.918 11 P 0 8 0;2=8,4=0
P 0.928 3.961 11 P 0 8 0;2=7,4=1
P 0.968 3.961 11 P 0 8 0;2=7,4=1
P 0.968 4.021 11 P 0 8 0;2=7,4=1
P 0.928 4.021 11 P 0 8 0;2=1,4=1
P 0.928 4.081 11 P 0 8 0;2=7,4=1
P 0.968 4.081 11 P 0 8 0;2=1,4=1
P 0.928 4.141 11 P 0 8 0;2=1,4=1
P 0.968 4.141 11 P 0 8 0;2=7,4=1
P 0.603 3.951 11 P 0 8 0;2=1,4=1
P 0.643 3.956 11 P 0 8 0;2=7,4=1
P 0.603 4.011 11 P 0 8 0;2=7,4=1
P 0.643 4.016 11 P 0 8 0;2=1,4=1
P 0.603 4.071 11 P 0 8 0;2=1,4=1
P 0.643 4.076 11 P 0 8 0;2=7,4=1
P 0.603 4.131 11 P 0 8 0;2=7,4=1
P 0.643 4.136 11 P 0 8 0;2=1,4=1
P 0.571 3.899 67 P 0 8 0;0,2=19,4=0
P 0.854 3.942 11 P 0 8 0;2=7,4=1
P 0.807 3.942 11 P 0 8 0;2=7,4=1
P 0.76 3.942 11 P 0 8 0;2=7,4=1
P 0.713 3.942 11 P 0 8 0;2=7,4=1
P 0.76 4.042 11 P 0 8 0;2=7,4=1
P 0.76 3.992 11 P 0 8 0;2=7,4=1
P 0.713 3.992 11 P 0 8 0;2=7,4=1
P 0.713 4.042 11 P 0 8 0;2=7,4=1
P 0.713 4.092 11 P 0 8 0;2=7,4=1
P 0.76 4.092 11 P 0 8 0;2=7,4=1
P 0.807 4.092 11 P 0 8 0;2=7,4=1
P 0.807 4.042 11 P 0 8 0;2=7,4=1
P 0.807 3.992 11 P 0 8 0;2=7,4=1
P 0.854 3.992 11 P 0 8 0;2=7,4=1
P 0.854 4.042 11 P 0 8 0;2=7,4=1
P 0.854 4.092 11 P 0 8 0;2=7,4=1
P 0.783 4.018 54 P 0 8 0;0,2=30,4=0
L 0.74 1.005 0.756 1.005 1 P 0 
L 0.756 1.005 0.76221004 0.99878996 1 P 0 
L 0.76221004 0.99878996 0.76221004 0.9475 1 P 0 
P 0.74 1.005 11 P 0 8 0;2=1,4=1
P 0.76221004 0.9475 46 P 0 8 0;0,2=31,4=0
L 0.79 1.005 0.788 1.003 1 P 0 
L 0.788 1.003 0.788 1 1 P 0 
L 0.788 1 0.7878 0.9998 1 P 0 
L 0.7878 0.9998 0.7878 0.9475 1 P 0 
P 0.79 1.005 11 P 0 8 0;2=1,4=1
P 0.7878 0.9475 46 P 0 8 0;0,2=31,4=0
L 0.84 1.005 0.825 1.005 1 P 0 
L 0.825 1.005 0.81338996 0.99338996 1 P 0 
L 0.81338996 0.99338996 0.81338996 0.9475 1 P 0 
P 0.81338996 0.9475 46 P 0 8 0;0,2=31,4=0
P 0.84 1.005 11 P 0 8 0;2=1,4=1
P 1.62033002 3.015 75 P 0 8 0;0,2=22,4=0
L 1.568 3.011 1.561 3.004 1 P 0 
L 1.561 3.004 1.53 3.004 1 P 0 
L 1.62033002 3.015 1.572 3.015 1 P 0 
L 1.572 3.015 1.568 3.011 1 P 0 
P 1.568 3.011 11 P 0 8 0;2=1,4=1
L 1.526 2.95 1.53 2.954 1 P 0 
L 1.53 2.954 1.53 3.004 1 P 0 
P 1.526 2.95 63 P 0 8 0;0,2=2,4=0
P 1.53 3.004 58 P 0 8 0;0,2=2,4=0
S P 0
OB 1.67 3.315 I
OS 1.785 3.315
OS 1.805 3.295
OS 1.805 3.235
OS 1.809080019685 3.230919980315
OS 1.809169980315 3.23025
OC 1.82625 3.213169980315 1.829 3.233 N
OS 1.826919980315 3.213080019685
OS 1.82905 3.21095
OS 1.828530019685 3.20971003937
OC 1.826980019685 3.202 1.84699734252 3.201986614173 N
OS 1.826980019685 3.178
OC 1.82743996063 3.17373996063 1.846999212598 3.178006594488 N
OS 1.827680019685 3.172680019685
OS 1.825 3.17
OS 1.725 3.17
OS 1.705 3.15
OS 1.675 3.15
OS 1.66 3.165
OS 1.66 3.305
OS 1.67 3.315
OE
SE
P 1.738 3.241 11 P 0 8 0;2=1,4=1
P 1.819 3.19 63 P 0 8 0;0,2=2,4=0
P 1.782 3.26 71 P 0 8 0;0,2=21,4=0
P 1.68331004 3.17 23 P 0 8 0;0,2=16,4=0
P 1.68331004 3.27 23 P 0 8 0;0,2=16,4=0
P 1.76 3.187 67 P 0 8 0;0,2=19,4=0
P 1.73966998 2.97111998 118 P 0 8 0;0,2=23,4=0
L 1.73966998 2.97561998 1.73966998 2.92826004 6 P 0 
L 1.73966998 2.92826004 1.73543002 2.92401998 6 P 0 
L 1.73543002 2.92401998 1.73543002 2.9 6 P 0 
L 1.73543002 2.9 1.765 2.9 6 P 0 
P 1.765 2.9 11 P 0 8 0;2=1,4=1
P 1.73543002 2.9 33 P 0 8 0;0,2=14,4=0
S P 0
OB 1.74 3.15 I
OS 1.83 3.15
OS 1.845 3.135
OS 1.845 3.08
OS 1.835 3.07
OS 1.835 3.062580019685
OS 1.834730019685 3.06211003937
OC 1.831980019685 3.052 1.851995767717 3.051984645669 N
OS 1.831980019685 3.028
OC 1.834730019685 3.01788996063 1.851995767717 3.028015354331 N
OS 1.835 3.017419980315
OS 1.835 3.015
OS 1.85305 2.99695
OS 1.85301003937 2.99606003937
OC 1.852980019685 2.995 1.872999015748 2.994963484252 N
OS 1.852980019685 2.976930019685
OC 1.84865 2.97295 1.848981299213 2.976934940945 Y
OC 1.847 2.973019980315 1.84697746063 2.953000984252 N
OS 1.823 2.973019980315
OC 1.82163996063 2.972969980315 1.823055019685 2.953002066929 N
OC 1.81736003937 2.97696003937 1.821361023622 2.976961220472 Y
OS 1.81736003937 2.98
OC 1.81081003937 2.99581003937 1.795004429134 2.98 N
OS 1.7955 3.011119980315
OC 1.78313996063 3.01741003937 1.779677066929 2.995316535433 N
OS 1.78248996063 3.01751003937
OS 1.775 3.025
OS 1.76045 3.025
OC 1.760169980315 3.025019980315 1.760024606299 3.021010433071 N
OS 1.724980019685 3.025019980315
OS 1.720019980315 3.02998996063
OS 1.720019980315 3.060019980315
OS 1.72 3.060019980315
OS 1.72 3.13
OS 1.74 3.15
OE
SE
P 1.73966998 3.03468996 75 P 0 8 0;0,2=22,4=0
P 1.73966998 3.05888002 113 P 0 8 0;0,2=32,4=0
P 1.822 3.105 71 P 0 8 0;0,2=21,4=0
P 1.78 3.095 11 P 0 8 0;2=1,4=1
P 1.835 2.981 58 P 0 8 0;0,2=2,4=0
P 1.76 3.133 67 P 0 8 0;0,2=19,4=0
P 1.824 3.04 63 P 0 8 0;0,2=2,4=0
P 1.73966998 2.99531004 75 P 0 8 0;0,2=22,4=0
L 1.795 2.946 1.802 2.939 1 P 0 
L 1.802 2.939 1.835 2.939 1 P 0 
L 1.73966998 2.99531004 1.77968996 2.99531004 1 P 0 
L 1.77968996 2.99531004 1.795 2.98 1 P 0 
L 1.795 2.98 1.795 2.946 1 P 0 
P 1.795 2.946 11 P 0 8 0;2=1,4=1
P 1.885 2.939 58 P 0 8 0;0,2=2,4=0
L 1.885 2.939 1.835 2.939 1 P 0 
P 1.835 2.939 58 P 0 8 0;0,2=2,4=0
L 5.249 0.87 5.2 0.87 1 P 0 
L 5.1245 0.89398002 5.19101998 0.89398002 1 P 0 
L 5.19101998 0.89398002 5.2 0.885 1 P 0 
L 5.2 0.885 5.2 0.87 1 P 0 
P 5.2 0.87 11 P 0 8 0;2=1,4=1
P 5.249 0.87 63 P 0 8 0;0,2=2,4=0
P 5.1245 0.89398002 94 P 0 8 0;0,2=10,4=0
L 4.47 3.21998002 4.51198002 3.21998002 1 P 0 
L 4.51198002 3.21998002 4.512 3.22 1 P 0 
P 4.47 3.21998002 11 P 0 8 0;2=1,4=1
L 4.4085 3.21998002 4.47 3.21998002 1 P 0 
P 4.4085 3.21998002 94 P 0 8 0;0,2=10,4=0
P 4.512 3.22 63 P 0 8 0;0,2=2,4=0
L 4.385 3.645 4.384 3.646 1 P 0 
L 4.384 3.646 4.384 3.7 1 P 0 
L 4.435 3.6185 4.4115 3.6185 1 P 0 
L 4.4115 3.6185 4.385 3.645 1 P 0 
P 4.385 3.645 11 P 0 8 0;2=1,4=1
L 4.2745 3.73898002 4.32898002 3.73898002 1 P 0 
L 4.32898002 3.73898002 4.335 3.745 1 P 0 
L 4.335 3.745 4.384 3.745 1 P 0 
L 4.384 3.7 4.384 3.745 1 P 0 
P 4.384 3.745 63 P 0 8 0;0,2=2,4=0
P 4.384 3.7 63 P 0 8 0;0,2=2,4=0
P 4.435 3.6185 73 P 0 8 0;0,2=13,4=0
P 4.2745 3.73898002 94 P 0 8 0;0,2=10,4=0
L 0.78 3.305 0.78 3.32 1 P 0 
L 0.78 3.32 0.8 3.34 1 P 0 
L 0.8 3.34 0.83616004 3.34 1 P 0 
L 0.83616004 3.34 0.855 3.35883996 1 P 0 
L 0.855 3.35883996 0.894 3.35883996 1 P 0 
P 0.78 3.305 11 P 0 8 0;2=8,4=0
P 0.894 3.35883996 96 P 0 8 0;0,2=18,4=0
L 1.03 3.515 1.01473002 3.53026998 1 P 0 
L 1.01473002 3.53026998 1.01473002 3.578 1 P 0 
P 1.03 3.515 11 P 0 8 0;2=1,4=1
P 1.01473002 3.578 40 P 0 8 0;0,2=18,4=0
L 1.19 3.52 1.17221004 3.53778996 1 P 0 
L 1.17221004 3.53778996 1.17221004 3.578 1 P 0 
P 1.19 3.52 11 P 0 8 0;2=1,4=1
P 1.17221004 3.578 40 P 0 8 0;0,2=18,4=0
P 0.99505 3.12 40 P 0 8 0;0,2=18,4=0
L 0.99505 3.12 0.99505 2.96005 1 P 0 
L 0.99505 2.96005 0.95 2.915 1 P 0 
P 0.95 2.915 11 P 0 8 0;2=8,4=0
P 0.97536004 3.12 40 P 0 8 0;0,2=18,4=0
L 0.97536004 3.12 0.97536004 3.02036004 1 P 0 
L 0.97536004 3.02036004 0.945 2.99 1 P 0 
P 0.945 2.99 11 P 0 8 0;2=8,4=0
P 0.894 3.20136004 96 P 0 8 0;0,2=18,4=0
L 0.894 3.20136004 0.894 3.039 1 P 0 
L 0.894 3.039 0.885 3.03 1 P 0 
P 0.885 3.03 11 P 0 8 0;2=8,4=0
L 0.875 2.955 0.875 2.975 1 P 0 
L 0.875 2.975 0.92 3.02 1 P 0 
L 0.92 3.02 0.92 3.145 1 P 0 
L 0.92 3.145 0.975 3.2 1 P 0 
L 0.975 3.2 0.975 3.23 1 P 0 
L 0.975 3.23 0.96426998 3.24073002 1 P 0 
L 0.96426998 3.24073002 0.894 3.24073002 1 P 0 
P 0.875 2.955 11 P 0 8 0;2=8,4=0
P 0.894 3.24073002 96 P 0 8 0;0,2=18,4=0
L 0.795 3.085 0.845 3.135 1 P 0 
L 0.845 3.135 0.845 3.24 1 P 0 
L 0.845 3.24 0.86541998 3.26041998 1 P 0 
L 0.86541998 3.26041998 0.894 3.26041998 1 P 0 
P 0.795 3.085 11 P 0 8 0;2=8,4=0
P 0.894 3.26041998 96 P 0 8 0;0,2=18,4=0
L 0.55 3.36 0.55 3.329 1 P 0 
L 0.55 3.329 0.589 3.29 1 P 0 
L 0.3701 3.4008 0.3701 3.3749 1 P 0 
L 0.3701 3.3749 0.385 3.36 1 P 0 
L 0.385 3.36 0.55 3.36 1 P 0 
P 0.55 3.36 11 P 0 8 0;2=1,4=1
P 0.589 3.29 63 P 0 8 0;0,2=2,4=0
P 0.3701 3.4008 12 P 0 8 0;2=17,4=0
L 0.595 3.554 0.55 3.554 1 P 0 
P 0.55 3.554 11 P 0 8 0;2=1,4=1
P 0.595 3.554 58 P 0 8 0;0,2=2,4=0
P 0.31693996 3.4315 12 P 0 8 0;2=17,4=0
L 1.271 3.75 1.271 3.741 1 P 0 
L 1.271 3.741 1.25095 3.72095 1 P 0 
L 1.25095 3.72095 1.25095 3.578 1 P 0 
P 1.25095 3.578 40 P 0 8 0;0,2=18,4=0
L 1.26956998 3.79 1.255 3.80456998 1 P 0 
L 1.255 3.80456998 1.255 3.87998996 1 P 0 
L 1.255 3.87998996 1.29346998 3.91846004 1 P 0 
L 1.29346998 3.91846004 1.29831004 3.91846004 1 P 0 
L 1.271 3.75 1.271 3.78856998 1 P 0 
L 1.271 3.78856998 1.26956998 3.79 1 P 0 
P 1.29831004 3.91846004 91 P 0 8 0;0,2=33,4=0
P 1.26956998 3.79 33 P 0 8 0;0,2=14,4=0
P 1.271 3.75 63 P 0 8 0;0,2=2,4=0
L 1.23126998 3.578 1.23126998 3.74773002 1 P 0 
L 1.23126998 3.74773002 1.229 3.75 1 P 0 
P 1.23126998 3.578 40 P 0 8 0;0,2=18,4=0
L 1.23543002 3.79 1.23543002 3.8278 1 P 0 
L 1.23543002 3.8278 1.21168996 3.85153996 1 P 0 
P 1.21168996 3.85153996 91 P 0 8 0;0,2=33,4=0
P 1.23543002 3.79 33 P 0 8 0;0,2=14,4=0
L 1.23543002 3.79 1.23543002 3.75643002 1 P 0 
L 1.23543002 3.75643002 1.229 3.75 1 P 0 
P 1.229 3.75 63 P 0 8 0;0,2=2,4=0
P 5.9945 1.57063002 107 P 0 8 0;0,2=34,4=0
L 5.9945 1.57063002 5.92 1.57063002 1 P 0 
P 5.92 1.57063002 11 P 0 8 0;2=1,4=1
P 6.14648002 1.57063002 110 P 0 8 0;0,2=35,4=0
L 6.14648002 1.57063002 6.21936998 1.57063002 1 P 0 
L 6.21936998 1.57063002 6.22 1.57 1 P 0 
P 6.22 1.57 11 P 0 8 0;2=1,4=1
L 5.92 1.46 5.93063002 1.47063002 1 P 0 
L 5.93063002 1.47063002 5.9945 1.47063002 1 P 0 
P 5.92 1.46 11 P 0 8 0;2=1,4=1
P 5.9945 1.47063002 107 P 0 8 0;0,2=34,4=0
L 6.22 1.465 6.21436998 1.47063002 1 P 0 
L 6.21436998 1.47063002 6.14648002 1.47063002 1 P 0 
P 6.22 1.465 11 P 0 8 0;2=1,4=1
P 6.14648002 1.47063002 110 P 0 8 0;0,2=35,4=0
L 5.92 1.68 5.92936998 1.67063002 1 P 0 
L 5.92936998 1.67063002 5.9945 1.67063002 1 P 0 
P 5.92 1.68 11 P 0 8 0;2=1,4=1
P 5.9945 1.67063002 107 P 0 8 0;0,2=34,4=0
L 6.14648002 1.67063002 6.22035 1.67063002 1 P 0 
P 6.22035 1.67063002 11 P 0 8 0;2=1,4=1
P 6.14648002 1.67063002 110 P 0 8 0;0,2=35,4=0
L 5.92 1.78 5.925 1.78 1 P 0 
L 5.925 1.78 5.93436998 1.77063002 1 P 0 
L 5.93436998 1.77063002 5.9945 1.77063002 1 P 0 
P 5.92 1.78 11 P 0 8 0;2=1,4=1
P 5.9945 1.77063002 107 P 0 8 0;0,2=34,4=0
L 6.22 1.755 6.20436998 1.77063002 1 P 0 
L 6.20436998 1.77063002 6.14648002 1.77063002 1 P 0 
P 6.22 1.755 11 P 0 8 0;2=1,4=1
P 6.14648002 1.77063002 110 P 0 8 0;0,2=35,4=0
L 6.1437 4.13778996 6.09423996 4.13778996 1 P 0 
P 6.09423996 4.13778996 11 P 0 8 0;2=1,4=1
P 6.1437 4.13778996 24 P 0 8 0;0,2=36,4=0
P 3.51 3.08 11 P 0 8 0;2=1,4=1
P 1.025 2.9 11 P 0 8 0;2=7,4=1
L 1.025 2.939 1.025 2.9 1 P 0 
P 1.025 2.939 58 P 0 8 0;0,2=2,4=0
L 1.025 2.939 1.075 2.939 1 P 0 
P 1.075 2.939 58 P 0 8 0;0,2=2,4=0
P 4.40343002 1.92216998 10 P 0 8 0;0,2=5,4=0
P 4.42311004 1.94185 9 P 0 8 0;2=4,4=1
L 4.40343002 1.92216998 4.42311004 1.94185 1 P 0 
P 3.46 3.065 11 P 0 8 0;2=1,4=1
L 1.125 2.939 1.125 2.9 1 P 0 
P 1.125 2.9 11 P 0 8 0;2=7,4=1
P 1.125 2.939 58 P 0 8 0;0,2=2,4=0
P 4.40343002 1.8828 10 P 0 8 0;0,2=5,4=0
P 4.42311004 1.90248002 9 P 0 8 0;2=4,4=1
L 4.40343002 1.8828 4.42311004 1.90248002 1 P 0 
P 3.035 1.64 11 P 0 8 0;2=7,4=1
L 3.44256004 2.765 3.44256004 2.6748 1 P 0 
L 3.44256004 2.6748 3.445 2.67236004 1 P 0 
L 3.445 2.67236004 3.445 2.65 1 P 0 
P 3.445 2.65 11 P 0 8 0;2=8,4=0
P 3.44256004 2.765 43 P 0 8 0;0,2=37,4=0
L 1.1288 0.7302 1.1522 0.7536 1 P 0 
L 1.1522 0.7536 1.1737 0.7536 1 P 0 
L 1.0705 0.7284 1.127 0.7284 1 P 0 
L 1.127 0.7284 1.1288 0.7302 1 P 0 
P 1.1737 0.7536 63 P 0 8 0;0,2=2,4=0
P 1.0705 0.7284 83 P 0 8 0;0,2=6,4=0
P 1.1288 0.7302 9 P 0 8 0;2=24,4=1
P 3.075 1.605 11 P 0 8 0;2=7,4=1
L 3.365 2.95 3.4098 2.95 1 P 0 
L 3.4098 2.95 3.44256004 2.91723996 1 P 0 
L 3.44256004 2.91723996 3.44256004 2.865 1 P 0 
P 3.44256004 2.865 43 P 0 8 0;0,2=37,4=0
P 3.365 2.95 9 P 0 8 0;2=9,4=1
L 0.7878 0.7085 0.7878 0.6528 1 P 0 
L 0.7878 0.6528 0.755 0.62 1 P 0 
P 0.755 0.62 11 P 0 8 0;2=8,4=0
P 0.7878 0.7085 46 P 0 8 0;0,2=31,4=0
L 0.715 0.77 0.73661998 0.74838002 1 P 0 
L 0.73661998 0.74838002 0.73661998 0.7085 1 P 0 
P 0.715 0.77 11 P 0 8 0;2=1,4=1
P 0.73661998 0.7085 46 P 0 8 0;0,2=31,4=0
L 1.13283996 3.578 1.13283996 3.61283002 3 P 0 
A 1.13283996 3.61283002 1.13451004 3.61686004 1.1385375 3.61282992 3 P 0 Y
L 1.13451004 3.61686004 1.13476004 3.61711004 3 P 0 
L 1.13476004 3.61711004 1.1348 3.61715 3 P 0 
A 1.1348 3.61715 1.1348 3.61743996 1.14722283 3.61729498 3 P 0 Y
L 1.1348 3.61743996 1.1348 3.63366004 3 P 0 
A 1.1348 3.63366004 1.13028996 3.64508996 1.11806112 3.63365984 3 P 0 N
L 1.13028996 3.64508996 1.1294 3.64603996 3 P 0 
A 1.1294 3.64603996 1.124 3.65973002 1.14405335 3.65972992 3 P 0 Y
L 1.124 3.65973002 1.124 3.66666004 3 P 0 
A 1.124 3.66666004 1.12383002 3.66805 1.11823238 3.66666004 3 P 0 N
A 1.12383002 3.66805 1.12108002 3.67291998 1.11370049 3.66554144 3 P 0 N
L 1.12108002 3.67291998 1.105 3.689 3 P 0 
P 1.13283996 3.578 40 P 0 8 0;0,2=18,4=0
P 1.105 3.689 58 P 0 8 0;0,2=2,4=0
P 1.15253002 3.578 40 P 0 8 0;0,2=18,4=0
L 1.15253002 3.578 1.15253002 3.61283002 3 P 0 
A 1.15253002 3.61283002 1.15086004 3.61686004 1.14683248 3.61283002 3 P 0 N
L 1.15086004 3.61686004 1.1506 3.61711998 3 P 0 
A 1.1506 3.61711998 1.1498 3.61811998 1.15462136 3.62115699 3 P 0 Y
L 1.1498 3.61811998 1.1498 3.63366004 3 P 0 
A 1.1498 3.63366004 1.14125 3.65535 1.11805463 3.63367638 3 P 0 N
L 1.14125 3.65535 1.14078002 3.65583996 3 P 0 
L 1.14078002 3.65583996 1.14036998 3.65628996 3 P 0 
A 1.14036998 3.65628996 1.139 3.65973002 1.14404656 3.65974695 3 P 0 Y
L 1.139 3.65973002 1.139 3.66666004 3 P 0 
A 1.139 3.66666004 1.14348002 3.67748996 1.15431299 3.66666703 3 P 0 Y
L 1.14348002 3.67748996 1.155 3.689 3 P 0 
P 1.155 3.689 58 P 0 8 0;0,2=2,4=0
L 0.83 3.445 0.83 3.45 1 P 0 
L 0.83 3.45 0.83726998 3.45726998 1 P 0 
L 0.83726998 3.45726998 0.894 3.45726998 1 P 0 
P 0.83 3.445 11 P 0 8 0;2=1,4=1
P 0.894 3.45726998 96 P 0 8 0;0,2=18,4=0
L 0.795 3.485 0.80305 3.47695 1 P 0 
L 0.80305 3.47695 0.894 3.47695 1 P 0 
P 0.795 3.485 11 P 0 8 0;2=1,4=1
P 0.894 3.47695 96 P 0 8 0;0,2=18,4=0
L 0.83 3.525 0.83 3.52 1 P 0 
L 0.83 3.52 0.835 3.515 1 P 0 
L 0.835 3.515 0.839 3.515 1 P 0 
L 0.839 3.515 0.85736004 3.49663996 1 P 0 
L 0.85736004 3.49663996 0.894 3.49663996 1 P 0 
P 0.83 3.525 11 P 0 8 0;2=1,4=1
P 0.894 3.49663996 96 P 0 8 0;0,2=18,4=0
L 0.951 3.519 0.962 3.519 1 P 0 
L 0.962 3.519 0.97536004 3.53236004 1 P 0 
L 0.97536004 3.53236004 0.97536004 3.578 1 P 0 
P 0.951 3.519 11 P 0 8 0;2=1,4=1
P 0.97536004 3.578 40 P 0 8 0;0,2=18,4=0
L 0.746 3.2 0.808 3.2 1 P 0 
L 0.808 3.2 0.8127 3.2047 1 P 0 
L 0.8127 3.2047 0.8127 3.26258996 1 P 0 
L 0.8127 3.26258996 0.82951004 3.2794 1 P 0 
L 0.894 3.29978996 0.8499 3.29978996 1 P 0 
L 0.8499 3.29978996 0.82951004 3.2794 1 P 0 
P 0.82951004 3.2794 11 P 0 8 0;2=1,4=1
P 0.894 3.29978996 96 P 0 8 0;0,2=18,4=0
P 0.746 3.2 63 P 0 8 0;0,2=2,4=0
L 0.79 3.155 0.83 3.195 1 P 0 
L 0.83 3.195 0.83 3.245 1 P 0 
L 0.83 3.245 0.8651 3.2801 1 P 0 
L 0.8651 3.2801 0.894 3.2801 1 P 0 
P 0.79 3.155 11 P 0 8 0;2=1,4=1
P 0.894 3.2801 96 P 0 8 0;0,2=18,4=0
L 0.894 3.31946998 0.8147 3.31946998 1 P 0 
L 0.8147 3.31946998 0.81 3.31476998 1 P 0 
L 0.81 3.31476998 0.81 3.29501004 1 P 0 
L 0.81 3.29501004 0.78635 3.27136004 1 P 0 
L 0.78635 3.27136004 0.78635 3.24491998 1 P 0 
L 0.746 3.245 0.78626998 3.245 1 P 0 
L 0.78626998 3.245 0.78635 3.24491998 1 P 0 
P 0.78635 3.24491998 11 P 0 8 0;2=1,4=1
P 0.894 3.31946998 96 P 0 8 0;0,2=18,4=0
P 0.746 3.245 63 P 0 8 0;0,2=2,4=0
L 1.26 3.18 1.27063996 3.16936004 1 P 0 
L 1.27063996 3.16936004 1.27063996 3.12 1 P 0 
P 1.26 3.18 11 P 0 8 0;2=1,4=1
P 1.27063996 3.12 40 P 0 8 0;0,2=18,4=0
L 1.295 3.28 1.31458002 3.26041998 1 P 0 
L 1.31458002 3.26041998 1.352 3.26041998 1 P 0 
P 1.295 3.28 11 P 0 8 0;2=1,4=1
P 1.352 3.26041998 96 P 0 8 0;0,2=18,4=0
L 1.075 3.02 1.075 3.06 1 P 0 
L 1.075 3.06 1.07378996 3.06121004 1 P 0 
L 1.07378996 3.06121004 1.07378996 3.12 1 P 0 
L 1.075 2.981 1.075 3.02 1 P 0 
P 1.075 3.02 11 P 0 8 0;2=1,4=1
P 1.075 2.981 58 P 0 8 0;0,2=2,4=0
P 1.07378996 3.12 40 P 0 8 0;0,2=18,4=0
L 1.125 3.02 1.125 2.981 1 P 0 
L 1.09346998 3.12 1.09346998 3.07653002 1 P 0 
L 1.09346998 3.07653002 1.125 3.045 1 P 0 
L 1.125 3.045 1.125 3.02 1 P 0 
P 1.125 3.02 11 P 0 8 0;2=1,4=1
P 1.175 2.981 58 P 0 8 0;0,2=2,4=0
L 1.175 2.981 1.125 2.981 1 P 0 
P 1.125 2.981 58 P 0 8 0;0,2=2,4=0
P 1.09346998 3.12 40 P 0 8 0;0,2=18,4=0
P 1.073 3.825 9 P 0 8 0;2=38,4=1
P 0.703 3.575 9 P 0 8 0;2=38,4=1
L 1.105 3.731 1.12013002 3.74613002 3 P 0 
A 1.12013002 3.74613002 1.12013002 3.75883002 1.11378002 3.75248002 3 P 0 N
L 1.12013002 3.75883002 1.08883002 3.79013002 3 P 0 
A 1.08883002 3.79013002 1.0821 3.80645 1.10513996 3.80640354 3 P 0 Y
L 1.0821 3.80645 1.0821 3.81353996 3 P 0 
A 1.0821 3.81353996 1.08043002 3.81756998 1.07640246 3.81353996 3 P 0 N
L 1.08043002 3.81756998 1.073 3.825 3 P 0 
P 1.105 3.731 58 P 0 8 0;0,2=2,4=0
L 0.35238002 3.4315 0.36091998 3.44005 3 P 0 
A 0.36091998 3.44005 0.3626 3.44408996 0.35688327 3.44409793 3 P 0 N
L 0.3626 3.44408996 0.3626 3.451 3 P 0 
A 0.3626 3.451 0.3866 3.475 0.3866 3.451 3 P 0 Y
L 0.3866 3.475 0.48288002 3.475 3 P 0 
A 0.48288002 3.475 0.50528002 3.46571998 0.48287992 3.44332549 3 P 0 Y
L 0.50528002 3.46571998 0.51395 3.45705 3 P 0 
A 0.51395 3.45705 0.53096998 3.45 0.53097028 3.47407047 3 P 0 N
L 0.53096998 3.45 0.54498996 3.45 3 P 0 
A 0.54498996 3.45 0.54948996 3.4545 0.54498996 3.4545 3 P 0 N
A 0.54948996 3.4545 0.55398996 3.459 0.55398996 3.4545 3 P 0 Y
L 0.55398996 3.459 0.56778996 3.459 3 P 0 
A 0.56778996 3.459 0.57228996 3.4545 0.56778996 3.4545 3 P 0 Y
A 0.57228996 3.4545 0.57678996 3.45 0.57678996 3.4545 3 P 0 N
L 0.57678996 3.45 0.59058996 3.45 3 P 0 
A 0.59058996 3.45 0.59508996 3.4545 0.59058996 3.4545 3 P 0 N
A 0.59508996 3.4545 0.59958996 3.459 0.59958996 3.4545 3 P 0 Y
L 0.59958996 3.459 0.61338996 3.459 3 P 0 
A 0.61338996 3.459 0.61788996 3.4545 0.61338996 3.4545 3 P 0 Y
A 0.61788996 3.4545 0.62238996 3.45 0.62238996 3.4545 3 P 0 N
L 0.62238996 3.45 0.63618996 3.45 3 P 0 
A 0.63618996 3.45 0.64068996 3.4545 0.63618996 3.4545 3 P 0 N
A 0.64068996 3.4545 0.64518996 3.459 0.64518996 3.4545 3 P 0 Y
L 0.64518996 3.459 0.65898996 3.459 3 P 0 
A 0.65898996 3.459 0.66348996 3.4545 0.65898996 3.4545 3 P 0 Y
A 0.66348996 3.4545 0.66798996 3.45 0.66798996 3.4545 3 P 0 N
L 0.66798996 3.45 0.68805 3.45 3 P 0 
A 0.68805 3.45 0.6965 3.45845 0.68805 3.45845 3 P 0 N
L 0.6965 3.45845 0.6965 3.46198996 3 P 0 
A 0.6965 3.46198996 0.69473002 3.46626998 0.69044035 3.46198996 3 P 0 N
L 0.69473002 3.46626998 0.69073002 3.47026998 3 P 0 
A 0.69073002 3.47026998 0.6826 3.4899 0.71036348 3.4899 3 P 0 Y
L 0.6826 3.4899 0.6826 3.5065 3 P 0 
L 0.703 3.575 0.70933002 3.56866998 3 P 0 
A 0.70933002 3.56866998 0.711 3.56463002 0.70527825 3.56462992 3 P 0 Y
L 0.711 3.56463002 0.711 3.555 3 P 0 
A 0.711 3.555 0.70938002 3.55108996 0.70547146 3.5549999 3 P 0 Y
L 0.70938002 3.55108996 0.70711004 3.54881998 3 P 0 
L 0.70711004 3.54881998 0.70378996 3.54681998 3 P 0 
A 0.70378996 3.54681998 0.70083002 3.546 0.70083455 3.55173573 3 P 0 Y
L 0.70083002 3.546 0.69628996 3.54573996 3 P 0 
A 0.69628996 3.54573996 0.68656004 3.54116004 0.69776368 3.52998356 3 P 0 N
A 0.68656004 3.54116004 0.6826 3.53158996 0.69603789 3.53163376 3 P 0 N
L 0.6826 3.53158996 0.6826 3.5065 3 P 0 
P 0.35238002 3.4315 12 P 0 8 0;2=17,4=0
P 0.6826 3.5065 53 P 0 8 0;0,2=6,4=0
P 0.33466004 3.4008 12 P 0 8 0;2=17,4=0
P 0.735 3.575 9 P 0 8 0;2=38,4=1
P 1.105 3.825 9 P 0 8 0;2=38,4=1
L 1.155 3.731 1.13745 3.74856004 3 P 0 
A 1.13745 3.74856004 1.13075 3.76943996 1.11378268 3.75248051 3 P 0 N
L 1.13075 3.76943996 1.09945 3.80073996 3 P 0 
A 1.09945 3.80073996 1.0971 3.80643002 1.10513406 3.80641772 3 P 0 Y
L 1.0971 3.80643002 1.0971 3.81355 3 P 0 
A 1.0971 3.81355 1.09961004 3.81961004 1.10567047 3.8135499 3 P 0 Y
L 1.09961004 3.81961004 1.105 3.825 3 P 0 
P 1.155 3.731 58 P 0 8 0;0,2=2,4=0
L 0.735 3.575 0.73226998 3.57226998 3 P 0 
A 0.73226998 3.57226998 0.726 3.55713996 0.74738996 3.55713996 3 P 0 N
A 0.726 3.55713996 0.73813996 3.545 0.73813996 3.55713996 3 P 0 N
L 0.73813996 3.545 0.74398996 3.545 3 P 0 
A 0.74398996 3.545 0.75041998 3.54233996 0.74399478 3.53591014 3 P 0 Y
L 0.75041998 3.54233996 0.75133002 3.54143002 3 P 0 
A 0.75133002 3.54143002 0.7574 3.52678002 0.73668602 3.52678002 3 P 0 Y
L 0.7574 3.52678002 0.7574 3.5065 3 P 0 
L 0.7574 3.5065 0.7574 3.49898002 3 P 0 
A 0.7574 3.49898002 0.75133002 3.48433002 0.73668602 3.49897992 3 P 0 Y
L 0.75133002 3.48433002 0.74903996 3.48203996 3 P 0 
A 0.74903996 3.48203996 0.74295 3.46733996 0.76373642 3.46733996 3 P 0 N
L 0.74295 3.46733996 0.74295 3.46221004 3 P 0 
A 0.74295 3.46221004 0.73541004 3.44403002 0.7172627 3.46220994 3 P 0 Y
A 0.73541004 3.44403002 0.71361004 3.435 0.71360994 3.46582953 3 P 0 Y
L 0.71361004 3.435 0.53096004 3.435 3 P 0 
A 0.53096004 3.435 0.50333996 3.44643996 0.53096407 3.47407215 3 P 0 Y
L 0.50333996 3.44643996 0.49466998 3.45511004 3 P 0 
A 0.49466998 3.45511004 0.48288002 3.46 0.48287421 3.44332795 3 P 0 N
L 0.48288002 3.46 0.3866 3.46 3 P 0 
A 0.3866 3.46 0.3776 3.451 0.3866 3.451 3 P 0 N
L 0.3776 3.451 0.3776 3.44408996 3 P 0 
A 0.3776 3.44408996 0.37926998 3.44005 0.38332175 3.44408996 3 P 0 N
L 0.37926998 3.44005 0.38781998 3.4315 3 P 0 
P 0.38781998 3.4315 12 P 0 8 0;2=17,4=0
P 0.29921998 3.4008 12 P 0 8 0;2=17,4=0
P 0.7574 3.5065 53 P 0 8 0;0,2=6,4=0
L 1.055 3.689 1.02836004 3.689 1 P 0 
L 1.02836004 3.689 1.01736004 3.7 1 P 0 
L 1.01736004 3.7 0.995 3.7 1 P 0 
P 1.055 3.689 58 P 0 8 0;0,2=2,4=0
P 0.995 3.7 11 P 0 8 0;2=8,4=0
P 4.285 3.46 11 P 0 8 0;2=7,4=1
L 4.34 3.496 4.321 3.496 1 P 0 
L 4.321 3.496 4.285 3.46 1 P 0 
L 4.34 3.496 4.3625 3.496 1 P 0 
L 4.3625 3.496 4.398 3.5315 1 P 0 
P 4.34 3.496 58 P 0 8 0;0,2=2,4=0
P 4.398 3.5315 73 P 0 8 0;0,2=13,4=0
L 2.15 3.438 2.05 3.438 1 P 0 
L 2.05 3.438 2.023 3.465 1 P 0 
L 2.023 3.465 1.645 3.465 1 P 0 
L 1.645 3.465 1.61758002 3.43758002 1 P 0 
L 1.61758002 3.43758002 1.352 3.43758002 1 P 0 
P 2.15 3.438 11 P 0 8 0;2=1,4=1
P 1.352 3.43758002 96 P 0 8 0;0,2=18,4=0
L 2.05 3.538 1.9996 3.538 1 P 0 
L 1.9996 3.538 1.9949 3.5427 1 P 0 
L 1.9949 3.5427 1.9949 3.5633 1 P 0 
L 1.9949 3.5633 1.9902 3.568 1 P 0 
L 1.9902 3.568 1.9749 3.568 1 P 0 
L 1.9749 3.568 1.9702 3.5633 1 P 0 
L 1.9702 3.5633 1.9702 3.5427 1 P 0 
L 1.9702 3.5427 1.9655 3.538 1 P 0 
L 1.9655 3.538 1.9502 3.538 1 P 0 
L 1.9502 3.538 1.9455 3.5427 1 P 0 
L 1.9455 3.5427 1.9455 3.5633 1 P 0 
L 1.9455 3.5633 1.9408 3.568 1 P 0 
L 1.9408 3.568 1.9255 3.568 1 P 0 
L 1.9255 3.568 1.9208 3.5633 1 P 0 
L 1.9208 3.5633 1.9208 3.5427 1 P 0 
L 1.9208 3.5427 1.9161 3.538 1 P 0 
L 1.9161 3.538 1.9008 3.538 1 P 0 
L 1.9008 3.538 1.8961 3.5427 1 P 0 
L 1.8961 3.5427 1.8961 3.5633 1 P 0 
L 1.8961 3.5633 1.8914 3.568 1 P 0 
L 1.8914 3.568 1.8761 3.568 1 P 0 
L 1.8761 3.568 1.8714 3.5633 1 P 0 
L 1.8714 3.5633 1.8714 3.5427 1 P 0 
L 1.8714 3.5427 1.8667 3.538 1 P 0 
L 1.8667 3.538 1.8514 3.538 1 P 0 
L 1.8514 3.538 1.8467 3.5427 1 P 0 
L 1.8467 3.5427 1.8467 3.5633 1 P 0 
L 1.8467 3.5633 1.842 3.568 1 P 0 
L 1.842 3.568 1.8267 3.568 1 P 0 
L 1.8267 3.568 1.822 3.5633 1 P 0 
L 1.822 3.5633 1.822 3.5427 1 P 0 
L 1.822 3.5427 1.8173 3.538 1 P 0 
L 1.8173 3.538 1.802 3.538 1 P 0 
L 1.802 3.538 1.7973 3.5427 1 P 0 
L 1.7973 3.5427 1.7973 3.5633 1 P 0 
L 1.7973 3.5633 1.7926 3.568 1 P 0 
L 1.7926 3.568 1.7773 3.568 1 P 0 
L 1.7773 3.568 1.7726 3.5633 1 P 0 
L 1.7726 3.5633 1.7726 3.5427 1 P 0 
L 1.7726 3.5427 1.7679 3.538 1 P 0 
L 1.7679 3.538 1.668 3.538 1 P 0 
L 1.668 3.538 1.60695 3.47695 1 P 0 
L 1.60695 3.47695 1.352 3.47695 1 P 0 
P 1.352 3.47695 96 P 0 8 0;0,2=18,4=0
P 2.05 3.538 11 P 0 8 0;2=1,4=1
L 2.05 3.488 1.9853 3.488 1 P 0 
L 1.9853 3.488 1.9806 3.4927 1 P 0 
L 1.9806 3.4927 1.9806 3.5143 1 P 0 
L 1.9806 3.5143 1.9759 3.519 1 P 0 
L 1.9759 3.519 1.9606 3.519 1 P 0 
L 1.9606 3.519 1.9559 3.5143 1 P 0 
L 1.9559 3.5143 1.9559 3.4927 1 P 0 
L 1.9559 3.4927 1.9512 3.488 1 P 0 
L 1.9512 3.488 1.9359 3.488 1 P 0 
L 1.9359 3.488 1.9312 3.4927 1 P 0 
L 1.9312 3.4927 1.9312 3.5143 1 P 0 
L 1.9312 3.5143 1.9265 3.519 1 P 0 
L 1.9265 3.519 1.9112 3.519 1 P 0 
L 1.9112 3.519 1.9065 3.5143 1 P 0 
L 1.9065 3.5143 1.9065 3.4927 1 P 0 
L 1.9065 3.4927 1.9018 3.488 1 P 0 
L 1.9018 3.488 1.8865 3.488 1 P 0 
L 1.8865 3.488 1.8818 3.4927 1 P 0 
L 1.8818 3.4927 1.8818 3.5143 1 P 0 
L 1.8818 3.5143 1.8771 3.519 1 P 0 
L 1.8771 3.519 1.8618 3.519 1 P 0 
L 1.8618 3.519 1.8571 3.5143 1 P 0 
L 1.8571 3.5143 1.8571 3.4927 1 P 0 
L 1.8571 3.4927 1.8524 3.488 1 P 0 
L 1.8524 3.488 1.8371 3.488 1 P 0 
L 1.8371 3.488 1.8324 3.4927 1 P 0 
L 1.8324 3.4927 1.8324 3.5143 1 P 0 
L 1.8324 3.5143 1.8277 3.519 1 P 0 
L 1.8277 3.519 1.8124 3.519 1 P 0 
L 1.8124 3.519 1.8077 3.5143 1 P 0 
L 1.8077 3.5143 1.8077 3.4927 1 P 0 
L 1.8077 3.4927 1.803 3.488 1 P 0 
L 1.803 3.488 1.7877 3.488 1 P 0 
L 1.7877 3.488 1.783 3.4927 1 P 0 
L 1.783 3.4927 1.783 3.5143 1 P 0 
L 1.783 3.5143 1.7783 3.519 1 P 0 
L 1.7783 3.519 1.763 3.519 1 P 0 
L 1.763 3.519 1.7583 3.5143 1 P 0 
L 1.7583 3.5143 1.7583 3.4927 1 P 0 
L 1.7583 3.4927 1.7536 3.488 1 P 0 
L 1.7536 3.488 1.643 3.488 1 P 0 
L 1.643 3.488 1.61226998 3.45726998 1 P 0 
L 1.61226998 3.45726998 1.352 3.45726998 1 P 0 
P 1.352 3.45726998 96 P 0 8 0;0,2=18,4=0
P 2.05 3.488 11 P 0 8 0;2=1,4=1
L 1.04018996 3.47425 1.04018996 3.47518996 6 P 0 
L 1.04018996 3.47518996 1.0541 3.4891 6 P 0 
L 1.0541 3.4891 1.0541 3.578 6 P 0 
P 1.0541 3.12 40 P 0 8 0;0,2=18,4=0
L 1.0541 3.12 1.0541 3.185 6 P 0 
L 1.29 3.215 1.30363996 3.20136004 8 P 0 
L 1.30363996 3.20136004 1.352 3.20136004 8 P 0 
L 1.352 3.49663996 1.3 3.49663996 6 P 0 
P 1.29 3.215 11 P 0 8 0;2=7,4=1
P 1.352 3.20136004 96 P 0 8 0;0,2=18,4=0
P 1.0541 3.185 11 P 0 8 0;2=1,4=1
P 1.3 3.49663996 11 P 0 8 0;2=7,4=1
P 1.352 3.49663996 96 P 0 8 0;0,2=18,4=0
P 1.04018996 3.47425 11 P 0 8 0;2=7,4=1
P 1.0541 3.578 40 P 0 8 0;0,2=18,4=0
L 4.205 3.66 4.2072 3.6622 1 P 0 
L 4.2072 3.6622 4.2745 3.6622 1 P 0 
P 4.205 3.66 11 P 0 8 0;2=1,4=1
P 4.2745 3.6622 94 P 0 8 0;0,2=10,4=0
P 0.975 3.41 11 P 0 8 0;2=7,4=1
L 4.225 3.545 4.225 3.57001004 1 P 0 
L 4.225 3.57001004 4.24041998 3.58543002 1 P 0 
L 4.24041998 3.58543002 4.2745 3.58543002 1 P 0 
P 4.225 3.545 11 P 0 8 0;2=1,4=1
P 4.2745 3.58543002 94 P 0 8 0;0,2=10,4=0
P 1.015 3.41 11 P 0 8 0;2=7,4=1
L 4.0355 3.61101998 3.96101998 3.61101998 1 P 0 
L 3.96101998 3.61101998 3.95 3.6 1 P 0 
P 3.95 3.6 11 P 0 8 0;2=1,4=1
P 4.0355 3.61101998 94 P 0 8 0;0,2=10,4=0
P 0.835 3.6 11 P 0 8 0;2=7,4=1
L 3.95 3.7 3.9622 3.6878 1 P 0 
L 3.9622 3.6878 4.0355 3.6878 1 P 0 
P 3.95 3.7 11 P 0 8 0;2=1,4=1
P 4.0355 3.6878 94 P 0 8 0;0,2=10,4=0
P 0.915 3.595 11 P 0 8 0;2=7,4=1
L 4.1184 3.5362 4.1237 3.5415 1 P 0 
L 4.1237 3.5415 4.1237 3.609 1 P 0 
L 4.1237 3.609 4.09608996 3.63661004 1 P 0 
L 4.09608996 3.63661004 4.0355 3.63661004 1 P 0 
P 4.1184 3.5362 11 P 0 8 0;2=7,4=1
L 4.1695 3.11761004 4.09261004 3.11761004 1 P 0 
L 4.09261004 3.11761004 4.085 3.11 1 P 0 
P 4.085 3.11 11 P 0 8 0;2=1,4=1
P 4.1695 3.11761004 94 P 0 8 0;0,2=10,4=0
P 4.0355 3.63661004 94 P 0 8 0;0,2=10,4=0
L 4.51 3.065 4.495 3.065 1 P 0 
L 4.495 3.065 4.46798002 3.09201998 1 P 0 
L 4.46798002 3.09201998 4.4085 3.09201998 1 P 0 
L 4.2745 3.61101998 4.32746004 3.61101998 1 P 0 
L 4.32746004 3.61101998 4.33381998 3.60466004 1 P 0 
P 4.51 3.065 11 P 0 8 0;2=7,4=1
P 4.4085 3.09201998 94 P 0 8 0;0,2=10,4=0
P 4.33381998 3.60466004 11 P 0 8 0;2=1,4=1
P 4.2745 3.61101998 94 P 0 8 0;0,2=10,4=0
L 4.4085 3.1688 4.3612 3.1688 1 P 0 
L 4.3612 3.1688 4.34 3.19 1 P 0 
L 4.34 3.19 4.34 3.28 1 P 0 
P 4.34 3.28 11 P 0 8 0;2=7,4=1
P 4.4085 3.1688 94 P 0 8 0;0,2=10,4=0
L 4.335 3.665 4.335 3.68 1 P 0 
L 4.335 3.68 4.3272 3.6878 1 P 0 
L 4.3272 3.6878 4.2745 3.6878 1 P 0 
P 4.335 3.665 11 P 0 8 0;2=1,4=1
P 4.2745 3.6878 94 P 0 8 0;0,2=10,4=0
L 4.09 3.71338996 4.09 3.6919 1 P 0 
L 4.09 3.6919 4.185 3.5969 1 P 0 
L 4.185 3.5969 4.185 3.545 1 P 0 
L 4.185 3.545 4.25 3.48 1 P 0 
L 4.25 3.48 4.25 3.39673996 1 P 0 
L 4.25 3.39673996 4.2547 3.39203996 1 P 0 
L 4.2547 3.39203996 4.2842 3.39203996 1 P 0 
L 4.2842 3.39203996 4.2889 3.38733996 1 P 0 
L 4.2889 3.38733996 4.2889 3.37203996 1 P 0 
L 4.2889 3.37203996 4.2842 3.36733996 1 P 0 
L 4.2842 3.36733996 4.2547 3.36733996 1 P 0 
L 4.2547 3.36733996 4.25 3.36263996 1 P 0 
L 4.25 3.36263996 4.25 3.34733996 1 P 0 
L 4.25 3.34733996 4.2547 3.34263996 1 P 0 
L 4.2547 3.34263996 4.2842 3.34263996 1 P 0 
L 4.2842 3.34263996 4.2889 3.33793996 1 P 0 
L 4.2889 3.33793996 4.2889 3.32263996 1 P 0 
L 4.2889 3.32263996 4.2842 3.31793996 1 P 0 
L 4.2842 3.31793996 4.2547 3.31793996 1 P 0 
L 4.2547 3.31793996 4.25 3.31323996 1 P 0 
L 4.25 3.31323996 4.25 3.22601004 1 P 0 
L 4.25 3.22601004 4.21898996 3.195 1 P 0 
L 4.21898996 3.195 4.17011004 3.195 1 P 0 
L 4.17011004 3.195 4.1695 3.19438996 1 P 0 
L 4.09 3.71338996 4.0355 3.71338996 1 P 0 
P 4.09 3.71338996 11 P 0 8 0;2=1,4=1
P 4.1695 3.19438996 94 P 0 8 0;0,2=10,4=0
P 4.0355 3.71338996 94 P 0 8 0;0,2=10,4=0
P 3.38 1.025 11 P 0 8 0;2=7,4=1
L 4.585 0.865 4.585 0.845 1 P 0 
L 4.585 0.845 4.625 0.805 1 P 0 
L 4.625 0.805 4.625 0.715 1 P 0 
L 4.625 0.715 4.59 0.68 1 P 0 
L 4.59 0.68 3.67 0.68 1 P 0 
L 3.67 0.68 3.585 0.765 1 P 0 
L 3.585 0.765 3.435 0.765 1 P 0 
L 3.435 0.765 3.38 0.82 1 P 0 
L 3.38 0.82 3.38 1.025 1 P 0 
L 0.62 3.235 0.62501004 3.235 1 P 0 
L 0.62501004 3.235 0.64736004 3.25735 1 P 0 
L 0.64736004 3.25735 0.65735 3.25735 1 P 0 
L 0.65735 3.25735 0.67265 3.27265 1 P 0 
L 0.67265 3.27265 0.72341004 3.27265 1 P 0 
L 0.72341004 3.27265 0.74235 3.29158996 1 P 0 
L 0.74235 3.29158996 0.74235 3.32748002 1 P 0 
L 0.74235 3.32748002 0.77486998 3.36 1 P 0 
L 0.77486998 3.36 0.82661004 3.36 1 P 0 
L 0.82661004 3.36 0.84513996 3.37853002 1 P 0 
L 0.84513996 3.37853002 0.894 3.37853002 1 P 0 
L 4.694 0.915 4.675 0.915 1 P 0 
L 4.675 0.915 4.655 0.895 1 P 0 
L 4.655 0.895 4.615 0.895 1 P 0 
L 4.615 0.895 4.585 0.865 1 P 0 
P 4.585 0.865 11 P 0 8 0;2=1,4=1
P 4.694 0.915 63 P 0 8 0;0,2=2,4=0
P 0.894 3.37853002 96 P 0 8 0;0,2=18,4=0
P 0.62 3.235 11 P 0 8 0;2=7,4=1
L 3.973 3.239 3.925 3.239 1 P 0 
P 3.925 3.239 11 P 0 8 0;2=1,4=1
P 3.973 3.239 63 P 0 8 0;0,2=2,4=0
P 0.825 3.39 11 P 0 8 0;2=7,4=1
L 0.894 3.39821004 0.83321004 3.39821004 1 P 0 
L 0.83321004 3.39821004 0.825 3.39 1 P 0 
P 0.894 3.39821004 96 P 0 8 0;0,2=18,4=0
L 0.894 3.4179 0.795 3.4179 1 P 0 
L 3.839 3.758 3.795 3.758 1 P 0 
P 0.795 3.4179 11 P 0 8 0;2=7,4=1
P 0.894 3.4179 96 P 0 8 0;0,2=18,4=0
P 3.795 3.758 11 P 0 8 0;2=1,4=1
P 3.839 3.758 63 P 0 8 0;0,2=2,4=0
L 0.704 3.2 0.704 3.17853996 1 P 0 
L 0.704 3.17853996 0.69928996 3.17383002 1 P 0 
L 0.69928996 3.17383002 0.67116998 3.17383002 1 P 0 
L 0.67116998 3.17383002 0.66 3.185 1 P 0 
P 3.62 1.28 11 P 0 8 0;2=7,4=1
L 5.195 0.755 5.18398002 0.76601998 1 P 0 
L 5.18398002 0.76601998 5.1245 0.76601998 1 P 0 
P 5.195 0.755 11 P 0 8 0;2=1,4=1
P 5.1245 0.76601998 94 P 0 8 0;0,2=10,4=0
L 4.8855 0.86838996 4.94161004 0.86838996 1 P 0 
L 4.94161004 0.86838996 4.96 0.85 1 P 0 
P 4.96 0.85 11 P 0 8 0;2=7,4=1
P 4.8855 0.86838996 94 P 0 8 0;0,2=10,4=0
P 0.704 3.2 63 P 0 8 0;0,2=2,4=0
P 0.66 3.185 11 P 0 8 0;2=7,4=1
P 3.62 1.235 11 P 0 8 0;2=7,4=1
L 5.195 0.815 5.1672 0.8428 1 P 0 
L 5.1672 0.8428 5.1245 0.8428 1 P 0 
L 0.704 3.245 0.694 3.235 1 P 0 
L 0.694 3.235 0.66 3.235 1 P 0 
P 5.195 0.815 11 P 0 8 0;2=1,4=1
P 5.1245 0.8428 94 P 0 8 0;0,2=10,4=0
L 4.937 0.79161004 4.8855 0.79161004 1 P 0 
P 4.8855 0.79161004 94 P 0 8 0;0,2=10,4=0
P 4.937 0.79161004 11 P 0 8 0;2=7,4=1
P 0.66 3.235 11 P 0 8 0;2=7,4=1
P 0.704 3.245 63 P 0 8 0;0,2=2,4=0
L 4.205 3.81 4.22 3.795 1 P 0 
L 4.22 3.795 4.22 3.73001004 1 P 0 
L 4.22 3.73001004 4.23661998 3.71338996 1 P 0 
L 4.23661998 3.71338996 4.2745 3.71338996 1 P 0 
P 4.205 3.81 11 P 0 8 0;2=7,4=1
P 4.2745 3.71338996 94 P 0 8 0;0,2=10,4=0
P 5.71056004 2.821 43 P 0 8 0;0,2=37,4=0
P 5.814 2.821 9 P 0 8 0;2=24,4=1
L 5.71056004 2.821 5.814 2.821 1 P 0 
L 4.19 3.735 4.16 3.705 1 P 0 
L 4.16 3.705 4.16 3.65 1 P 0 
L 4.16 3.65 4.17338996 3.63661004 1 P 0 
L 4.17338996 3.63661004 4.2745 3.63661004 1 P 0 
P 4.19 3.735 11 P 0 8 0;2=7,4=1
P 4.2745 3.63661004 94 P 0 8 0;0,2=10,4=0
P 5.71056004 2.721 43 P 0 8 0;0,2=37,4=0
P 5.814 2.721 9 P 0 8 0;2=24,4=1
L 5.71056004 2.721 5.814 2.721 1 P 0 
L 3.895 3.7 3.895 3.685 1 P 0 
L 3.895 3.685 3.91791998 3.66208002 1 P 0 
L 3.91791998 3.66208002 3.95088002 3.66208002 1 P 0 
L 3.95088002 3.66208002 3.951 3.6622 1 P 0 
L 3.951 3.6622 4.0355 3.6622 1 P 0 
P 3.895 3.7 11 P 0 8 0;2=7,4=1
P 4.0355 3.6622 94 P 0 8 0;0,2=10,4=0
L 5.71056004 3.021 5.815 3.021 1 P 0 
P 5.71056004 3.021 43 P 0 8 0;0,2=37,4=0
P 5.815 3.021 9 P 0 8 0;2=24,4=1
L 4.135 3.735 4.115 3.735 1 P 0 
L 4.115 3.735 4.11101998 3.73898002 1 P 0 
L 4.11101998 3.73898002 4.0355 3.73898002 1 P 0 
P 4.135 3.735 11 P 0 8 0;2=7,4=1
P 4.0355 3.73898002 94 P 0 8 0;0,2=10,4=0
P 5.71056004 2.621 43 P 0 8 0;0,2=37,4=0
P 5.814 2.621 9 P 0 8 0;2=24,4=1
L 5.71056004 2.621 5.814 2.621 1 P 0 
L 6.22356004 2.615 6.32 2.615 1 P 0 
L 6.32 2.615 6.33 2.625 1 P 0 
L 6.33 2.625 6.33 2.67 1 P 0 
L 6.33 2.67 6.33 2.7103 1 P 0 
L 6.33 2.7103 6.3253 2.715 1 P 0 
L 6.3253 2.715 6.22356004 2.715 1 P 0 
P 2.3 3.475 11 P 0 8 0;2=7,4=1
P 5.045 3.405 11 P 0 8 0;2=7,4=1
P 6.22356004 2.715 43 P 0 8 0;0,2=37,4=0
P 6.33 2.67 9 P 0 8 0;2=24,4=1
P 6.22356004 2.615 43 P 0 8 0;0,2=37,4=0
P 1.35 3.12 11 P 0 8 0;2=7,4=1
L 6.33 2.865 6.33 2.9 1 P 0 
L 6.33 2.9 6.315 2.915 1 P 0 
L 6.315 2.915 6.22356004 2.915 1 P 0 
L 6.22356004 2.815 6.315 2.815 1 P 0 
L 6.315 2.815 6.33 2.83 1 P 0 
L 6.33 2.83 6.33 2.865 1 P 0 
P 2.255 3.475 11 P 0 8 0;2=7,4=1
P 5.09 3.405 11 P 0 8 0;2=7,4=1
P 6.22356004 2.815 43 P 0 8 0;0,2=37,4=0
P 6.33 2.865 11 P 0 8 0;2=1,4=1
P 6.22356004 2.915 43 P 0 8 0;0,2=37,4=0
P 1.46 3.34 11 P 0 8 0;2=7,4=1
L 4.705 0.825 4.736 0.856 1 P 0 
L 4.736 0.856 4.736 0.865 1 P 0 
P 4.575 2.235 11 P 0 8 0;2=7,4=1
L 4.48216998 1.92216998 4.50185 1.94185 1 P 0 
P 4.50185 1.94185 9 P 0 8 0;2=4,4=1
P 4.48216998 1.92216998 10 P 0 8 0;0,2=5,4=0
L 4.736 0.865 4.81 0.865 1 P 0 
L 4.81 0.865 4.83898002 0.89398002 1 P 0 
L 4.83898002 0.89398002 4.8855 0.89398002 1 P 0 
P 4.705 0.825 11 P 0 8 0;2=1,4=1
P 4.736 0.865 63 P 0 8 0;0,2=2,4=0
P 4.8855 0.89398002 94 P 0 8 0;0,2=10,4=0
L 4.755 0.825 4.745 0.825 1 P 0 
L 4.745 0.825 4.736 0.816 1 P 0 
L 4.736 0.816 4.736 0.785 1 P 0 
L 4.8855 0.8172 4.8472 0.8172 1 P 0 
L 4.8472 0.8172 4.835 0.805 1 P 0 
L 4.835 0.805 4.77 0.805 1 P 0 
L 4.77 0.805 4.75 0.785 1 P 0 
L 4.75 0.785 4.736 0.785 1 P 0 
P 4.575 2.275 11 P 0 8 0;2=7,4=1
L 4.36406004 1.96153996 4.38373996 1.98121998 1 P 0 
P 4.38373996 1.98121998 9 P 0 8 0;2=4,4=1
P 4.36406004 1.96153996 10 P 0 8 0;0,2=5,4=0
P 4.755 0.825 11 P 0 8 0;2=1,4=1
P 4.736 0.785 63 P 0 8 0;0,2=2,4=0
P 4.8855 0.8172 94 P 0 8 0;0,2=10,4=0
P 1.26 0.72 11 P 0 8 0;2=1,4=1
L 4.67901998 1.80406004 4.6987 1.82373996 1 P 0 
P 4.6987 1.82373996 9 P 0 8 0;2=4,4=1
P 4.67901998 1.80406004 10 P 0 8 0;0,2=5,4=0
P 0.842 0.75 11 P 0 8 0;2=1,4=1
L 4.71838996 1.80406004 4.73806998 1.82373996 1 P 0 
P 4.73806998 1.82373996 9 P 0 8 0;2=4,4=1
P 4.71838996 1.80406004 10 P 0 8 0;0,2=5,4=0
P 4.10816004 1.90248002 9 P 0 8 0;2=15,4=1
P 3.73648996 1.85735 11 P 0 8 0;2=7,4=1
L 4.12783996 1.8828 4.10816004 1.90248002 1 P 0 
L 4.694 0.965 4.63 1.029 1 P 0 
L 4.63 1.029 4.63 1.12 1 P 0 
L 4.63 1.12 4.67 1.16 1 P 0 
L 4.67 1.16 4.67 1.205 1 P 0 
L 4.67 1.205 4.625 1.25 1 P 0 
L 4.625 1.25 4.39501004 1.25 1 P 0 
L 4.39501004 1.25 4.34501004 1.2 1 P 0 
L 4.34501004 1.2 4.13 1.2 1 P 0 
L 4.13 1.2 4.075 1.255 1 P 0 
L 4.075 1.255 3.87 1.255 1 P 0 
L 3.87 1.255 3.845 1.28 1 P 0 
L 3.845 1.28 3.845 1.445 1 P 0 
L 3.845 1.445 3.825 1.465 1 P 0 
L 3.825 1.465 3.825 1.65 1 P 0 
L 3.825 1.65 3.715 1.76 1 P 0 
L 3.715 1.76 3.715 1.81 1 P 0 
L 3.715 1.81 3.73648996 1.83148996 1 P 0 
L 3.73648996 1.83148996 3.73648996 1.85735 1 P 0 
P 4.694 0.965 63 P 0 8 0;0,2=2,4=0
P 4.12783996 1.8828 10 P 0 8 0;0,2=5,4=0
P 4.10816004 1.82373996 9 P 0 8 0;2=4,4=1
L 4.075 3.005 4.095 3.005 1 P 0 
L 4.095 3.005 4.12 3.03 1 P 0 
L 4.12 3.03 4.335 3.03 1 P 0 
L 4.335 3.03 4.345 3.02 1 P 0 
L 3.973 3.291 3.925 3.291 1 P 0 
P 4.345 3.02 11 P 0 8 0;2=7,4=1
L 4.12783996 1.80406004 4.10816004 1.82373996 1 P 0 
P 4.12783996 1.80406004 10 P 0 8 0;0,2=5,4=0
P 4.075 3.005 11 P 0 8 0;2=7,4=1
P 3.925 3.291 11 P 0 8 0;2=1,4=1
P 3.973 3.291 63 P 0 8 0;0,2=2,4=0
P 4.14753002 1.82373996 9 P 0 8 0;2=4,4=1
L 4.13 3.005 4.14 2.995 1 P 0 
L 4.14 2.995 4.365 2.995 1 P 0 
L 4.365 2.995 4.39 3.02 1 P 0 
L 3.839 3.81 3.795 3.81 1 P 0 
P 4.39 3.02 11 P 0 8 0;2=7,4=1
L 4.16721004 1.80406004 4.14753002 1.82373996 1 P 0 
P 4.16721004 1.80406004 10 P 0 8 0;0,2=5,4=0
P 4.13 3.005 11 P 0 8 0;2=7,4=1
P 3.795 3.81 11 P 0 8 0;2=1,4=1
P 3.839 3.81 63 P 0 8 0;0,2=2,4=0
L 4.4 3.325 4.39 3.335 1 P 0 
L 4.39 3.335 4.39 3.345 1 P 0 
L 4.39 3.345 4.34 3.395 1 P 0 
L 4.34 3.395 4.34 3.454 1 P 0 
P 4.615 3.11 11 P 0 8 0;2=7,4=1
L 4.67901998 1.8828 4.6987 1.90248002 1 P 0 
P 4.6987 1.90248002 9 P 0 8 0;2=4,4=1
P 4.67901998 1.8828 10 P 0 8 0;0,2=5,4=0
P 4.34 3.454 58 P 0 8 0;0,2=2,4=0
P 4.4 3.325 11 P 0 8 0;2=1,4=1
P 4.615 2.68408996 11 P 0 8 0;2=7,4=1
L 4.15 2.468 4.17235 2.44565 1 P 0 
L 4.17235 2.44565 4.26835 2.44565 1 P 0 
L 4.26835 2.44565 4.34265 2.37135 1 P 0 
L 4.34265 2.37135 4.34265 2.22565 1 P 0 
L 4.34265 2.22565 4.304 2.187 1 P 0 
L 4.304 2.187 4.304 2.1377 1 P 0 
L 4.304 2.1377 4.28531998 2.11901998 1 P 0 
P 4.28531998 2.11901998 10 P 0 8 0;0,2=5,4=0
L 4.15 2.51 4.15 2.468 1 P 0 
P 4.15 2.468 11 P 0 8 0;2=7,4=1
P 4.15 2.51 58 P 0 8 0;0,2=2,4=0
P 6.22 1.415 11 P 0 8 0;2=1,4=1
L 4.685 2.7 4.66 2.675 1 P 0 
L 4.66 2.675 4.66 2.66 1 P 0 
L 4.66 2.66 4.635 2.635 1 P 0 
L 4.635 2.635 4.635 2.57 1 P 0 
L 4.635 2.57 4.605 2.54 1 P 0 
L 4.605 2.54 4.345 2.54 1 P 0 
L 4.345 2.54 4.315 2.51 1 P 0 
L 4.315 2.51 4.209 2.51 1 P 0 
P 4.685 2.7 11 P 0 8 0;2=7,4=1
L 4.209 2.51 4.209 2.468 1 P 0 
P 4.209 2.51 58 P 0 8 0;0,2=2,4=0
P 4.209 2.468 11 P 0 8 0;2=7,4=1
P 4.34436998 2.1387 9 P 0 8 0;2=4,4=1
L 4.32468996 2.11901998 4.34436998 2.1387 1 P 0 
P 4.32468996 2.11901998 10 P 0 8 0;0,2=5,4=0
P 6.22 1.516 11 P 0 8 0;2=1,4=1
P 4.975 2.26 11 P 0 8 0;2=7,4=1
L 4.093 2.468 4.13005 2.43095 1 P 0 
L 4.13005 2.43095 4.26225 2.43095 1 P 0 
L 4.26225 2.43095 4.32795 2.36525 1 P 0 
L 4.32795 2.36525 4.32795 2.2621 1 P 0 
L 4.32795 2.2621 4.24595 2.1801 1 P 0 
L 4.24595 2.1801 4.24595 2.15838996 1 P 0 
P 4.093 2.51 58 P 0 8 0;0,2=2,4=0
L 4.093 2.51 4.093 2.468 1 P 0 
P 4.093 2.468 11 P 0 8 0;2=7,4=1
P 4.24595 2.15838996 10 P 0 8 0;0,2=5,4=0
P 6.22 1.62 11 P 0 8 0;2=1,4=1
P 4.925 2.26 11 P 0 8 0;2=1,4=1
L 4.037 2.468 4.08875 2.41625 1 P 0 
L 4.08875 2.41625 4.25616004 2.41625 1 P 0 
L 4.25616004 2.41625 4.31325 2.35916004 1 P 0 
L 4.31325 2.35916004 4.31325 2.26425 1 P 0 
L 4.31325 2.26425 4.225 2.176 1 P 0 
L 4.225 2.176 4.225 2.13996998 1 P 0 
L 4.225 2.13996998 4.24595 2.11901998 1 P 0 
P 4.037 2.51 58 P 0 8 0;0,2=2,4=0
L 4.037 2.51 4.037 2.468 1 P 0 
P 4.037 2.468 11 P 0 8 0;2=7,4=1
P 4.24595 2.11901998 10 P 0 8 0;0,2=5,4=0
P 6.22 1.815 11 P 0 8 0;2=1,4=1
P 5.92 1.41 11 P 0 8 0;2=1,4=1
P 5.09 2.155 11 P 0 8 0;2=7,4=1
P 3.801 2.51 58 P 0 8 0;0,2=2,4=0
L 3.801 2.51 3.801 2.468 1 P 0 
P 3.801 2.468 11 P 0 8 0;2=7,4=1
P 4.10816004 2.09933002 9 P 0 8 0;2=4,4=1
P 4.12783996 2.07965 10 P 0 8 0;0,2=5,4=0
L 4.12783996 2.07965 4.10816004 2.09933002 1 P 0 
P 5.92 1.515 11 P 0 8 0;2=1,4=1
P 5.135 2.155 11 P 0 8 0;2=7,4=1
P 3.86 2.468 11 P 0 8 0;2=7,4=1
L 3.86 2.51 3.86 2.468 1 P 0 
P 3.86 2.51 58 P 0 8 0;0,2=2,4=0
P 4.14753002 2.09933002 9 P 0 8 0;2=4,4=1
P 4.16721004 2.07965 10 P 0 8 0;0,2=5,4=0
L 4.16721004 2.07965 4.14753002 2.09933002 1 P 0 
P 5.92 1.63 11 P 0 8 0;2=1,4=1
P 5.115 2.065 11 P 0 8 0;2=7,4=1
L 3.919 2.468 4.00015 2.38685 1 P 0 
L 4.00015 2.38685 4.23915 2.38685 1 P 0 
L 4.23915 2.38685 4.282 2.344 1 P 0 
L 4.282 2.344 4.282 2.28 1 P 0 
L 4.282 2.28 4.16721004 2.16521004 1 P 0 
L 4.16721004 2.16521004 4.16721004 2.15838996 1 P 0 
P 3.919 2.51 58 P 0 8 0;0,2=2,4=0
L 3.919 2.51 3.919 2.468 1 P 0 
P 3.919 2.468 11 P 0 8 0;2=7,4=1
P 4.16721004 2.15838996 10 P 0 8 0;0,2=5,4=0
P 5.92 1.73 11 P 0 8 0;2=1,4=1
P 5.13 2.105 11 P 0 8 0;2=7,4=1
L 4.20658002 2.15838996 4.20658002 2.17658002 1 P 0 
L 4.20658002 2.17658002 4.29855 2.26855 1 P 0 
L 4.29855 2.26855 4.29855 2.35306998 1 P 0 
L 4.29855 2.35306998 4.25006998 2.40155 1 P 0 
L 4.25006998 2.40155 4.04445 2.40155 1 P 0 
L 4.04445 2.40155 3.978 2.468 1 P 0 
P 4.20658002 2.15838996 10 P 0 8 0;0,2=5,4=0
P 3.978 2.51 58 P 0 8 0;0,2=2,4=0
L 3.978 2.51 3.978 2.468 1 P 0 
P 3.978 2.468 11 P 0 8 0;2=7,4=1
L 4.685 2.645 4.675 2.645 1 P 0 
L 4.675 2.645 4.655 2.625 1 P 0 
L 4.655 2.625 4.655 2.48 1 P 0 
L 4.655 2.48 4.636 2.461 1 P 0 
L 4.636 2.461 4.62 2.461 1 P 0 
P 4.685 2.645 11 P 0 8 0;2=7,4=1
P 4.62 2.461 58 P 0 8 0;0,2=2,4=0
L 4.1 3.38 4.08 3.4 1 P 0 
L 4.08 3.4 4.08 3.429 1 P 0 
L 4.14941004 3.4076 4.1276 3.4076 1 P 0 
L 4.1276 3.4076 4.1 3.38 1 P 0 
P 4.1 3.38 11 P 0 8 0;2=1,4=1
P 4.14941004 3.4076 49 P 0 8 0;0,2=11,4=0
P 4.08 3.429 58 P 0 8 0;0,2=2,4=0
P 4.53 2.461 58 P 0 8 0;0,2=2,4=0
L 4.53 2.461 4.53 2.5 1 P 0 
P 4.53 2.5 11 P 0 8 0;2=7,4=1
L 3.9 3.385 3.87 3.415 1 P 0 
L 3.87 3.415 3.87 3.424 1 P 0 
L 3.95441004 3.4056 3.9206 3.4056 1 P 0 
L 3.9206 3.4056 3.9 3.385 1 P 0 
P 3.9 3.385 11 P 0 8 0;2=1,4=1
P 3.95441004 3.4056 49 P 0 8 0;0,2=11,4=0
P 3.87 3.424 58 P 0 8 0;0,2=2,4=0
L 4.485 3.115 4.48238996 3.11761004 1 P 0 
L 4.48238996 3.11761004 4.4085 3.11761004 1 P 0 
P 4.575 2.419 58 P 0 8 0;0,2=2,4=0
P 4.4085 3.11761004 94 P 0 8 0;0,2=10,4=0
P 4.485 3.115 11 P 0 8 0;2=1,4=1
P 4.535 2.366 58 P 0 8 0;0,2=2,4=0
L 4.535 2.366 4.567 2.366 1 P 0 
L 4.567 2.366 4.575 2.374 1 P 0 
P 4.575 2.374 11 P 0 8 0;2=7,4=1
L 4.575 2.419 4.575 2.374 1 P 0 
L 4.29441998 3.10075 4.29415 3.10075 1 P 0 
L 4.29415 3.10075 4.2517 3.1432 1 P 0 
L 4.2517 3.1432 4.1695 3.1432 1 P 0 
P 4.485 2.461 58 P 0 8 0;0,2=2,4=0
L 4.485 2.461 4.485 2.5 1 P 0 
P 4.485 2.5 11 P 0 8 0;2=7,4=1
P 4.29441998 3.10075 11 P 0 8 0;2=1,4=1
P 4.1695 3.1432 94 P 0 8 0;0,2=10,4=0
L 4.54 3.125 4.47061004 3.19438996 1 P 0 
L 4.47061004 3.19438996 4.4085 3.19438996 1 P 0 
P 4.61 2.345 11 P 0 8 0;2=7,4=1
L 4.65 2.341 4.614 2.341 1 P 0 
L 4.614 2.341 4.61 2.345 1 P 0 
P 4.65 2.341 58 P 0 8 0;0,2=2,4=0
P 4.4085 3.19438996 94 P 0 8 0;0,2=10,4=0
P 4.54 3.125 11 P 0 8 0;2=1,4=1
L 4.085 3.21998002 4.1695 3.21998002 1 P 0 
P 4.085 3.21998002 11 P 0 8 0;2=1,4=1
P 4.1695 3.21998002 94 P 0 8 0;0,2=10,4=0
P 4.35 2.505 11 P 0 8 0;2=7,4=1
L 4.71838996 1.96153996 4.74846004 1.96153996 1 P 0 
L 4.74846004 1.96153996 4.81 1.9 1 P 0 
L 4.81 1.9 5.00501004 1.9 1 P 0 
L 5.00501004 1.9 5.04 1.86501004 1 P 0 
L 5.04 1.86501004 5.04 1.735 1 P 0 
L 5.04 1.735 5.09 1.685 1 P 0 
L 5.09 1.685 5.09 1.2334 1 P 0 
L 5.09 1.2334 5.21681998 1.10658002 1 P 0 
L 5.21681998 1.10658002 5.32681998 1.10658002 1 P 0 
L 5.32681998 1.10658002 5.375 1.0584 1 P 0 
L 5.375 1.0584 5.375 0.88 1 P 0 
L 5.375 0.88 5.39 0.865 1 P 0 
L 5.39 0.865 5.39 0.815 1 P 0 
L 5.39 0.815 5.365 0.79 1 P 0 
L 5.365 0.79 5.26 0.79 1 P 0 
L 5.26 0.79 5.249 0.779 1 P 0 
L 5.249 0.779 5.249 0.76 1 P 0 
P 5.365 0.79 11 P 0 8 0;2=1,4=1
L 5.249 0.76 5.23096004 0.76 1 P 0 
L 5.23096004 0.76 5.22 0.77096004 1 P 0 
L 5.22 0.77096004 5.22 0.7753 1 P 0 
L 5.22 0.7753 5.2103 0.785 1 P 0 
L 5.2103 0.785 5.16998996 0.785 1 P 0 
L 5.16998996 0.785 5.16338002 0.79161004 1 P 0 
L 5.16338002 0.79161004 5.1245 0.79161004 1 P 0 
P 5.1245 0.79161004 94 P 0 8 0;0,2=10,4=0
P 5.249 0.76 63 P 0 8 0;0,2=2,4=0
P 4.71838996 1.96153996 10 P 0 8 0;0,2=5,4=0
L 4.71838996 1.92216998 4.75775 1.92216998 1 P 0 
L 4.75775 1.92216998 4.79991998 1.88 1 P 0 
L 4.79991998 1.88 4.99 1.88 1 P 0 
L 4.99 1.88 5.02 1.85 1 P 0 
L 5.02 1.85 5.02 1.73 1 P 0 
L 5.02 1.73 5.07 1.68 1 P 0 
L 5.07 1.68 5.07 1.22498996 1 P 0 
L 5.07 1.22498996 5.20848996 1.0865 1 P 0 
L 5.20848996 1.0865 5.21805 1.0865 1 P 0 
L 5.21805 1.0865 5.22275 1.0818 1 P 0 
L 5.22275 1.0818 5.22275 1.0543 1 P 0 
L 5.22275 1.0543 5.22745 1.0496 1 P 0 
L 5.22745 1.0496 5.24275 1.0496 1 P 0 
L 5.24275 1.0496 5.24745 1.0543 1 P 0 
L 5.24745 1.0543 5.24745 1.0818 1 P 0 
L 5.24745 1.0818 5.25215 1.0865 1 P 0 
L 5.25215 1.0865 5.26745 1.0865 1 P 0 
L 5.26745 1.0865 5.27215 1.0818 1 P 0 
L 5.27215 1.0818 5.27215 1.0543 1 P 0 
L 5.27215 1.0543 5.27685 1.0496 1 P 0 
L 5.27685 1.0496 5.29215 1.0496 1 P 0 
L 5.29215 1.0496 5.29685 1.0543 1 P 0 
L 5.29685 1.0543 5.29685 1.0818 1 P 0 
L 5.29685 1.0818 5.30155 1.0865 1 P 0 
L 5.30155 1.0865 5.3185 1.0865 1 P 0 
L 5.3185 1.0865 5.355 1.05 1 P 0 
L 5.355 1.05 5.355 0.875 1 P 0 
L 5.355 0.875 5.365 0.865 1 P 0 
L 5.365 0.865 5.365 0.845 1 P 0 
L 5.249 0.82 5.249 0.83 1 P 0 
L 5.249 0.83 5.264 0.845 1 P 0 
L 5.264 0.845 5.365 0.845 1 P 0 
P 5.365 0.845 11 P 0 8 0;2=1,4=1
L 5.249 0.82 5.225 0.82 1 P 0 
L 5.225 0.82 5.205 0.84 1 P 0 
L 5.205 0.84 5.195 0.84 1 P 0 
L 5.195 0.84 5.16661004 0.86838996 1 P 0 
L 5.16661004 0.86838996 5.1245 0.86838996 1 P 0 
P 5.249 0.82 63 P 0 8 0;0,2=2,4=0
P 5.1245 0.86838996 94 P 0 8 0;0,2=10,4=0
P 4.71838996 1.92216998 10 P 0 8 0;0,2=5,4=0
L 4.08 3.471 4.08 3.5202 1 P 0 
L 4.08 3.5202 4.0661 3.5341 1 P 0 
P 4.0661 3.5341 11 P 0 8 0;2=1,4=1
L 4.14941004 3.4824 4.0914 3.4824 1 P 0 
L 4.0914 3.4824 4.08 3.471 1 P 0 
P 4.08 3.471 58 P 0 8 0;0,2=2,4=0
P 4.14941004 3.4824 49 P 0 8 0;0,2=11,4=0
L 3.87 3.466 3.83 3.466 1 P 0 
P 3.83 3.466 9 P 0 8 0;2=24,4=1
L 3.95441004 3.4804 3.8844 3.4804 1 P 0 
L 3.8844 3.4804 3.87 3.466 1 P 0 
P 3.87 3.466 58 P 0 8 0;0,2=2,4=0
P 3.95441004 3.4804 49 P 0 8 0;0,2=11,4=0
P 4.35143002 3.06643002 11 P 0 8 0;2=7,4=1
L 4.4085 3.06643002 4.35143002 3.06643002 1 P 0 
P 4.4085 3.06643002 94 P 0 8 0;0,2=10,4=0
P 3.7 3.325 11 P 0 8 0;2=1,4=1
L 3.5825 3.4005 3.5825 3.2405 1 P 0 
L 3.5825 3.2405 3.668 3.155 1 P 0 
L 3.668 3.155 4.005 3.155 1 P 0 
L 4.005 3.155 4.08 3.08 1 P 0 
L 4.08 3.08 4.1 3.08 1 P 0 
L 4.1 3.08 4.11201998 3.09201998 1 P 0 
L 4.11201998 3.09201998 4.1695 3.09201998 1 P 0 
P 4.1695 3.09201998 94 P 0 8 0;0,2=10,4=0
P 3.5825 3.4005 9 P 0 8 0;2=9,4=1
L 4.4085 3.1432 4.33 3.1432 1 P 0 
P 4.33 3.1432 11 P 0 8 0;2=7,4=1
P 4.4085 3.1432 94 P 0 8 0;0,2=10,4=0
P 3.83 3.235 11 P 0 8 0;2=1,4=1
L 3.769 3.235 3.83 3.235 1 P 0 
P 3.769 3.235 102 P 0 8 0;0,2=39,4=0
L 4.085 3.165 4.1244 3.165 1 P 0 
L 4.1244 3.165 4.1282 3.1688 1 P 0 
L 4.1282 3.1688 4.1695 3.1688 1 P 0 
P 4.085 3.165 11 P 0 8 0;2=7,4=1
P 4.1695 3.1688 94 P 0 8 0;0,2=10,4=0
P 3.415 3.335 9 P 0 8 0;2=9,4=1
L 3.481 3.335 3.415 3.335 1 P 0 
P 3.481 3.335 102 P 0 8 0;0,2=39,4=0
L 1.26 0.62 1.2214 0.6586 1 P 0 
L 1.2214 0.6586 1.2157 0.6586 1 P 0 
L 1.3085 0.613 1.271 0.613 1 P 0 
L 1.271 0.613 1.264 0.62 1 P 0 
L 1.264 0.62 1.26 0.62 1 P 0 
L 0.74 1.3 0.74 1.315 1 P 0 
L 0.74 1.315 0.76 1.335 1 P 0 
L 0.76 1.335 0.8 1.335 1 P 0 
L 0.8 1.335 0.805 1.34 1 P 0 
L 0.805 1.34 0.805 1.42243996 1 P 0 
L 1.3085 0.613 1.3085 0.658 1 P 0 
P 1.3085 0.658 63 P 0 8 0;0,2=2,4=0
P 1.3085 0.613 63 P 0 8 0;0,2=2,4=0
P 0.805 1.42243996 86 P 0 8 0;0,2=37,4=0
P 0.74 1.3 11 P 0 8 0;2=7,4=1
P 1.2157 0.6586 63 P 0 8 0;0,2=2,4=0
P 1.26 0.62 9 P 0 8 0;2=24,4=1
P 0.785 0.8225 11 P 0 8 0;2=7,4=1
L 0.76321004 0.783 0.7609 0.78531004 1 P 0 
L 0.7609 0.78531004 0.7609 0.8353 1 P 0 
L 0.7609 0.8353 0.7557 0.8405 1 P 0 
L 0.7557 0.8405 0.7312 0.8405 1 P 0 
L 0.7312 0.8405 0.7186 0.8279 1 P 0 
L 0.7186 0.8279 0.7186 0.8024 1 P 0 
L 0.7186 0.8024 0.7392 0.7818 1 P 0 
L 0.7392 0.7818 0.7392 0.7711 1 P 0 
L 0.7392 0.7711 0.76221004 0.74808996 1 P 0 
L 0.76221004 0.74808996 0.76221004 0.7085 1 P 0 
L 1.26 0.67 1.246 0.684 1 P 0 
L 1.246 0.684 1.1784 0.684 1 P 0 
L 1.1784 0.684 1.1737 0.6887 1 P 0 
L 1.1737 0.6887 1.1737 0.7086 1 P 0 
L 1.3087 0.753 1.3087 0.708 1 P 0 
L 1.26 0.67 1.2707 0.67 1 P 0 
L 1.2707 0.67 1.3087 0.708 1 P 0 
L 0.695 1.3 0.705 1.31 1 P 0 
L 0.705 1.31 0.705 1.42243996 1 P 0 
P 0.705 1.42243996 86 P 0 8 0;0,2=37,4=0
P 0.695 1.3 11 P 0 8 0;2=7,4=1
L 1.1737 0.7086 1.14733996 0.7086 1 P 0 
L 1.14733996 0.7086 1.14273996 0.704 1 P 0 
L 1.14273996 0.704 1.037 0.704 1 P 0 
L 1.037 0.704 1.0126 0.7284 1 P 0 
L 1.0126 0.7284 0.9575 0.7284 1 P 0 
P 0.9575 0.7284 83 P 0 8 0;0,2=6,4=0
P 1.3087 0.708 63 P 0 8 0;0,2=2,4=0
P 1.3087 0.753 63 P 0 8 0;0,2=2,4=0
P 1.1737 0.7086 63 P 0 8 0;0,2=2,4=0
P 1.26 0.67 9 P 0 8 0;2=24,4=1
P 0.76321004 0.783 11 P 0 8 0;2=7,4=1
P 0.76221004 0.7085 46 P 0 8 0;0,2=31,4=0
P 3.32 3.015 11 P 0 8 0;2=8,4=0
P 3.24 3.01 11 P 0 8 0;2=8,4=0
L 0.606 1.57 0.66356004 1.62756004 1 P 0 
L 0.66356004 1.62756004 0.705 1.62756004 1 P 0 
P 0.606 1.57 11 P 0 8 0;2=1,4=1
P 0.705 1.62756004 86 P 0 8 0;0,2=37,4=0
L 0.835 1.73 0.835 1.7 1 P 0 
L 0.835 1.7 0.805 1.67 1 P 0 
L 0.805 1.67 0.805 1.62756004 1 P 0 
P 0.835 1.73 11 P 0 8 0;2=1,4=1
P 0.805 1.62756004 86 P 0 8 0;0,2=37,4=0
S P 0
OB 2.805669980315 2.559430019685 I
OC 2.805669980315 2.559430019685 2.685669980315 2.559430019685 Y
OE
OB 2.748169980315 2.559430019685 H
OC 2.748169980315 2.559430019685 2.685669980315 2.559430019685 N
OE
SE
S P 0
OB 1.580669980315 2.680430019685 I
OC 1.580669980315 2.680430019685 1.460669980315 2.680430019685 Y
OE
OB 1.523169980315 2.680430019685 H
OC 1.523169980315 2.680430019685 1.460669980315 2.680430019685 N
OE
SE
S P 0
OB 1.555669980315 1.060430019685 I
OC 1.555669980315 1.060430019685 1.435669980315 1.060430019685 Y
OE
OB 1.498169980315 1.060430019685 H
OC 1.498169980315 1.060430019685 1.435669980315 1.060430019685 N
OE
SE
L 0.355 3.27 0.38 3.245 1 P 0 
L 0.38 3.245 0.38 3.231 1 P 0 
L 0.06873996 3.30413996 0.32086004 3.30413996 1 P 0 
L 0.32086004 3.30413996 0.355 3.27 1 P 0 
P 0.355 3.27 11 P 0 8 0;2=1,4=1
L 0.43 3.231 0.38 3.231 1 P 0 
P 0.06873996 3.30413996 68 P 0 8 0;0,2=40,4=0
P 0.38 3.231 58 P 0 8 0;0,2=2,4=0
P 0.43 3.231 58 P 0 8 0;0,2=2,4=0
L 0.28 3.27 0.15 3.27 1 P 0 
L 0.15 3.27 0.1487 3.2687 1 P 0 
L 0.1487 3.2687 0.08251998 3.2687 1 P 0 
L 0.28 3.231 0.28 3.27 1 P 0 
P 0.28 3.27 11 P 0 8 0;2=1,4=1
L 0.33 3.231 0.28 3.231 1 P 0 
P 0.08251998 3.2687 51 P 0 8 0;0,2=41,4=0
P 0.28 3.231 58 P 0 8 0;0,2=2,4=0
P 0.33 3.231 58 P 0 8 0;0,2=2,4=0
L 0.13 3.187 0.151 3.208 1 P 0 
L 0.151 3.208 0.151 3.2263 1 P 0 
L 0.151 3.2263 0.1557 3.231 1 P 0 
L 0.1557 3.231 0.18 3.231 1 P 0 
L 0.06873996 3.1998 0.0972 3.1998 1 P 0 
L 0.0972 3.1998 0.11 3.187 1 P 0 
L 0.11 3.187 0.13 3.187 1 P 0 
P 0.13 3.187 11 P 0 8 0;2=1,4=1
L 0.18 3.231 0.23 3.231 1 P 0 
P 0.23 3.231 58 P 0 8 0;0,2=2,4=0
P 0.18 3.231 58 P 0 8 0;0,2=2,4=0
P 0.06873996 3.1998 68 P 0 8 0;0,2=40,4=0
L 0.74546998 1.975 0.70046998 1.975 1 P 0 
L 0.70046998 1.975 0.69023002 1.98523996 1 P 0 
P 0.69023002 1.98523996 11 P 0 8 0;2=7,4=1
P 0.74546998 1.975 63 P 0 8 0;0,2=2,4=0
L 0.74546998 1.975 0.74546998 1.93 1 P 0 
P 0.74546998 1.93 63 P 0 8 0;0,2=2,4=0
L 0.125 2.195 0.09241004 2.16241004 1 P 0 
L 0.09241004 2.16241004 0.06873996 2.16241004 1 P 0 
P 0.125 2.195 11 P 0 8 0;2=1,4=1
P 0.06873996 2.16241004 68 P 0 8 0;0,2=40,4=0
L 0.69 1.93 0.69 1.925 1 P 0 
L 0.69 1.925 0.73 1.885 1 P 0 
L 0.73 1.885 0.74546998 1.885 1 P 0 
P 0.69 1.93 11 P 0 8 0;2=7,4=1
P 0.74546998 1.885 63 P 0 8 0;0,2=2,4=0
L 0.74546998 1.885 0.74546998 1.84 1 P 0 
P 0.74546998 1.84 63 P 0 8 0;0,2=2,4=0
L 0.125 2.145 0.12 2.145 1 P 0 
L 0.12 2.145 0.10196998 2.12696998 1 P 0 
L 0.10196998 2.12696998 0.08251998 2.12696998 1 P 0 
P 0.125 2.145 11 P 0 8 0;2=1,4=1
P 0.08251998 2.12696998 51 P 0 8 0;0,2=41,4=0
L 0.74546998 1.795 0.735 1.795 1 P 0 
L 0.735 1.795 0.69 1.84 1 P 0 
L 0.69 1.84 0.69 1.875 1 P 0 
P 0.69 1.875 11 P 0 8 0;2=7,4=1
P 0.74546998 1.795 63 P 0 8 0;0,2=2,4=0
L 0.74546998 1.795 0.74546998 1.75 1 P 0 
P 0.74546998 1.75 63 P 0 8 0;0,2=2,4=0
L 0.125 2.045 0.11193002 2.05806998 1 P 0 
L 0.11193002 2.05806998 0.06873996 2.05806998 1 P 0 
P 0.125 2.045 11 P 0 8 0;2=1,4=1
P 0.06873996 2.05806998 68 P 0 8 0;0,2=40,4=0
L 0.13 2.73326998 0.16673002 2.77 1 P 0 
L 0.16673002 2.77 0.31308002 2.77 1 P 0 
L 0.31308002 2.77 0.377 2.70608002 1 P 0 
L 0.06873996 2.73326998 0.13 2.73326998 1 P 0 
P 0.13 2.73326998 11 P 0 8 0;2=1,4=1
P 0.377 2.70608002 58 P 0 8 0;0,2=2,4=0
L 0.377 2.70608002 0.422 2.70608002 1 P 0 
P 0.422 2.70608002 58 P 0 8 0;0,2=2,4=0
P 0.06873996 2.73326998 68 P 0 8 0;0,2=40,4=0
L 0.287 2.743 0.28 2.75 1 P 0 
L 0.28 2.75 0.184 2.75 1 P 0 
L 0.184 2.75 0.13183002 2.69783002 1 P 0 
L 0.13183002 2.69783002 0.08251998 2.69783002 1 P 0 
P 0.287 2.743 11 P 0 8 0;2=1,4=1
L 0.287 2.70608002 0.287 2.743 1 P 0 
P 0.287 2.70608002 58 P 0 8 0;0,2=2,4=0
L 0.287 2.70608002 0.332 2.70608002 1 P 0 
P 0.332 2.70608002 58 P 0 8 0;0,2=2,4=0
P 0.08251998 2.69783002 51 P 0 8 0;0,2=41,4=0
L 0.125 2.615 0.11 2.615 1 P 0 
L 0.11 2.615 0.09606998 2.62893002 1 P 0 
L 0.09606998 2.62893002 0.06873996 2.62893002 1 P 0 
L 0.197 2.70608002 0.17608002 2.70608002 1 P 0 
L 0.17608002 2.70608002 0.157 2.687 1 P 0 
L 0.157 2.687 0.157 2.637 1 P 0 
L 0.157 2.637 0.135 2.615 1 P 0 
L 0.135 2.615 0.125 2.615 1 P 0 
P 0.125 2.615 11 P 0 8 0;2=1,4=1
P 0.197 2.70608002 58 P 0 8 0;0,2=2,4=0
L 0.197 2.70608002 0.242 2.70608002 1 P 0 
P 0.242 2.70608002 58 P 0 8 0;0,2=2,4=0
P 0.06873996 2.62893002 68 P 0 8 0;0,2=40,4=0
L 0.735 1.19 0.735 1.206 1 P 0 
L 0.735 1.206 0.779 1.25 1 P 0 
P 0.735 1.19 11 P 0 8 0;2=7,4=1
P 0.779 1.25 63 P 0 8 0;0,2=2,4=0
L 0.779 1.25 0.779 1.3 1 P 0 
P 0.779 1.3 63 P 0 8 0;0,2=2,4=0
L 0.125 1.06 0.10806998 1.06 1 P 0 
L 0.10806998 1.06 0.06873996 1.02066998 1 P 0 
P 0.125 1.06 11 P 0 8 0;2=1,4=1
P 0.06873996 1.02066998 68 P 0 8 0;0,2=40,4=0
L 0.68 1.19 0.685 1.19 1 P 0 
L 0.685 1.19 0.725 1.15 1 P 0 
L 0.725 1.15 0.779 1.15 1 P 0 
P 0.68 1.19 11 P 0 8 0;2=7,4=1
P 0.779 1.2 63 P 0 8 0;0,2=2,4=0
L 0.779 1.2 0.779 1.15 1 P 0 
P 0.779 1.15 63 P 0 8 0;0,2=2,4=0
L 0.125 1.01 0.125 1.00826004 1 P 0 
L 0.125 1.00826004 0.10196998 0.98523002 1 P 0 
L 0.10196998 0.98523002 0.08251998 0.98523002 1 P 0 
P 0.125 1.01 11 P 0 8 0;2=1,4=1
P 0.08251998 0.98523002 51 P 0 8 0;0,2=41,4=0
L 0.675 1.145 0.72 1.1 1 P 0 
L 0.72 1.1 0.779 1.1 1 P 0 
P 0.675 1.145 11 P 0 8 0;2=7,4=1
P 0.779 1.1 63 P 0 8 0;0,2=2,4=0
L 0.779 1.1 0.779 1.05 1 P 0 
P 0.779 1.05 63 P 0 8 0;0,2=2,4=0
L 0.125 0.91 0.12 0.91 1 P 0 
L 0.12 0.91 0.11366998 0.91633002 1 P 0 
L 0.11366998 0.91633002 0.06873996 0.91633002 1 P 0 
P 0.125 0.91 11 P 0 8 0;2=1,4=1
P 0.06873996 0.91633002 68 P 0 8 0;0,2=40,4=0
L 0.125 1.62 0.09653996 1.59153996 1 P 0 
L 0.09653996 1.59153996 0.06873996 1.59153996 1 P 0 
L 0.371 1.56898002 0.31998002 1.62 1 P 0 
L 0.31998002 1.62 0.125 1.62 1 P 0 
P 0.125 1.62 11 P 0 8 0;2=1,4=1
P 0.371 1.56898002 58 P 0 8 0;0,2=2,4=0
L 0.371 1.56898002 0.416 1.56898002 1 P 0 
P 0.416 1.56898002 58 P 0 8 0;0,2=2,4=0
P 0.06873996 1.59153996 68 P 0 8 0;0,2=40,4=0
L 0.13 1.57 0.165 1.605 1 P 0 
L 0.165 1.605 0.24498002 1.605 1 P 0 
L 0.24498002 1.605 0.281 1.56898002 1 P 0 
P 0.13 1.57 11 P 0 8 0;2=1,4=1
L 0.08251998 1.5561 0.1161 1.5561 1 P 0 
L 0.1161 1.5561 0.13 1.57 1 P 0 
P 0.08251998 1.5561 51 P 0 8 0;0,2=41,4=0
P 0.281 1.56898002 58 P 0 8 0;0,2=2,4=0
L 0.281 1.56898002 0.326 1.56898002 1 P 0 
P 0.326 1.56898002 58 P 0 8 0;0,2=2,4=0
L 0.1362 1.4872 0.13903002 1.49003002 1 P 0 
L 0.13903002 1.49003002 0.13903002 1.54136998 1 P 0 
L 0.13903002 1.54136998 0.16663996 1.56898002 1 P 0 
L 0.16663996 1.56898002 0.191 1.56898002 1 P 0 
L 0.06873996 1.4872 0.1362 1.4872 1 P 0 
P 0.1362 1.4872 11 P 0 8 0;2=1,4=1
P 0.06873996 1.4872 68 P 0 8 0;0,2=40,4=0
P 0.191 1.56898002 58 P 0 8 0;0,2=2,4=0
L 0.191 1.56898002 0.236 1.56898002 1 P 0 
P 0.236 1.56898002 58 P 0 8 0;0,2=2,4=0
L 2.937 3.206 2.937 3.173 7 P 0 
L 2.937 3.206 3.02306998 3.206 7 P 0 
L 3.02306998 3.206 3.0425 3.22543002 7 P 0 
P 2.937 3.173 11 P 0 8 0;2=1,4=1
P 3.0425 3.22543002 94 P 0 8 0;0,2=10,4=0
P 2.937 3.206 63 P 0 8 0;0,2=2,4=0
P 3.01 3.17 11 P 0 8 0;2=7,4=1
P 0.896 2.489 9 P 0 8 0;2=9,4=1
L 0.896 2.489 0.8594 2.4524 1 P 0 
L 0.8594 2.4524 0.8594 2.4275 1 P 0 
P 0.8594 2.4275 50 P 0 8 0;0,2=42,4=0
P 4.2391 4.01168996 85 P 0 8 0;0,2=0,4=0
P 4.31168996 4.01168996 9 P 0 8 0;2=9,4=1
L 4.31168996 4.01168996 4.2391 4.01168996 1 P 0 
L 4.354 4.015 4.315 4.015 1 P 0 
L 4.315 4.015 4.31168996 4.01168996 1 P 0 
P 4.354 4.015 63 P 0 8 0;0,2=2,4=0
P 4.2391 3.95263002 85 P 0 8 0;0,2=0,4=0
P 4.319 3.922 9 P 0 8 0;2=9,4=1
L 4.319 3.922 4.326 3.915 1 P 0 
L 4.326 3.915 4.354 3.915 1 P 0 
L 4.2391 3.95263002 4.28836998 3.95263002 1 P 0 
L 4.28836998 3.95263002 4.319 3.922 1 P 0 
P 4.354 3.915 63 P 0 8 0;0,2=2,4=0
L 4.5 4.115 4.475 4.115 1 P 0 
L 4.475 4.115 4.45 4.09 1 P 0 
L 4.45 4.09 4.425 4.09 1 P 0 
L 4.425 4.09 4.4 4.065 1 P 0 
L 4.4 4.065 4.396 4.065 1 P 0 
P 4.5 4.115 11 P 0 8 0;2=1,4=1
P 4.396 4.065 63 P 0 8 0;0,2=2,4=0
L 1.42 0.69535 1.38265 0.658 1 P 0 
L 1.38265 0.658 1.3505 0.658 1 P 0 
P 1.315 2.905 9 P 0 8 0;2=26,4=1
L 2.932 3.295 2.921 3.295 1 P 0 
L 2.921 3.295 2.895 3.269 1 P 0 
L 2.895 3.269 2.895 3.259 1 P 0 
P 2.932 3.295 9 P 0 8 0;2=26,4=1
P 2.895 3.259 63 P 0 8 0;0,2=2,4=0
P 0.915 1.4 11 P 0 8 0;2=7,4=1
P 1.42 0.69535 9 P 0 8 0;2=24,4=1
P 1.3505 0.658 63 P 0 8 0;0,2=2,4=0
L 4.5 4.165 4.475 4.14 1 P 0 
L 4.475 4.14 4.421 4.14 1 P 0 
L 4.421 4.14 4.396 4.115 1 P 0 
P 4.5 4.165 11 P 0 8 0;2=1,4=1
P 4.396 4.115 63 P 0 8 0;0,2=2,4=0
L 1.4207 0.779 1.3767 0.779 1 P 0 
L 1.3767 0.779 1.3507 0.753 1 P 0 
P 1.36 2.905 9 P 0 8 0;2=26,4=1
L 2.896 3.301 2.896 3.332 1 P 0 
P 2.896 3.301 9 P 0 8 0;2=26,4=1
P 2.896 3.332 63 P 0 8 0;0,2=2,4=0
P 0.965 1.4 11 P 0 8 0;2=7,4=1
P 1.3507 0.753 63 P 0 8 0;0,2=2,4=0
P 1.4207 0.779 9 P 0 8 0;2=24,4=1
P 4.63965 2.00091004 10 P 0 8 0;0,2=5,4=0
L 4.63965 2.00091004 4.65933002 2.02058996 1 P 0 
P 4.65933002 2.02058996 9 P 0 8 0;2=15,4=1
P 4.33 3.535 11 P 0 8 0;2=7,4=1
P 4.44 4.065 9 P 0 8 0;2=9,4=1
P 4.61996004 2.05996004 9 P 0 8 0;2=4,4=1
P 4.395 3.415 9 P 0 8 0;2=26,4=1
L 4.60028002 2.04028002 4.61996004 2.05996004 1 P 0 
P 4.60028002 2.04028002 10 P 0 8 0;0,2=5,4=0
P 4.44 4.115 9 P 0 8 0;2=9,4=1
P 4.61996004 2.09933002 9 P 0 8 0;2=4,4=1
P 4.425 3.36088996 9 P 0 8 0;2=26,4=1
L 4.60028002 2.07965 4.61996004 2.09933002 1 P 0 
P 4.60028002 2.07965 10 P 0 8 0;0,2=5,4=0
L 0.64248002 2.709 0.64248002 2.73551998 1 P 0 
L 0.64248002 2.73551998 0.638 2.74 1 P 0 
P 0.638 2.74 9 P 0 8 0;2=26,4=1
L 0.825 2.305 0.8338 2.2962 1 P 0 
L 0.8338 2.2962 0.8338 2.2465 1 P 0 
P 0.8338 2.2465 50 P 0 8 0;0,2=42,4=0
P 0.825 2.305 9 P 0 8 0;2=9,4=1
P 0.64248002 2.664 63 P 0 8 0;0,2=2,4=0
L 0.64248002 2.664 0.64248002 2.709 1 P 0 
P 0.64248002 2.709 63 P 0 8 0;0,2=2,4=0
L 0.756 2.79 0.756 2.824 1 P 0 
L 0.756 2.824 0.755 2.825 1 P 0 
L 0.80648002 2.831 0.761 2.831 1 P 0 
L 0.761 2.831 0.755 2.825 1 P 0 
P 0.80648002 2.831 58 P 0 8 0;0,2=2,4=0
P 0.756 2.79 63 P 0 8 0;0,2=2,4=0
P 0.755 2.825 9 P 0 8 0;2=26,4=1
P 0.795 2.345 9 P 0 8 0;2=9,4=1
L 0.795 2.345 0.795 2.295 1 P 0 
L 0.795 2.295 0.8082 2.2818 1 P 0 
L 0.8082 2.2818 0.8082 2.2465 1 P 0 
P 0.8082 2.2465 50 P 0 8 0;0,2=42,4=0
L 6.02558996 4.13778996 5.97613002 4.13778996 1 P 0 
P 5.97613002 4.13778996 11 P 0 8 0;2=1,4=1
P 6.02558996 4.13778996 24 P 0 8 0;0,2=36,4=0
L 5.90748002 4.13778996 5.90748002 4.18725 1 P 0 
P 5.90748002 4.18725 11 P 0 8 0;2=1,4=1
P 5.90748002 4.13778996 24 P 0 8 0;0,2=36,4=0
L 0.905 1.935 0.85735 1.88735 1 P 0 
L 0.85735 1.88735 0.85735 1.86705 1 P 0 
L 0.85735 1.86705 0.8303 1.84 1 P 0 
L 0.8303 1.84 0.78746998 1.84 1 P 0 
P 0.78746998 1.84 63 P 0 8 0;0,2=2,4=0
P 4.06878996 2.02058996 9 P 0 8 0;2=4,4=1
P 0.905 1.935 11 P 0 8 0;2=1,4=1
P 4.08846998 2.00091004 10 P 0 8 0;0,2=5,4=0
L 4.08846998 2.00091004 4.06878996 2.02058996 1 P 0 
L 0.945 1.97 0.94 1.975 1 P 0 
L 0.94 1.975 0.78746998 1.975 1 P 0 
P 3.99005 2.05996004 9 P 0 8 0;2=4,4=1
P 0.945 1.97 11 P 0 8 0;2=1,4=1
P 4.00973002 2.04028002 10 P 0 8 0;0,2=5,4=0
L 4.00973002 2.04028002 3.99005 2.05996004 1 P 0 
P 0.78746998 1.975 63 P 0 8 0;0,2=2,4=0
L 0.905 1.885 0.815 1.795 1 P 0 
L 0.815 1.795 0.78746998 1.795 1 P 0 
P 4.02941998 2.05996004 9 P 0 8 0;2=4,4=1
P 0.905 1.885 11 P 0 8 0;2=1,4=1
P 4.0491 2.04028002 10 P 0 8 0;0,2=5,4=0
L 4.0491 2.04028002 4.02941998 2.05996004 1 P 0 
P 0.78746998 1.795 63 P 0 8 0;0,2=2,4=0
P 0.63 2.15 11 P 0 8 0;2=7,4=1
P 3.95066998 2.02058996 9 P 0 8 0;2=4,4=1
P 0.985 2.185 11 P 0 8 0;2=1,4=1
L 3.97035 2.00091004 3.95066998 2.02058996 1 P 0 
P 3.97035 2.00091004 10 P 0 8 0;0,2=5,4=0
L 0.287 2.66408002 0.287 2.62508002 1 P 0 
P 0.287 2.62508002 11 P 0 8 0;2=7,4=1
P 0.287 2.66408002 58 P 0 8 0;0,2=2,4=0
L 0.43 2.555 0.43 2.64 1 P 0 
L 0.43 2.64 0.422 2.648 1 P 0 
L 0.422 2.648 0.422 2.66408002 1 P 0 
P 0.43 2.555 11 P 0 8 0;2=1,4=1
P 0.422 2.66408002 58 P 0 8 0;0,2=2,4=0
P 3.95066998 1.98121998 9 P 0 8 0;2=4,4=1
L 3.95066998 1.98121998 3.95793996 1.97393996 1 P 0 
L 3.95793996 1.97393996 3.97035 1.96153996 1 P 0 
P 0.63 2.105 11 P 0 8 0;2=7,4=1
P 0.99 2.015 11 P 0 8 0;2=7,4=1
P 3.97035 1.96153996 10 P 0 8 0;0,2=5,4=0
L 0.242 2.66408002 0.242 2.62508002 1 P 0 
P 0.242 2.62508002 11 P 0 8 0;2=1,4=1
P 0.242 2.66408002 58 P 0 8 0;0,2=2,4=0
P 3.99005 1.98121998 9 P 0 8 0;2=4,4=1
P 0.63 2.06 11 P 0 8 0;2=7,4=1
P 0.99 1.975 11 P 0 8 0;2=7,4=1
P 4.00973002 1.96153996 10 P 0 8 0;0,2=5,4=0
L 4.00973002 1.96153996 3.99005 1.98121998 1 P 0 
P 4.02941998 1.82373996 9 P 0 8 0;2=4,4=1
L 4.02941998 1.82373996 4.0491 1.80406004 1 P 0 
L 0.935 1.3 0.91 1.275 1 P 0 
L 0.91 1.275 0.91 1.205 1 P 0 
L 0.91 1.205 0.855 1.15 1 P 0 
L 0.855 1.15 0.821 1.15 1 P 0 
P 0.935 1.3 11 P 0 8 0;2=1,4=1
P 0.821 1.15 63 P 0 8 0;0,2=2,4=0
P 4.0491 1.80406004 10 P 0 8 0;0,2=5,4=0
P 3.95066998 1.90248002 9 P 0 8 0;2=4,4=1
L 3.97035 1.8828 3.95066998 1.90248002 1 P 0 
L 0.821 1.25 0.865 1.25 1 P 0 
L 0.865 1.25 0.87 1.255 1 P 0 
P 0.87 1.255 11 P 0 8 0;2=1,4=1
P 0.821 1.25 63 P 0 8 0;0,2=2,4=0
P 3.97035 1.8828 10 P 0 8 0;0,2=5,4=0
P 3.95066998 1.86311004 9 P 0 8 0;2=4,4=1
L 3.97035 1.84343002 3.95066998 1.86311004 1 P 0 
L 0.935 1.25 0.935 1.195 1 P 0 
L 0.935 1.195 0.84 1.1 1 P 0 
L 0.84 1.1 0.821 1.1 1 P 0 
P 0.935 1.25 11 P 0 8 0;2=1,4=1
P 0.821 1.1 63 P 0 8 0;0,2=2,4=0
P 3.97035 1.84343002 10 P 0 8 0;0,2=5,4=0
P 4.06878996 1.94185 9 P 0 8 0;2=4,4=1
P 0.92 1.73 11 P 0 8 0;2=1,4=1
P 4.08846998 1.92216998 10 P 0 8 0;0,2=5,4=0
L 4.08846998 1.92216998 4.06878996 1.94185 1 P 0 
L 0.281 1.52698002 0.281 1.48798002 1 P 0 
P 0.281 1.48798002 11 P 0 8 0;2=7,4=1
P 0.281 1.52698002 58 P 0 8 0;0,2=2,4=0
P 4.06878996 1.86311004 9 P 0 8 0;2=4,4=1
L 4.08846998 1.84343002 4.06878996 1.86311004 1 P 0 
P 0.985 1.655 11 P 0 8 0;2=1,4=1
P 4.08846998 1.84343002 10 P 0 8 0;0,2=5,4=0
P 0.371 1.52698002 58 P 0 8 0;0,2=2,4=0
P 0.371 1.48798002 11 P 0 8 0;2=7,4=1
L 0.371 1.52698002 0.371 1.48798002 1 P 0 
P 4.06878996 1.82373996 9 P 0 8 0;2=4,4=1
L 4.06878996 1.82373996 4.08846998 1.80406004 1 P 0 
P 4.08846998 1.80406004 10 P 0 8 0;0,2=5,4=0
P 0.985 1.59 11 P 0 8 0;2=1,4=1
P 0.236 1.52698002 58 P 0 8 0;0,2=2,4=0
P 0.236 1.48798002 11 P 0 8 0;2=7,4=1
L 0.236 1.52698002 0.236 1.48798002 1 P 0 
L 0.28 3.189 0.28 3.155 1 P 0 
L 0.28 3.155 0.345 3.09 1 P 0 
P 0.28 3.189 58 P 0 8 0;0,2=2,4=0
P 0.345 3.09 11 P 0 8 0;2=7,4=1
P 3.84091004 2.00091004 11 P 0 8 0;2=1,4=1
L 3.89161004 2.00091004 3.84091004 2.00091004 1 P 0 
P 3.89161004 2.00091004 10 P 0 8 0;0,2=5,4=0
P 0.99 1.885 11 P 0 8 0;2=7,4=1
L 0.395 3.09 0.395 3.11498996 1 P 0 
L 0.395 3.11498996 0.38 3.12998996 1 P 0 
L 0.38 3.12998996 0.38 3.189 1 P 0 
P 0.38 3.189 58 P 0 8 0;0,2=2,4=0
P 0.395 3.09 11 P 0 8 0;2=7,4=1
L 3.89161004 2.07965 3.87193002 2.09933002 1 P 0 
P 3.87193002 2.09933002 9 P 0 8 0;2=15,4=1
P 3.89161004 2.07965 10 P 0 8 0;0,2=5,4=0
P 0.99 2.065 11 P 0 8 0;2=7,4=1
L 0.445 3.09 0.42265 3.06765 1 P 0 
L 0.42265 3.06765 0.32235 3.06765 1 P 0 
L 0.32235 3.06765 0.23 3.16 1 P 0 
L 0.23 3.16 0.23 3.189 1 P 0 
P 0.23 3.189 58 P 0 8 0;0,2=2,4=0
P 0.445 3.09 11 P 0 8 0;2=1,4=1
P 3.9113 2.09933002 9 P 0 8 0;2=4,4=1
P 0.975 2.14 11 P 0 8 0;2=7,4=1
L 3.93098002 2.07965 3.9113 2.09933002 1 P 0 
P 3.93098002 2.07965 10 P 0 8 0;0,2=5,4=0
L 0.55708002 1.92086998 0.55708002 1.97791998 1 P 0 
L 0.55708002 1.97791998 0.53 2.005 1 P 0 
L 0.53 2.005 0.53 2.049 1 P 0 
P 0.55708002 1.92086998 35 P 0 8 0;0,2=43,4=0
P 0.53 2.005 11 P 0 8 0;2=1,4=1
P 0.53 2.049 58 P 0 8 0;0,2=2,4=0
L 0.53 2.584 0.53 2.557 1 P 0 
L 0.53 2.557 0.552 2.535 1 P 0 
L 0.552 2.535 0.552 2.53038002 1 P 0 
L 0.552 2.53038002 0.55708002 2.5253 1 P 0 
L 0.55708002 2.5253 0.55708002 2.49173996 1 P 0 
P 0.552 2.535 11 P 0 8 0;2=1,4=1
P 0.55708002 2.49173996 35 P 0 8 0;0,2=43,4=0
P 0.53 2.584 58 P 0 8 0;0,2=2,4=0
L 0.455 1.825 0.355 1.925 1 P 0 
L 0.355 1.925 0.355 2.075 1 P 0 
L 0.355 2.075 0.3335 2.0965 1 P 0 
L 0.3335 2.0965 0.2725 2.0965 1 P 0 
L 0.455 1.781 0.455 1.825 1 P 0 
P 0.455 1.825 11 P 0 8 0;2=1,4=1
P 0.455 1.781 58 P 0 8 0;0,2=2,4=0
L 0.16038996 1.85433002 0.16038996 1.97538996 1 P 0 
L 0.16038996 1.97538996 0.2725 2.0875 1 P 0 
L 0.2725 2.0875 0.2725 2.0965 1 P 0 
P 0.16038996 1.85433002 15 P 0 8 0;2=44,4=0
P 0.2725 2.0965 74 P 0 8 0;0,2=45,4=0
L 0.2725 2.1835 0.4485 2.1835 1 P 0 
L 0.4485 2.1835 0.46 2.195 1 P 0 
L 0.46 2.195 0.46451998 2.19951998 1 P 0 
L 0.46451998 2.19951998 0.46451998 2.233 1 P 0 
P 0.46 2.195 11 P 0 8 0;2=1,4=1
P 0.46451998 2.233 58 P 0 8 0;0,2=2,4=0
L 0.16038996 2.4252 0.16038996 2.30461004 1 P 0 
L 0.16038996 2.30461004 0.2725 2.1925 1 P 0 
L 0.2725 2.1925 0.2725 2.1835 1 P 0 
P 0.16038996 2.4252 15 P 0 8 0;2=44,4=0
P 0.2725 2.1835 74 P 0 8 0;0,2=45,4=0
L 0.445 0.735 0.4 0.78 1 P 0 
L 0.4 0.78 0.4 0.86 1 P 0 
L 0.4 0.86 0.3035 0.9565 1 P 0 
L 0.3035 0.9565 0.2725 0.9565 1 P 0 
P 0.445 0.735 11 P 0 8 0;2=1,4=1
L 0.16038996 0.7126 0.16038996 0.82038996 1 P 0 
L 0.16038996 0.82038996 0.2725 0.9325 1 P 0 
L 0.2725 0.9325 0.2725 0.9565 1 P 0 
P 0.16038996 0.7126 15 P 0 8 0;2=44,4=0
P 0.2725 0.9565 74 P 0 8 0;0,2=45,4=0
L 0.455 1.0439 0.4546 1.0435 1 P 0 
L 0.4546 1.0435 0.2725 1.0435 1 P 0 
P 0.455 1.0839 58 P 0 8 0;0,2=2,4=0
P 0.455 1.0439 11 P 0 8 0;2=1,4=1
L 0.455 1.0839 0.455 1.0439 1 P 0 
L 0.16038996 1.28346004 0.16038996 1.16961004 1 P 0 
L 0.16038996 1.16961004 0.2725 1.0575 1 P 0 
L 0.2725 1.0575 0.2725 1.0435 1 P 0 
P 0.16038996 1.28346004 15 P 0 8 0;2=44,4=0
P 0.2725 1.0435 74 P 0 8 0;0,2=45,4=0
L 0.535 1.835 0.5374 1.8326 1 P 0 
L 0.5374 1.8326 0.5374 1.78778996 1 P 0 
L 0.535 1.835 0.525 1.835 1 P 0 
L 0.525 1.835 0.51771998 1.82771998 1 P 0 
L 0.51771998 1.82771998 0.51771998 1.78778996 1 P 0 
P 0.535 1.835 11 P 0 8 0;2=1,4=1
L 0.455 1.739 0.455 1.686 1 P 0 
L 0.51771998 1.78778996 0.51771998 1.75471998 1 P 0 
L 0.51771998 1.75471998 0.502 1.739 1 P 0 
L 0.502 1.739 0.455 1.739 1 P 0 
P 0.455 1.739 58 P 0 8 0;0,2=2,4=0
P 0.455 1.686 58 P 0 8 0;0,2=2,4=0
P 0.51771998 1.78778996 35 P 0 8 0;0,2=43,4=0
P 0.5374 1.78778996 35 P 0 8 0;0,2=43,4=0
L 0.532 2.40186998 0.522 2.40186998 1 P 0 
L 0.522 2.40186998 0.51771998 2.39758996 1 P 0 
L 0.51771998 2.39758996 0.51771998 2.35866004 1 P 0 
P 0.532 2.40186998 11 P 0 8 0;2=1,4=1
L 0.5374 2.35866004 0.5374 2.39646998 1 P 0 
L 0.5374 2.39646998 0.532 2.40186998 1 P 0 
L 0.452 2.326 0.452 2.28751998 1 P 0 
L 0.452 2.28751998 0.46451998 2.275 1 P 0 
P 0.46451998 2.275 58 P 0 8 0;0,2=2,4=0
L 0.51771998 2.35866004 0.51771998 2.33371998 1 P 0 
L 0.51771998 2.33371998 0.51 2.326 1 P 0 
L 0.51 2.326 0.452 2.326 1 P 0 
P 0.51771998 2.35866004 35 P 0 8 0;0,2=43,4=0
P 0.5374 2.35866004 35 P 0 8 0;0,2=43,4=0
P 0.452 2.326 58 P 0 8 0;0,2=2,4=0
L 0.505 0.60228002 0.51771998 0.615 1 P 0 
L 0.51771998 0.615 0.51771998 0.64606004 1 P 0 
L 0.443 0.647 0.443 0.631 1 P 0 
L 0.443 0.631 0.47171998 0.60228002 1 P 0 
L 0.47171998 0.60228002 0.505 0.60228002 1 P 0 
P 0.505 0.60228002 11 P 0 8 0;2=1,4=1
L 0.5374 0.64606004 0.5374 0.6826 1 P 0 
L 0.5374 0.6826 0.53395 0.68605 1 P 0 
L 0.53395 0.68605 0.52105 0.68605 1 P 0 
L 0.52105 0.68605 0.51771998 0.68271998 1 P 0 
L 0.51771998 0.68271998 0.51771998 0.64606004 1 P 0 
P 0.5374 0.64606004 35 P 0 8 0;0,2=43,4=0
P 0.51771998 0.64606004 35 P 0 8 0;0,2=43,4=0
P 0.443 0.647 58 P 0 8 0;0,2=2,4=0
L 0.5374 1.26 0.5374 1.21691998 1 P 0 
L 0.51771998 1.21691998 0.51771998 1.2553 1 P 0 
L 0.51771998 1.2553 0.52241998 1.26 1 P 0 
L 0.52241998 1.26 0.5374 1.26 1 P 0 
P 0.5374 1.26 11 P 0 8 0;2=1,4=1
L 0.455 1.178 0.455 1.1259 1 P 0 
L 0.455 1.178 0.511 1.178 1 P 0 
L 0.511 1.178 0.51771998 1.18471998 1 P 0 
L 0.51771998 1.18471998 0.51771998 1.21691998 1 P 0 
P 0.5374 1.21691998 35 P 0 8 0;0,2=43,4=0
P 0.51771998 1.21691998 35 P 0 8 0;0,2=43,4=0
P 0.455 1.178 58 P 0 8 0;0,2=2,4=0
P 0.455 1.1259 58 P 0 8 0;0,2=2,4=0
L 0.48 2.005 0.48 2.049 1 P 0 
L 0.5374 1.92086998 0.5374 1.9556 1 P 0 
L 0.5374 1.9556 0.488 2.005 1 P 0 
L 0.488 2.005 0.48 2.005 1 P 0 
P 0.48 2.005 11 P 0 8 0;2=1,4=1
P 0.5374 1.92086998 35 P 0 8 0;0,2=43,4=0
P 0.48 2.049 58 P 0 8 0;0,2=2,4=0
L 0.485 2.525 0.478 2.532 1 P 0 
L 0.478 2.532 0.478 2.569 1 P 0 
L 0.5374 2.49173996 0.5374 2.5153 1 P 0 
L 0.5374 2.5153 0.5327 2.52 1 P 0 
L 0.5327 2.52 0.49 2.52 1 P 0 
L 0.49 2.52 0.485 2.525 1 P 0 
P 0.485 2.525 11 P 0 8 0;2=1,4=1
P 0.5374 2.49173996 35 P 0 8 0;0,2=43,4=0
P 0.478 2.569 58 P 0 8 0;0,2=2,4=0
L 0.515 0.835 0.485 0.865 1 P 0 
L 0.485 0.865 0.485 0.884 1 P 0 
L 0.5374 0.77913996 0.5374 0.8126 1 P 0 
L 0.5374 0.8126 0.515 0.835 1 P 0 
P 0.515 0.835 11 P 0 8 0;2=1,4=1
P 0.485 0.884 58 P 0 8 0;0,2=2,4=0
P 0.5374 0.77913996 35 P 0 8 0;0,2=43,4=0
L 0.475 1.405 0.50938996 1.405 1 P 0 
L 0.50938996 1.405 0.5374 1.37698996 1 P 0 
L 0.5374 1.37698996 0.5374 1.35 1 P 0 
L 0.475 1.405 0.475 1.439 1 P 0 
L 0.475 1.439 0.48 1.444 1 P 0 
P 0.475 1.405 11 P 0 8 0;2=1,4=1
P 0.48 1.444 58 P 0 8 0;0,2=2,4=0
P 0.5374 1.35 35 P 0 8 0;0,2=43,4=0
L 6.2655 1.0066 6.2884 1.0066 1 P 0 
L 6.2884 1.0066 6.33 0.965 1 P 0 
L 6.33 0.965 6.335 0.965 1 P 0 
L 6.335 0.965 6.379 0.965 1 P 0 
P 6.2655 1.0066 93 P 0 8 0;0,2=42,4=0
P 6.335 0.965 11 P 0 8 0;2=1,4=1
P 6.379 0.965 63 P 0 8 0;0,2=2,4=0
L 6.2655 1.0322 6.3228 1.0322 1 P 0 
L 6.3228 1.0322 6.335 1.02 1 P 0 
L 6.335 1.02 6.379 1.02 1 P 0 
P 6.2655 1.0322 93 P 0 8 0;0,2=42,4=0
P 6.335 1.02 11 P 0 8 0;2=1,4=1
P 6.379 1.02 63 P 0 8 0;0,2=2,4=0
L 6.2655 1.0578 6.3128 1.0578 1 P 0 
L 6.3128 1.0578 6.335 1.08 1 P 0 
L 6.335 1.08 6.379 1.08 1 P 0 
P 6.379 1.08 63 P 0 8 0;0,2=2,4=0
P 6.2655 1.0578 93 P 0 8 0;0,2=42,4=0
P 6.335 1.08 11 P 0 8 0;2=1,4=1
P 2.0966 3.0845 50 P 0 8 0;0,2=42,4=0
L 2.085 3.017 2.083 3.015 1 P 0 
L 2.083 3.015 2.083 2.973 1 P 0 
L 2.0966 3.0845 2.0966 3.0286 1 P 0 
L 2.0966 3.0286 2.085 3.017 1 P 0 
P 2.085 3.017 9 P 0 8 0;2=24,4=1
P 2.083 2.973 58 P 0 8 0;0,2=2,4=0
P 2.1222 3.0845 50 P 0 8 0;0,2=42,4=0
L 2.135 3.017 2.128 3.01 1 P 0 
L 2.128 3.01 2.128 2.973 1 P 0 
L 2.1222 3.0845 2.1222 3.0428 1 P 0 
L 2.1222 3.0428 2.135 3.03 1 P 0 
L 2.135 3.03 2.135 3.017 1 P 0 
P 2.135 3.017 9 P 0 8 0;2=24,4=1
P 2.128 2.973 58 P 0 8 0;0,2=2,4=0
P 2.1478 3.0845 50 P 0 8 0;0,2=42,4=0
L 2.1478 3.0845 2.1478 3.0482 1 P 0 
L 2.1478 3.0482 2.163 3.033 1 P 0 
L 2.163 3.033 2.169 3.033 1 P 0 
L 2.169 3.033 2.185 3.017 1 P 0 
L 2.173 2.973 2.173 3.005 1 P 0 
L 2.173 3.005 2.185 3.017 1 P 0 
P 2.185 3.017 9 P 0 8 0;2=24,4=1
P 2.173 2.973 58 P 0 8 0;0,2=2,4=0
P 5.956 1.08 63 P 0 8 0;0,2=2,4=0
L 5.956 1.08 5.965 1.08 1 P 0 
L 5.965 1.08 6.0085 1.1235 1 P 0 
L 6.0845 1.0834 6.0486 1.0834 1 P 0 
L 6.0486 1.0834 6.0085 1.1235 1 P 0 
P 6.0085 1.1235 11 P 0 8 0;2=1,4=1
P 6.0845 1.0834 93 P 0 8 0;0,2=42,4=0
P 2.1734 3.2655 50 P 0 8 0;0,2=42,4=0
L 2.1734 3.2655 2.1734 3.3034 1 P 0 
L 2.1734 3.3034 2.18 3.31 1 P 0 
L 2.18 3.31 2.21 3.31 1 P 0 
L 2.21 3.31 2.22 3.3 1 P 0 
L 2.22 3.3 2.241 3.3 1 P 0 
L 2.241 3.3 2.254 3.287 1 P 0 
L 2.254 3.287 2.2628 3.287 1 P 0 
P 2.2628 3.287 58 P 0 8 0;0,2=2,4=0
P 2.22 3.3 9 P 0 8 0;2=24,4=1
L 5.8 1.048 5.8 1.01 1 P 0 
L 5.8 1.01 5.88 0.93 1 P 0 
L 5.88 0.93 5.95 0.93 1 P 0 
L 5.95 0.93 5.956 0.936 1 P 0 
L 5.956 0.936 5.956 0.965 1 P 0 
L 6.0845 1.0322 6.0232 1.0322 1 P 0 
L 6.0232 1.0322 5.956 0.965 1 P 0 
P 5.956 0.965 63 P 0 8 0;0,2=2,4=0
P 5.8 1.048 11 P 0 8 0;2=8,4=0
P 6.0845 1.0322 93 P 0 8 0;0,2=42,4=0
P 4.34436998 2.02058996 9 P 0 8 0;2=4,4=1
P 4.32468996 2.00091004 10 P 0 8 0;0,2=5,4=0
L 4.32468996 2.00091004 4.34436998 2.02058996 1 P 0 
P 5.285 2.99 9 P 0 8 0;2=26,4=1
P 4.32468996 2.15838996 10 P 0 8 0;0,2=5,4=0
L 4.32468996 2.15838996 4.34436998 2.17806998 1 P 0 
P 3.125 3.075 11 P 0 8 0;2=7,4=1
P 4.34436998 2.17806998 9 P 0 8 0;2=4,4=1
P 1.959 3.247 58 P 0 8 0;0,2=2,4=0
L 1.959 3.247 1.985 3.247 1 P 0 
L 1.985 3.247 2.017 3.279 1 P 0 
L 2.017 3.279 2.017 3.302 1 P 0 
L 2.017 3.302 2.065 3.35 1 P 0 
L 2.065 3.35 2.105 3.35 1 P 0 
L 2.105 3.35 2.1222 3.3328 1 P 0 
L 2.1222 3.3328 2.1222 3.2655 1 P 0 
P 2.1222 3.2655 50 P 0 8 0;0,2=42,4=0
P 2.017 3.279 11 P 0 8 0;2=8,4=0
P 0.636 2.915 11 P 0 8 0;2=8,4=0
P 4.38373996 2.17806998 9 P 0 8 0;2=4,4=1
P 2.97 3.105 11 P 0 8 0;2=1,4=1
L 4.36406004 2.15838996 4.38373996 2.17806998 1 P 0 
P 4.36406004 2.15838996 10 P 0 8 0;0,2=5,4=0
L 5.91 2.785 5.91 2.795 1 P 0 
L 5.91 2.795 5.93 2.815 1 P 0 
L 5.93 2.815 6.01843996 2.815 1 P 0 
P 6.01843996 2.815 43 P 0 8 0;0,2=37,4=0
P 5.91 2.785 11 P 0 8 0;2=1,4=1
P 6.01843996 2.615 43 P 0 8 0;0,2=37,4=0
L 6.01843996 2.615 5.91 2.615 1 P 0 
P 5.91 2.615 9 P 0 8 0;2=24,4=1
L 5.91 2.915 5.91 2.965 1 P 0 
L 5.91 2.965 5.87 3.005 1 P 0 
L 5.87 3.005 5.87 3.09 1 P 0 
L 5.87 3.09 5.83 3.13 1 P 0 
L 5.83 3.13 5.245 3.13 1 P 0 
L 5.245 3.13 5.15598002 3.21901998 1 P 0 
L 5.15598002 3.21901998 5.15598002 3.22566004 1 P 0 
L 5.15598002 3.22566004 5.18183996 3.25151998 1 P 0 
L 5.18183996 3.25151998 5.18183996 3.25816004 1 P 0 
L 5.18183996 3.25816004 5.17101004 3.26898996 1 P 0 
L 5.17101004 3.26898996 5.16436998 3.26898996 1 P 0 
L 5.16436998 3.26898996 5.13851004 3.24313002 1 P 0 
L 5.13851004 3.24313002 5.13186998 3.24313002 1 P 0 
L 5.13186998 3.24313002 5.12103996 3.25396004 1 P 0 
L 5.12103996 3.25396004 5.12103996 3.2606 1 P 0 
L 5.12103996 3.2606 5.1469 3.28646004 1 P 0 
L 5.1469 3.28646004 5.1469 3.2931 1 P 0 
L 5.1469 3.2931 5.13606998 3.30393002 1 P 0 
L 5.13606998 3.30393002 5.12943002 3.30393002 1 P 0 
L 5.12943002 3.30393002 5.10356998 3.27806998 1 P 0 
L 5.10356998 3.27806998 5.09693002 3.27806998 1 P 0 
L 5.09693002 3.27806998 5.0861 3.2889 1 P 0 
L 5.0861 3.2889 5.0861 3.29553996 1 P 0 
L 5.0861 3.29553996 5.11196004 3.3214 1 P 0 
L 5.11196004 3.3214 5.11196004 3.32803996 1 P 0 
L 5.11196004 3.32803996 5.10113002 3.33886998 1 P 0 
L 5.10113002 3.33886998 5.09448996 3.33886998 1 P 0 
L 5.09448996 3.33886998 5.06863002 3.31301004 1 P 0 
L 5.06863002 3.31301004 5.06198996 3.31301004 1 P 0 
L 5.06198996 3.31301004 5.05116004 3.32383996 1 P 0 
L 5.05116004 3.32383996 5.05116004 3.33048002 1 P 0 
L 5.05116004 3.33048002 5.07051998 3.34983996 1 P 0 
L 5.07051998 3.34983996 5.07051998 3.35648002 1 P 0 
L 5.07051998 3.35648002 5.05968996 3.36731004 1 P 0 
L 5.05968996 3.36731004 5.05305 3.36731004 1 P 0 
L 5.05305 3.36731004 5.03368996 3.34795 1 P 0 
L 5.03368996 3.34795 5.02705 3.34795 1 P 0 
L 5.02705 3.34795 5.01 3.365 1 P 0 
L 5.01 3.365 5.01 3.479 1 P 0 
L 5.01 3.479 4.985 3.504 1 P 0 
P 4.985 3.504 58 P 0 8 0;0,2=2,4=0
L 6.01843996 2.915 5.91 2.915 1 P 0 
P 5.91 2.915 11 P 0 8 0;2=1,4=1
P 6.01843996 2.915 43 P 0 8 0;0,2=37,4=0
L 4.885 3.504 4.91 3.479 1 P 0 
L 4.91 3.479 4.91 3.43 1 P 0 
L 4.91 3.43 5.23 3.11 1 P 0 
L 5.23 3.11 5.82 3.11 1 P 0 
L 5.82 3.11 5.845 3.085 1 P 0 
L 5.845 3.085 5.845 2.99498996 1 P 0 
L 5.845 2.99498996 5.85763996 2.98235 1 P 0 
L 5.85763996 2.98235 5.85763996 2.76736004 1 P 0 
L 5.85763996 2.76736004 5.91 2.715 1 P 0 
P 4.885 3.504 58 P 0 8 0;0,2=2,4=0
L 6.01843996 2.715 5.91 2.715 1 P 0 
P 5.91 2.715 11 P 0 8 0;2=1,4=1
P 6.01843996 2.715 43 P 0 8 0;0,2=37,4=0
L 0.54 2.135 0.538 2.135 1 P 0 
L 0.538 2.135 0.53 2.127 1 P 0 
L 0.53 2.127 0.53 2.091 1 P 0 
P 0.54 2.135 11 P 0 8 0;2=7,4=1
P 0.53 2.091 58 P 0 8 0;0,2=2,4=0
P 0.67 1.09 11 P 0 8 0;2=1,4=1
P 4.61996004 1.66626998 9 P 0 8 0;2=4,4=1
L 4.60028002 1.68595 4.61996004 1.66626998 1 P 0 
P 4.60028002 1.68595 10 P 0 8 0;0,2=5,4=0
L 0.45 2.13 0.46255 2.13 1 P 0 
L 0.46255 2.13 0.48 2.11255 1 P 0 
L 0.48 2.11255 0.48 2.091 1 P 0 
P 0.48 2.091 58 P 0 8 0;0,2=2,4=0
P 0.45 2.13 11 P 0 8 0;2=7,4=1
P 4.6987 2.09933002 9 P 0 8 0;2=4,4=1
P 4.67901998 2.07965 10 P 0 8 0;0,2=5,4=0
L 4.67901998 2.07965 4.6987 2.09933002 1 P 0 
P 0.965 2.355 11 P 0 8 0;2=1,4=1
L 0.48231998 2.6453 0.48261998 2.645 1 P 0 
L 0.48261998 2.645 0.494 2.645 1 P 0 
L 0.494 2.645 0.513 2.626 1 P 0 
L 0.513 2.626 0.53 2.626 1 P 0 
L 4.56091004 1.68595 4.5806 1.70563996 1 P 0 
P 4.56091004 1.68595 10 P 0 8 0;0,2=5,4=0
P 4.5806 1.70563996 9 P 0 8 0;2=4,4=1
P 0.735 1.125 11 P 0 8 0;2=1,4=1
P 0.48231998 2.6453 11 P 0 8 0;2=7,4=1
P 0.53 2.626 58 P 0 8 0;0,2=2,4=0
L 0.525 2.78 0.505 2.78 1 P 0 
L 0.505 2.78 0.45 2.725 1 P 0 
L 0.45 2.725 0.45 2.639 1 P 0 
L 0.45 2.639 0.478 2.611 1 P 0 
P 3.755 3.505 9 P 0 8 0;2=26,4=1
P 4.67901998 2.11901998 10 P 0 8 0;0,2=5,4=0
L 4.67901998 2.11901998 4.6987 2.1387 1 P 0 
P 4.6987 2.1387 9 P 0 8 0;2=4,4=1
P 0.525 2.78 11 P 0 8 0;2=7,4=1
P 0.478 2.611 58 P 0 8 0;0,2=2,4=0
L 4.6 0.76 4.545 0.705 1 P 0 
L 4.545 0.705 4.2 0.705 1 P 0 
L 4.2 0.705 4.175 0.73 1 P 0 
L 4.175 0.73 4.175 0.75 1 P 0 
P 4.6 0.76 11 P 0 8 0;2=7,4=1
P 4.60028002 1.76468996 10 P 0 8 0;0,2=5,4=0
L 4.60028002 1.76468996 4.61996004 1.78436998 1 P 0 
P 4.61996004 1.78436998 9 P 0 8 0;2=4,4=1
P 0.905 1.05 11 P 0 8 0;2=7,4=1
P 4.175 0.75 11 P 0 8 0;2=7,4=1
P 0.51765 0.966 9 P 0 8 0;2=9,4=1
L 0.535 0.926 0.535 0.94865 1 P 0 
L 0.535 0.94865 0.51765 0.966 1 P 0 
P 0.535 0.926 58 P 0 8 0;0,2=2,4=0
P 2.078 0.8301 11 P 0 8 0;2=7,4=1
L 0.46 0.82 0.46 0.843 1 P 0 
L 0.46 0.843 0.447 0.856 1 P 0 
L 0.447 0.856 0.447 0.91401004 1 P 0 
L 0.447 0.91401004 0.45898996 0.926 1 P 0 
L 0.45898996 0.926 0.485 0.926 1 P 0 
P 0.485 0.926 58 P 0 8 0;0,2=2,4=0
P 0.46 0.82 9 P 0 8 0;2=9,4=1
P 4.65933002 1.78436998 9 P 0 8 0;2=4,4=1
L 4.63965 1.76468996 4.65933002 1.78436998 1 P 0 
P 4.63965 1.76468996 10 P 0 8 0;0,2=5,4=0
L 0.5413 1.525 0.53 1.5137 1 P 0 
L 0.53 1.5137 0.53 1.486 1 P 0 
P 0.53 1.486 58 P 0 8 0;0,2=2,4=0
P 0.5413 1.525 11 P 0 8 0;2=1,4=1
P 4.61996004 1.70563996 9 P 0 8 0;2=4,4=1
L 4.60028002 1.72531998 4.61996004 1.70563996 1 P 0 
P 4.60028002 1.72531998 10 P 0 8 0;0,2=5,4=0
P 0.625 1.005 11 P 0 8 0;2=7,4=1
L 0.4839 1.28311998 0.48311998 1.28311998 1 P 0 
L 0.48311998 1.28311998 0.48 1.28 1 P 0 
L 0.48 1.28 0.475 1.28 1 P 0 
L 0.475 1.28 0.43643996 1.31856004 1 P 0 
L 0.43643996 1.31856004 0.43643996 1.47143996 1 P 0 
L 0.43643996 1.47143996 0.451 1.486 1 P 0 
L 0.451 1.486 0.48 1.486 1 P 0 
P 4.65933002 1.70563996 9 P 0 8 0;2=4,4=1
L 4.63965 1.72531998 4.65933002 1.70563996 1 P 0 
P 4.63965 1.72531998 10 P 0 8 0;0,2=5,4=0
P 0.935 1.105 11 P 0 8 0;2=1,4=1
P 0.48 1.486 58 P 0 8 0;0,2=2,4=0
P 0.4839 1.28311998 11 P 0 8 0;2=7,4=1
L 0.9575 0.6536 1.0046 0.6536 1 P 0 
L 1.0046 0.6536 1.036 0.685 1 P 0 
L 1.036 0.685 1.109 0.685 1 P 0 
L 1.109 0.685 1.128 0.666 1 P 0 
L 1.128 0.666 1.136 0.658 1 P 0 
L 1.136 0.658 1.1731 0.658 1 P 0 
L 1.1731 0.658 1.1737 0.6586 1 P 0 
P 1.128 0.666 9 P 0 8 0;2=9,4=1
P 0.9575 0.6536 83 P 0 8 0;0,2=6,4=0
P 1.1737 0.6586 63 P 0 8 0;0,2=2,4=0
L 6.02558996 4.27558002 5.97613002 4.27558002 1 P 0 
P 5.97613002 4.27558002 11 P 0 8 0;2=1,4=1
P 6.02558996 4.27558002 24 P 0 8 0;0,2=36,4=0
L 0.58 0.884 0.58 0.865 1 P 0 
L 0.58 0.865 0.595 0.85 1 P 0 
L 0.595 0.85 0.595 0.82 1 P 0 
L 0.595 0.82 0.57676004 0.80176004 1 P 0 
L 0.57676004 0.80176004 0.57676004 0.77913996 1 P 0 
L 0.635 0.845 0.635 0.87 1 P 0 
L 0.635 0.87 0.621 0.884 1 P 0 
L 0.621 0.884 0.58 0.884 1 P 0 
P 4.16721004 1.84343002 10 P 0 8 0;0,2=5,4=0
P 4.14753002 1.86311004 9 P 0 8 0;2=4,4=1
L 4.16721004 1.84343002 4.14753002 1.86311004 1 P 0 
P 0.945 1.63 11 P 0 8 0;2=7,4=1
P 0.635 0.845 11 P 0 8 0;2=8,4=0
P 0.58 0.884 58 P 0 8 0;0,2=2,4=0
P 0.57676004 0.77913996 35 P 0 8 0;0,2=43,4=0
L 0.555 0.59 0.555 0.6 1 P 0 
L 0.555 0.6 0.55708002 0.60208002 1 P 0 
L 0.55708002 0.60208002 0.55708002 0.64606004 1 P 0 
P 4.20658002 1.84343002 10 P 0 8 0;0,2=5,4=0
P 4.1869 1.86311004 9 P 0 8 0;2=4,4=1
P 0.975 1.72 11 P 0 8 0;2=7,4=1
L 4.20658002 1.84343002 4.1869 1.86311004 1 P 0 
P 0.644 0.7 11 P 0 8 0;2=8,4=0
P 0.55708002 0.64606004 35 P 0 8 0;0,2=43,4=0
P 0.555 0.59 11 P 0 8 0;2=1,4=1
P 4.0489 3.95263002 85 P 0 8 0;0,2=0,4=0
L 3.935 3.91 3.97763002 3.95263002 1 P 0 
L 3.97763002 3.95263002 4.0489 3.95263002 1 P 0 
P 3.935 3.91 9 P 0 8 0;2=24,4=1
P 0.835 1.885 11 P 0 8 0;2=7,4=1
L 0.78746998 1.885 0.835 1.885 1 P 0 
P 0.78746998 1.885 63 P 0 8 0;0,2=2,4=0
P 4.0489 3.97231004 85 P 0 8 0;0,2=0,4=0
L 3.885 3.91 3.94731004 3.97231004 1 P 0 
L 3.94731004 3.97231004 4.0489 3.97231004 1 P 0 
P 3.885 3.91 9 P 0 8 0;2=24,4=1
L 0.78746998 1.93 0.835 1.93 1 P 0 
P 0.835 1.93 11 P 0 8 0;2=7,4=1
P 0.78746998 1.93 63 P 0 8 0;0,2=2,4=0
P 4.0474 3.93293996 81 P 0 8 0;0,2=3,4=0
L 3.985 3.91 4.00793996 3.93293996 1 P 0 
L 4.00793996 3.93293996 4.0474 3.93293996 1 P 0 
L 0.78746998 1.75 0.805 1.75 1 P 0 
L 0.805 1.75 0.835 1.78 1 P 0 
P 3.985 3.91 9 P 0 8 0;2=24,4=1
P 0.835 1.78 11 P 0 8 0;2=7,4=1
P 0.78746998 1.75 63 P 0 8 0;0,2=2,4=0
L 0.58 1.444 0.58 1.42 1 P 0 
L 0.58 1.42 0.585 1.415 1 P 0 
L 0.585 1.415 0.585 1.385 1 P 0 
L 0.585 1.385 0.57676004 1.37676004 1 P 0 
L 0.57676004 1.37676004 0.57676004 1.35 1 P 0 
L 0.57676004 1.35 0.59 1.35 1 P 0 
L 0.59 1.35 0.645 1.295 1 P 0 
P 0.645 1.295 11 P 0 8 0;2=8,4=0
P 0.58 1.444 58 P 0 8 0;0,2=2,4=0
P 0.57676004 1.35 35 P 0 8 0;0,2=43,4=0
P 4.20658002 1.8828 10 P 0 8 0;0,2=5,4=0
P 4.1869 1.90248002 9 P 0 8 0;2=4,4=1
P 0.955 1.92 11 P 0 8 0;2=7,4=1
L 4.20658002 1.8828 4.1869 1.90248002 1 P 0 
L 0.505 1.1259 0.505 1.15 1 P 0 
L 0.505 1.15 0.515 1.16 1 P 0 
L 0.515 1.16 0.53208002 1.16 1 P 0 
L 0.53208002 1.16 0.55708002 1.185 1 P 0 
L 0.55708002 1.185 0.55708002 1.21691998 1 P 0 
P 0.55708002 1.21691998 35 P 0 8 0;0,2=43,4=0
P 0.505 1.1259 58 P 0 8 0;0,2=2,4=0
P 0.565 1.13 11 P 0 8 0;2=8,4=0
L 0.505 1.1259 0.5609 1.1259 1 P 0 
L 0.5609 1.1259 0.565 1.13 1 P 0 
P 4.16721004 1.8828 10 P 0 8 0;0,2=5,4=0
P 4.14753002 1.90248002 9 P 0 8 0;2=4,4=1
P 0.885 1.49 11 P 0 8 0;2=1,4=1
P 0.99 1.755 11 P 0 8 0;2=7,4=1
L 4.16721004 1.8828 4.14753002 1.90248002 1 P 0 
P 4.0489 4.03136998 85 P 0 8 0;0,2=0,4=0
P 3.935 4 9 P 0 8 0;2=26,4=1
L 4.0489 4.03136998 3.96636998 4.03136998 1 P 0 
L 3.96636998 4.03136998 3.935 4 1 P 0 
L 0.332 2.66408002 0.332 2.62508002 1 P 0 
P 0.332 2.62508002 11 P 0 8 0;2=1,4=1
P 0.332 2.66408002 58 P 0 8 0;0,2=2,4=0
P 4.0474 4.05106004 81 P 0 8 0;0,2=3,4=0
L 0.405 2.62 0.377 2.648 1 P 0 
L 0.377 2.648 0.377 2.66408002 1 P 0 
L 4.0474 4.05106004 3.93606004 4.05106004 1 P 0 
L 3.93606004 4.05106004 3.885 4 1 P 0 
P 3.885 4 9 P 0 8 0;2=26,4=1
P 0.405 2.62 11 P 0 8 0;2=1,4=1
P 0.377 2.66408002 58 P 0 8 0;0,2=2,4=0
P 4.0489 4.01168996 85 P 0 8 0;0,2=0,4=0
L 0.19 2.625 0.197 2.632 1 P 0 
L 0.197 2.632 0.197 2.66408002 1 P 0 
P 3.985 4 9 P 0 8 0;2=26,4=1
L 4.0489 4.01168996 3.99668996 4.01168996 1 P 0 
L 3.99668996 4.01168996 3.985 4 1 P 0 
P 0.19 2.625 11 P 0 8 0;2=1,4=1
P 0.197 2.66408002 58 P 0 8 0;0,2=2,4=0
L 0.575 2.049 0.62016998 2.00383002 1 P 0 
L 0.62016998 2.00383002 0.62016998 1.99516998 1 P 0 
L 0.62016998 1.99516998 0.62 1.995 1 P 0 
L 0.62 1.995 0.57676004 1.95176004 1 P 0 
L 0.57676004 1.95176004 0.57676004 1.92086998 1 P 0 
P 0.62 1.995 11 P 0 8 0;2=8,4=0
P 0.57676004 1.92086998 35 P 0 8 0;0,2=43,4=0
P 0.575 2.049 58 P 0 8 0;0,2=2,4=0
P 4.32468996 1.80406004 10 P 0 8 0;0,2=5,4=0
P 4.34436998 1.82373996 9 P 0 8 0;2=4,4=1
L 4.32468996 1.80406004 4.34436998 1.82373996 1 P 0 
P 0.75 1.417 11 P 0 8 0;2=7,4=1
P 4.28531998 1.80406004 10 P 0 8 0;0,2=5,4=0
P 4.26563996 1.82373996 9 P 0 8 0;2=4,4=1
P 0.952 1.51 11 P 0 8 0;2=1,4=1
L 4.26563996 1.82373996 4.28531998 1.80406004 1 P 0 
L 0.556 1.65 0.556 1.699 1 P 0 
L 0.556 1.699 0.545 1.71 1 P 0 
L 0.55708002 1.78778996 0.55708002 1.72208002 1 P 0 
L 0.55708002 1.72208002 0.545 1.71 1 P 0 
P 0.545 1.71 11 P 0 8 0;2=8,4=0
P 0.556 1.65 63 P 0 8 0;0,2=2,4=0
P 0.55708002 1.78778996 35 P 0 8 0;0,2=43,4=0
L 3.98 4.185 4.01 4.155 1 P 0 
L 4.01 4.155 4.09993002 4.155 1 P 0 
L 4.09993002 4.155 4.10463002 4.1503 1 P 0 
L 4.10463002 4.1503 4.10463002 4.0871 1 P 0 
P 4.10463002 4.0871 39 P 0 8 0;0,2=46,4=0
P 0.415 1.275 11 P 0 8 0;2=7,4=1
P 0.821 1.2 63 P 0 8 0;0,2=2,4=0
L 0.821 1.2 0.87 1.2 1 P 0 
P 0.87 1.2 11 P 0 8 0;2=7,4=1
P 0.7558 4.19003996 9 P 0 8 0;2=24,4=1
P 3.98 4.185 9 P 0 8 0;2=26,4=1
L 4.03 4.185 4.1 4.185 1 P 0 
L 4.1 4.185 4.12431004 4.16068996 1 P 0 
L 4.12431004 4.16068996 4.12431004 4.0871 1 P 0 
P 4.12431004 4.0871 39 P 0 8 0;0,2=46,4=0
P 0.465 1.33 11 P 0 8 0;2=7,4=1
P 0.821 1.3 63 P 0 8 0;0,2=2,4=0
P 0.87 1.3 11 P 0 8 0;2=7,4=1
L 0.821 1.3 0.87 1.3 1 P 0 
P 0.705 4.19 9 P 0 8 0;2=24,4=1
P 4.03 4.185 9 P 0 8 0;2=26,4=1
L 3.93 4.185 3.975 4.14 1 P 0 
L 3.975 4.14 4.08023996 4.14 1 P 0 
L 4.08023996 4.14 4.08493996 4.1353 1 P 0 
L 4.08493996 4.1353 4.08493996 4.0886 1 P 0 
P 4.08493996 4.0886 38 P 0 8 0;0,2=47,4=0
L 0.89 1.105 0.88 1.105 1 P 0 
L 0.88 1.105 0.825 1.05 1 P 0 
L 0.825 1.05 0.821 1.05 1 P 0 
P 0.41408996 1.32591004 11 P 0 8 0;2=7,4=1
P 0.821 1.05 63 P 0 8 0;0,2=2,4=0
P 0.89 1.105 11 P 0 8 0;2=7,4=1
P 0.805 4.205 11 P 0 8 0;2=1,4=1
P 3.93 4.185 9 P 0 8 0;2=26,4=1
L 0.578 2.569 0.595 2.569 1 P 0 
L 0.595 2.569 0.647 2.517 1 P 0 
P 0.647 2.517 11 P 0 8 0;2=8,4=0
P 4.24595 1.80406004 10 P 0 8 0;0,2=5,4=0
P 4.22626998 1.82373996 9 P 0 8 0;2=4,4=1
L 4.22626998 1.82373996 4.24595 1.80406004 1 P 0 
P 0.939 1.552 11 P 0 8 0;2=7,4=1
P 0.57676004 2.49173996 35 P 0 8 0;0,2=43,4=0
L 0.57676004 2.49173996 0.57676004 2.56776004 1 P 0 
L 0.57676004 2.56776004 0.578 2.569 1 P 0 
P 0.578 2.569 58 P 0 8 0;0,2=2,4=0
L 0.575 2.265 0.575 2.295 1 P 0 
L 0.575 2.295 0.55708002 2.31291998 1 P 0 
L 0.55708002 2.31291998 0.55708002 2.35866004 1 P 0 
L 0.51451998 2.275 0.53 2.275 1 P 0 
L 0.53 2.275 0.54 2.265 1 P 0 
L 0.54 2.265 0.575 2.265 1 P 0 
P 0.575 2.265 11 P 0 8 0;2=8,4=0
P 0.51451998 2.275 58 P 0 8 0;0,2=2,4=0
P 0.55708002 2.35866004 35 P 0 8 0;0,2=43,4=0
P 4.24595 1.84343002 10 P 0 8 0;0,2=5,4=0
P 4.22626998 1.86311004 9 P 0 8 0;2=4,4=1
P 0.957 2.275 11 P 0 8 0;2=1,4=1
L 4.24595 1.84343002 4.22626998 1.86311004 1 P 0 
P 4.18336998 4.0871 39 P 0 8 0;0,2=46,4=0
P 4.168 4.24 9 P 0 8 0;2=26,4=1
P 0.855 4.205 9 P 0 8 0;2=26,4=1
L 4.18336998 4.0871 4.18336998 4.22463002 1 P 0 
L 4.18336998 4.22463002 4.168 4.24 1 P 0 
P 0.15 2.79 11 P 0 8 0;2=1,4=1
P 0.326 1.487 11 P 0 8 0;2=7,4=1
P 0.326 1.52698002 58 P 0 8 0;0,2=2,4=0
L 0.326 1.52698002 0.326 1.487 1 P 0 
P 4.20306004 4.0886 38 P 0 8 0;0,2=47,4=0
P 0.09 2.86 11 P 0 8 0;2=1,4=1
L 4.20306004 4.0886 4.20306004 4.21968996 1 P 0 
L 4.20306004 4.21968996 4.22336998 4.24 1 P 0 
P 0.9 4.205 9 P 0 8 0;2=26,4=1
P 4.22336998 4.24 9 P 0 8 0;2=26,4=1
P 0.416 1.52698002 58 P 0 8 0;0,2=2,4=0
P 0.416 1.48798002 11 P 0 8 0;2=7,4=1
L 0.416 1.52698002 0.416 1.48798002 1 P 0 
P 4.16368996 4.0871 39 P 0 8 0;0,2=46,4=0
L 4.14 4.19 4.16368996 4.16631004 1 P 0 
L 4.16368996 4.16631004 4.16368996 4.0871 1 P 0 
P 0.09 2.79 11 P 0 8 0;2=1,4=1
P 0.98 4.2 9 P 0 8 0;2=26,4=1
P 4.14 4.19 9 P 0 8 0;2=26,4=1
P 0.191 1.52698002 58 P 0 8 0;0,2=2,4=0
P 0.191 1.48798002 11 P 0 8 0;2=7,4=1
L 0.191 1.52698002 0.191 1.48798002 1 P 0 
P 4.10463002 3.8969 39 P 0 8 0;0,2=46,4=0
L 4.10463002 3.83 4.10463002 3.8969 1 P 0 
P 4.10463002 3.83 9 P 0 8 0;2=24,4=1
L 0.33 3.189 0.33 3.145 1 P 0 
P 0.33 3.145 11 P 0 8 0;2=7,4=1
P 0.33 3.189 58 P 0 8 0;0,2=2,4=0
P 4.08493996 3.8954 38 P 0 8 0;0,2=47,4=0
L 4.08493996 3.8954 4.08493996 3.86031004 1 P 0 
L 4.08493996 3.86031004 4.05463002 3.83 1 P 0 
P 4.05463002 3.83 9 P 0 8 0;2=24,4=1
L 0.43 3.189 0.43 3.145 1 P 0 
P 0.43 3.145 11 P 0 8 0;2=7,4=1
P 0.43 3.189 58 P 0 8 0;0,2=2,4=0
P 4.12431004 3.8969 39 P 0 8 0;0,2=46,4=0
L 4.12431004 3.8969 4.12431004 3.86031998 1 P 0 
L 4.12431004 3.86031998 4.15463002 3.83 1 P 0 
P 4.15463002 3.83 9 P 0 8 0;2=24,4=1
L 0.18 3.189 0.18 3.145 1 P 0 
P 0.18 3.145 11 P 0 8 0;2=7,4=1
P 0.18 3.189 58 P 0 8 0;0,2=2,4=0
L 0.87 2.714 0.87 2.77 8 P 0 
L 0.87 2.77 0.851 2.789 8 P 0 
L 0.851 2.789 0.80648002 2.789 8 P 0 
S P 0
OB 0.854 2.754 I
OS 0.915169980315 2.754
OC 0.9188 2.748330019685 0.915166141732 2.750000590551 Y
OC 0.916980019685 2.74 0.936997834646 2.739990255906 N
OS 0.916980019685 2.716
OC 0.91971003937 2.705919980315 0.936996850394 2.716011515748 N
OC 0.91646003937 2.695 0.936475984252 2.694986515748 N
OS 0.91646003937 2.671
OC 0.918769980315 2.661680019685 0.936476279528 2.67101476378 N
OS 0.919 2.66123996063
OS 0.919 2.6567
OS 0.91886003937 2.65633996063
OC 0.91746003937 2.649 0.93747726378 2.648985433071 N
OS 0.91746003937 2.61746003937
OS 0.91623996063 2.61623996063
OS 0.88123996063 2.61623996063
OS 0.878669980315 2.61881003937
OS 0.87965 2.62018996063
OC 0.885019980315 2.637 0.85600226378 2.637006988189 N
OC 0.856 2.666019980315 0.856 2.637 N
OS 0.8556 2.666019980315
OC 0.85168996063 2.666319980315 0.85173730315 2.641306397638 N
OS 0.843680019685 2.666319980315
OS 0.835 2.675
OS 0.814480019685 2.675
OS 0.814480019685 2.689
OS 0.849480019685 2.724
OS 0.849480019685 2.749480019685
OS 0.854 2.754
OE
SE
L 0.871 2.713 0.87 2.714 8 P 0 
P 0.89848002 2.632 64 P 0 8 0;0,2=19,4=0
L 0.64248002 2.614 0.64248002 2.58 8 P 0 
P 0.76948002 2.525 58 P 0 8 0;0,2=2,4=0
P 0.64248002 2.614 63 P 0 8 0;0,2=2,4=0
L 0.686 2.74 0.68448002 2.73848002 8 P 0 
L 0.68448002 2.73848002 0.68448002 2.709 8 P 0 
P 0.80648002 2.789 58 P 0 8 0;0,2=2,4=0
P 0.81998996 2.68068996 45 P 0 8 0;0,2=48,4=0
P 0.909 2.728 63 P 0 8 0;0,2=2,4=0
P 0.90848002 2.683 63 P 0 8 0;0,2=2,4=0
P 0.869 2.672 11 P 0 8 0;2=7,4=1
P 0.871 2.713 9 P 0 8 0;2=9,4=1
P 0.686 2.74 9 P 0 8 0;2=26,4=1
P 0.68448002 2.709 63 P 0 8 0;0,2=2,4=0
P 0.64248002 2.58 11 P 0 8 0;2=7,4=1
P 0.736 2.525 9 P 0 8 0;2=26,4=1
L 0.76948002 2.525 0.736 2.525 8 P 0 
P 0.714 2.329 11 P 0 8 0;2=7,4=1
L 0.714 2.294 0.758 2.294 8 P 0 
L 0.758 2.294 0.7826 2.2694 8 P 0 
L 0.7826 2.2694 0.7826 2.2465 8 P 0 
P 0.7826 2.2465 50 P 0 8 0;0,2=42,4=0
L 0.714 2.294 0.714 2.329 8 P 0 
P 0.714 2.294 58 P 0 8 0;0,2=2,4=0
L 3.45698002 2.509 3.491 2.509 8 P 0 
L 3.491 2.47698002 3.491 2.509 8 P 0 
S P 0
OB 3.375 2.515 I
OS 3.458980019685 2.515
OS 3.458980019685 2.494
OC 3.474 2.478980019685 3.474 2.494 N
OS 3.505 2.478980019685
OS 3.505 2.395
OS 3.50001003937 2.39001003937
OS 3.49973996063 2.389869980315
OC 3.49341003937 2.385 3.509993110236 2.369994291339 N
OS 3.485 2.385
OS 3.475 2.395
OS 3.475 2.43
OS 3.458 2.447
OS 3.388 2.447
OS 3.375 2.46
OS 3.375 2.515
OE
SE
P 3.429 2.468 9 P 0 8 0;2=9,4=1
P 3.435 2.511 58 P 0 8 0;0,2=2,4=0
P 3.491 2.509 67 P 0 8 0;0,2=19,4=0
P 3.38483996 2.511 58 P 0 8 0;0,2=2,4=0
L 3.485 2.395 3.4725 2.3825 6 P 0 
L 3.4725 2.3825 3.45191998 2.38251004 6 P 0 
L 3.45191998 2.38251004 3.45151998 2.3829 6 P 0 
P 3.45151998 2.3829 60 P 0 8 0;0,2=49,4=0
P 3.39983996 2.40503996 30 P 0 8 0;0,2=50,4=0
L 3.39983996 2.40503996 3.39983996 2.44983996 6 P 0 
L 3.51 2.33243002 3.49256998 2.33243002 1 P 0 
L 3.49256998 2.33243002 3.48146998 2.34353002 1 P 0 
L 3.48146998 2.34353002 3.45151998 2.34353002 1 P 0 
L 3.57 2.33243002 3.51 2.33243002 1 P 0 
P 3.51 2.33243002 11 P 0 8 0;2=7,4=1
P 3.45151998 2.34353002 60 P 0 8 0;0,2=49,4=0
P 3.57 2.33243002 89 P 0 8 0;0,2=51,4=0
L 3.57 2.33243002 3.60243002 2.33243002 1 P 0 
L 3.60243002 2.33243002 3.61643002 2.34643002 1 P 0 
L 3.61643002 2.34643002 3.63673002 2.34643002 1 P 0 
P 3.63673002 2.34643002 47 P 0 8 0;0,2=14,4=0
P 3.278 2.468 9 P 0 8 0;2=9,4=1
L 3.278 2.468 3.314 2.432 1 P 0 
L 3.314 2.432 3.348 2.432 1 P 0 
L 3.348 2.432 3.36046998 2.41953002 1 P 0 
L 3.36046998 2.41953002 3.36046998 2.40503996 1 P 0 
L 3.285 2.511 3.285 2.492 1 P 0 
L 3.285 2.492 3.278 2.485 1 P 0 
L 3.278 2.485 3.278 2.468 1 P 0 
P 3.285 2.511 58 P 0 8 0;0,2=2,4=0
P 3.36046998 2.40503996 30 P 0 8 0;0,2=50,4=0
P 3.243 2.547 9 P 0 8 0;2=9,4=1
L 3.243 2.547 3.252 2.538 1 P 0 
L 3.252 2.538 3.252 2.458 1 P 0 
L 3.252 2.458 3.30741998 2.40258002 1 P 0 
L 3.30741998 2.40258002 3.32848002 2.40258002 1 P 0 
L 3.201 2.569 3.221 2.569 1 P 0 
L 3.221 2.569 3.243 2.547 1 P 0 
P 3.201 2.569 63 P 0 8 0;0,2=2,4=0
P 3.32848002 2.40258002 60 P 0 8 0;0,2=49,4=0
P 3.385 2.135 11 P 0 8 0;2=8,4=0
L 3.385 2.135 3.385 2.155 1 P 0 
L 3.385 2.155 3.39983996 2.16983996 1 P 0 
L 3.39983996 2.16983996 3.39983996 2.22296004 1 P 0 
P 3.39983996 2.22296004 30 P 0 8 0;0,2=50,4=0
L 3.32848002 2.32383996 3.31036998 2.32383996 1 P 0 
L 3.31036998 2.32383996 3.27421004 2.36 1 P 0 
L 3.27421004 2.36 3.24 2.36 1 P 0 
L 3.24 2.36 3.24 2.395 1 P 0 
L 3.24 2.395 3.201 2.434 1 P 0 
P 3.24 2.36 9 P 0 8 0;2=9,4=1
P 3.32848002 2.32383996 60 P 0 8 0;0,2=49,4=0
P 3.201 2.479 63 P 0 8 0;0,2=2,4=0
L 3.201 2.479 3.201 2.434 1 P 0 
P 3.201 2.434 63 P 0 8 0;0,2=2,4=0
L 3.285 2.38645 3.28155 2.38645 1 P 0 
L 3.28155 2.38645 3.23 2.438 1 P 0 
L 3.23 2.438 3.23 2.495 1 P 0 
L 3.23 2.495 3.201 2.524 1 P 0 
L 3.32848002 2.34353002 3.31146998 2.34353002 1 P 0 
L 3.31146998 2.34353002 3.285 2.37 1 P 0 
L 3.285 2.37 3.285 2.38645 1 P 0 
P 3.285 2.38645 9 P 0 8 0;2=9,4=1
P 3.201 2.524 63 P 0 8 0;0,2=2,4=0
P 3.32848002 2.34353002 60 P 0 8 0;0,2=49,4=0
P 0.835 2.566 58 P 0 8 0;0,2=2,4=0
L 0.835 2.566 0.835 2.6 1 P 0 
L 0.835 2.6 0.832 2.603 1 P 0 
L 0.832 2.603 0.82531004 2.603 1 P 0 
L 0.82531004 2.603 0.79931998 2.62898996 1 P 0 
L 0.79931998 2.62898996 0.79931998 2.63048996 1 P 0 
P 0.832 2.603 11 P 0 8 0;2=1,4=1
P 0.79931998 2.63048996 32 P 0 8 0;0,2=52,4=0
P 0.76948002 2.567 58 P 0 8 0;0,2=2,4=0
P 0.77963996 2.601 9 P 0 8 0;2=9,4=1
L 0.77963996 2.601 0.77963996 2.63048996 1 P 0 
L 0.76948002 2.567 0.77963996 2.57716004 1 P 0 
L 0.77963996 2.57716004 0.77963996 2.601 1 P 0 
P 0.77963996 2.63048996 32 P 0 8 0;0,2=52,4=0
P 0.68448002 2.614 63 P 0 8 0;0,2=2,4=0
L 0.68448002 2.614 0.68448002 2.58851998 1 P 0 
L 0.68448002 2.58851998 0.695 2.578 1 P 0 
P 0.695 2.578 11 P 0 8 0;2=1,4=1
L 0.75896998 2.64131004 0.74066004 2.623 1 P 0 
L 0.74066004 2.623 0.69348002 2.623 1 P 0 
L 0.69348002 2.623 0.68448002 2.614 1 P 0 
P 0.75896998 2.64131004 45 P 0 8 0;0,2=48,4=0
L 0.72 2.714 0.72 2.74 1 P 0 
L 0.72 2.74 0.69073996 2.76926004 1 P 0 
L 0.69073996 2.76926004 0.68173996 2.76926004 1 P 0 
L 0.68173996 2.76926004 0.661 2.79 1 P 0 
P 0.661 2.79 63 P 0 8 0;0,2=2,4=0
L 0.72 2.714 0.72 2.71 1 P 0 
L 0.72 2.71 0.725 2.705 1 P 0 
L 0.725 2.705 0.74898996 2.705 1 P 0 
L 0.74898996 2.705 0.75896998 2.69501998 1 P 0 
L 0.75896998 2.69501998 0.75896998 2.68068996 1 P 0 
P 0.72 2.714 9 P 0 8 0;2=9,4=1
P 0.75896998 2.68068996 45 P 0 8 0;0,2=48,4=0
L 0.825 2.732 0.82 2.732 1 P 0 
L 0.82 2.732 0.79931998 2.71131998 1 P 0 
L 0.79931998 2.71131998 0.79931998 2.69151004 1 P 0 
P 0.825 2.732 9 P 0 8 0;2=9,4=1
P 0.79931998 2.69151004 32 P 0 8 0;0,2=52,4=0
P 6.01953002 2.14381998 36 P 0 8 0;0,2=22,4=0
P 6.033 2.324 64 P 0 8 0;0,2=19,4=0
L 6.033 2.324 6.033 2.274 9 P 0 
L 6.033 2.274 6.029 2.27 9 P 0 
L 6.01953002 2.18853002 6.01953002 2.21553002 6 P 0 
L 6.01953002 2.21553002 6.029 2.225 6 P 0 
P 6.01953002 2.18853002 11 P 0 8 0;2=1,4=1
L 6.01953002 2.14381998 6.01953002 2.18853002 6 P 0 
L 6.029 2.225 6.029 2.27 9 P 0 
P 6.029 2.27 63 P 0 8 0;0,2=2,4=0
P 6.029 2.225 63 P 0 8 0;0,2=2,4=0
P 4.41975 2.92521004 65 P 0 8 0;0,2=53,4=0
L 4.524 2.995 4.435 2.995 1 P 0 
L 4.435 2.995 4.415 2.975 1 P 0 
P 4.524 2.995 63 P 0 8 0;0,2=2,4=0
L 4.41975 2.92521004 4.41975 2.97025 1 P 0 
L 4.41975 2.97025 4.415 2.975 1 P 0 
P 4.415 2.975 9 P 0 8 0;2=9,4=1
L 6.1437 4.27558002 6.09423996 4.27558002 1 P 0 
P 6.09423996 4.27558002 11 P 0 8 0;2=1,4=1
P 6.1437 4.27558002 24 P 0 8 0;0,2=36,4=0
L 0.845 2.18 0.83296004 2.18 1 P 0 
L 0.83296004 2.18 0.804 2.15103996 1 P 0 
P 0.959 2.789 11 P 0 8 0;2=7,4=1
P 0.845 2.18 11 P 0 8 0;2=1,4=1
P 0.804 2.15103996 72 P 0 8 0;0,2=54,4=0
P 5.99983996 2.14381998 36 P 0 8 0;0,2=22,4=0
L 5.99983996 2.14381998 5.99983996 2.17516998 1 P 0 
L 5.99983996 2.17516998 5.97001004 2.205 1 P 0 
L 5.97001004 2.205 5.94153002 2.205 1 P 0 
L 5.94153002 2.33 5.94153002 2.37653002 1 P 0 
L 5.94153002 2.37653002 5.955 2.39 1 P 0 
P 5.955 2.39 11 P 0 8 0;2=8,4=0
L 5.94153002 2.205 5.94153002 2.239 1 P 0 
P 5.94153002 2.205 9 P 0 8 0;2=24,4=1
L 5.94153002 2.28401998 5.94153002 2.33 1 P 0 
P 5.94153002 2.33 63 P 0 8 0;0,2=2,4=0
L 5.94153002 2.239 5.94153002 2.28401998 1 P 0 
P 5.94153002 2.28401998 63 P 0 8 0;0,2=2,4=0
P 5.94153002 2.239 63 P 0 8 0;0,2=2,4=0
P 5.99983996 2.04418002 36 P 0 8 0;0,2=22,4=0
L 5.99983996 2.04418002 5.99983996 2.01316004 1 P 0 
L 5.99983996 2.01316004 6.012 2.001 1 P 0 
L 6.012 2.001 6.01901998 2.001 1 P 0 
L 6.01901998 1.95065 6.01901998 2.001 1 P 0 
P 6.01901998 2.001 9 P 0 8 0;2=24,4=1
P 6.01901998 1.95065 58 P 0 8 0;0,2=2,4=0
P 5.87 1.84 11 P 0 8 0;2=8,4=0
L 3.4593 2.17 3.4593 2.2007 1 P 0 
L 3.4593 2.2007 3.45151998 2.20848002 1 P 0 
L 3.45151998 2.20848002 3.45151998 2.22541998 1 P 0 
P 3.4593 2.17 9 P 0 8 0;2=24,4=1
P 3.45151998 2.22541998 60 P 0 8 0;0,2=49,4=0
L 3.44 2.12 3.44 2.15 1 P 0 
L 3.44 2.15 3.41953002 2.17046998 1 P 0 
L 3.41953002 2.17046998 3.41953002 2.22296004 1 P 0 
P 3.44 2.12 11 P 0 8 0;2=1,4=1
P 3.41953002 2.22296004 30 P 0 8 0;0,2=50,4=0
P 4.34436998 1.94185 9 P 0 8 0;2=4,4=1
P 3.18 2.685 9 P 0 8 0;2=9,4=1
L 4.32468996 1.92216998 4.34436998 1.94185 1 P 0 
P 4.32468996 1.92216998 10 P 0 8 0;0,2=5,4=0
P 3.523 1.75 9 P 0 8 0;2=26,4=1
L 3.523 1.75 3.52751004 1.74548996 1 P 0 
L 3.52751004 1.74548996 3.554 1.74548996 1 P 0 
P 3.554 1.74548996 58 P 0 8 0;0,2=2,4=0
P 4.712 1.157 11 P 0 8 0;2=8,4=0
P 4.42311004 1.50878996 9 P 0 8 0;2=4,4=1
P 4.40343002 1.52846998 10 P 0 8 0;0,2=5,4=0
L 4.40343002 1.52846998 4.42311004 1.50878996 1 P 0 
P 4.61996004 1.6269 11 P 0 8 0;2=8,4=0
P 4.60028002 1.64658002 10 P 0 8 0;0,2=5,4=0
L 4.60028002 1.64658002 4.61996004 1.6269 1 P 0 
P 4.29 1.235 11 P 0 8 0;2=8,4=0
P 4.38373996 1.46941998 9 P 0 8 0;2=4,4=1
P 4.36406004 1.4891 10 P 0 8 0;0,2=5,4=0
L 4.36406004 1.4891 4.38373996 1.46941998 1 P 0 
P 4.15 1.235 11 P 0 8 0;2=8,4=0
P 4.34436998 1.50878996 9 P 0 8 0;2=4,4=1
L 4.34436998 1.50878996 4.32468996 1.52846998 1 P 0 
P 4.32468996 1.52846998 10 P 0 8 0;0,2=5,4=0
P 5.035 1.49 11 P 0 8 0;2=8,4=0
P 4.65933002 1.58753002 9 P 0 8 0;2=4,4=1
L 4.63965 1.60721004 4.65933002 1.58753002 1 P 0 
P 4.63965 1.60721004 10 P 0 8 0;0,2=5,4=0
P 4.185 1.17 11 P 0 8 0;2=8,4=0
P 4.34436998 1.46941998 9 P 0 8 0;2=4,4=1
L 4.34436998 1.46941998 4.32468996 1.4891 1 P 0 
P 4.32468996 1.4891 10 P 0 8 0;0,2=5,4=0
L 4.816 1.258 4.80018002 1.27381998 1 P 0 
L 4.80018002 1.27381998 4.46118002 1.27381998 1 P 0 
L 4.46118002 1.27381998 4.425 1.31 1 P 0 
L 4.425 1.31 4.425 1.34941004 1 P 0 
L 4.425 1.34941004 4.40343002 1.37098002 1 P 0 
P 4.816 1.258 11 P 0 8 0;2=8,4=0
P 4.40343002 1.37098002 10 P 0 8 0;0,2=5,4=0
P 4.665 1.104 11 P 0 8 0;2=8,4=0
P 4.38373996 1.3513 9 P 0 8 0;2=4,4=1
P 4.36406004 1.37098002 10 P 0 8 0;0,2=5,4=0
L 4.36406004 1.37098002 4.38373996 1.3513 1 P 0 
L 4.91 1.54 4.893 1.54 1 P 0 
L 4.893 1.54 4.82578996 1.60721004 1 P 0 
L 4.82578996 1.60721004 4.71838996 1.60721004 1 P 0 
P 4.91 1.54 11 P 0 8 0;2=8,4=0
P 4.71838996 1.60721004 10 P 0 8 0;0,2=5,4=0
P 4.768 1.207 11 P 0 8 0;2=8,4=0
P 4.42311004 1.46941998 9 P 0 8 0;2=4,4=1
P 4.40343002 1.4891 10 P 0 8 0;0,2=5,4=0
L 4.40343002 1.4891 4.42311004 1.46941998 1 P 0 
P 5.03 1.55 11 P 0 8 0;2=8,4=0
P 4.58058996 1.6269 9 P 0 8 0;2=4,4=1
L 4.56091004 1.64658002 4.58058996 1.6269 1 P 0 
P 4.56091004 1.64658002 10 P 0 8 0;0,2=5,4=0
P 4.828 1.103 11 P 0 8 0;2=8,4=0
P 4.42311004 1.43005 9 P 0 8 0;2=4,4=1
P 4.40343002 1.44973002 10 P 0 8 0;0,2=5,4=0
L 4.40343002 1.44973002 4.42311004 1.43005 1 P 0 
L 4.83 1.33 4.785 1.285 1 P 0 
L 4.785 1.285 4.475 1.285 1 P 0 
L 4.475 1.285 4.4428 1.3172 1 P 0 
L 4.4428 1.3172 4.4428 1.33161004 1 P 0 
P 4.83 1.33 11 P 0 8 0;2=8,4=0
P 4.4428 1.33161004 10 P 0 8 0;0,2=5,4=0
L 4.40343002 1.33161004 4.40343002 1.29843002 1 P 0 
L 4.40343002 1.29843002 4.39 1.285 1 P 0 
L 4.39 1.285 4.27 1.285 1 P 0 
L 4.27 1.285 4.22 1.235 1 P 0 
P 4.22 1.235 11 P 0 8 0;2=8,4=0
P 4.40343002 1.33161004 10 P 0 8 0;0,2=5,4=0
P 3.83128002 1.78371998 9 P 0 8 0;2=26,4=1
L 3.83128002 1.78371998 3.85161998 1.80406004 1 P 0 
L 3.85161998 1.80406004 3.89161004 1.80406004 1 P 0 
L 6.02558996 4.21653996 6.02558996 4.175 1 P 0 
P 6.02558996 4.175 11 P 0 8 0;2=1,4=1
P 6.02558996 4.21653996 24 P 0 8 0;0,2=36,4=0
P 3.89161004 1.80406004 10 P 0 8 0;0,2=5,4=0
L 3.89161004 1.84343002 3.87193002 1.86311004 1 P 0 
L 6.1437 4.21653996 6.1437 4.175 1 P 0 
P 6.1437 4.175 11 P 0 8 0;2=1,4=1
P 6.1437 4.21653996 24 P 0 8 0;0,2=36,4=0
P 3.87193002 1.86311004 9 P 0 8 0;2=4,4=1
P 3.89161004 1.84343002 10 P 0 8 0;0,2=5,4=0
P 4.14753002 2.05996004 9 P 0 8 0;2=4,4=1
P 4.16721004 2.04028002 10 P 0 8 0;0,2=5,4=0
L 4.16721004 2.04028002 4.14753002 2.05996004 1 P 0 
P 5.83 2.97 11 P 0 8 0;2=7,4=1
P 5.89953002 2.366 9 P 0 8 0;2=24,4=1
L 5.89953002 2.33 5.89953002 2.366 1 P 0 
P 5.89953002 2.33 63 P 0 8 0;0,2=2,4=0
P 3.61123996 3.49876004 9 P 0 8 0;2=9,4=1
P 4.54121998 1.94185 9 P 0 8 0;2=4,4=1
P 4.52153996 1.92216998 10 P 0 8 0;0,2=5,4=0
L 4.52153996 1.92216998 4.54121998 1.94185 1 P 0 
P 4.22626998 1.94185 9 P 0 8 0;2=4,4=1
P 4.24595 1.92216998 10 P 0 8 0;0,2=5,4=0
L 4.24595 1.92216998 4.22626998 1.94185 1 P 0 
P 1.96496998 0.76501998 9 P 0 8 0;2=24,4=1
L 1.96496998 0.76501998 1.96496998 0.66473002 1 P 0 
L 1.96496998 0.66473002 1.9977 0.632 1 P 0 
P 1.9977 0.632 58 P 0 8 0;0,2=2,4=0
P 4.1869 1.98121998 9 P 0 8 0;2=4,4=1
P 3.12 2.565 11 P 0 8 0;2=7,4=1
P 3.119 2.299 11 P 0 8 0;2=1,4=1
P 3.159 2.299 63 P 0 8 0;0,2=2,4=0
L 3.159 2.299 3.119 2.299 1 P 0 
P 4.20658002 1.96153996 10 P 0 8 0;0,2=5,4=0
L 4.20658002 1.96153996 4.1869 1.98121998 1 P 0 
P 4.26563996 1.90248002 9 P 0 8 0;2=4,4=1
P 3.385 2.59 11 P 0 8 0;2=1,4=1
P 4.28531998 1.8828 10 P 0 8 0;0,2=5,4=0
L 4.28531998 1.8828 4.26563996 1.90248002 1 P 0 
P 5.155 2.01 11 P 0 8 0;2=7,4=1
L 6.025 1.83 6.025 1.84 1 P 0 
L 6.025 1.84 6.01901998 1.84598002 1 P 0 
L 6.01901998 1.84598002 6.01901998 1.90865 1 P 0 
P 6.025 1.83 11 P 0 8 0;2=1,4=1
P 6.01901998 1.90865 58 P 0 8 0;0,2=2,4=0
P 4.1869 2.05996004 9 P 0 8 0;2=4,4=1
P 4.20658002 2.04028002 10 P 0 8 0;0,2=5,4=0
L 4.20658002 2.04028002 4.1869 2.05996004 1 P 0 
P 4.34436998 1.90248002 9 P 0 8 0;2=4,4=1
P 4.32468996 1.8828 10 P 0 8 0;0,2=5,4=0
L 4.32468996 1.8828 4.34436998 1.90248002 1 P 0 
P 2.554 2.901 11 P 0 8 0;2=1,4=1
L 4.75 1.63 4.884 1.63 1 P 0 
L 4.67901998 1.64658002 4.6956 1.63 1 P 0 
L 4.6956 1.63 4.75 1.63 1 P 0 
P 4.75 1.63 9 P 0 8 0;2=15,4=1
P 4.884 1.675 63 P 0 8 0;0,2=2,4=0
L 4.884 1.675 4.884 1.63 1 P 0 
P 4.884 1.63 63 P 0 8 0;0,2=2,4=0
P 4.67901998 1.64658002 10 P 0 8 0;0,2=5,4=0
P 3.205 1.7 11 P 0 8 0;2=1,4=1
L 3.205 1.7 3.2 1.695 1 P 0 
L 3.2 1.695 3.166 1.695 1 P 0 
P 3.166 1.695 63 P 0 8 0;0,2=2,4=0
L 3.166 1.695 3.166 1.645 1 P 0 
P 3.166 1.645 63 P 0 8 0;0,2=2,4=0
L 4.775 1.705 4.75595 1.68595 1 P 0 
L 4.75595 1.68595 4.71838996 1.68595 1 P 0 
P 4.71838996 1.68595 10 P 0 8 0;0,2=5,4=0
P 4.775 1.705 11 P 0 8 0;2=7,4=1
P 4.84 1.855 11 P 0 8 0;2=1,4=1
P 4.58058996 1.82373996 9 P 0 8 0;2=4,4=1
P 4.56091004 1.80406004 10 P 0 8 0;0,2=5,4=0
L 4.56091004 1.80406004 4.58058996 1.82373996 1 P 0 
P 4.65933002 1.86311004 9 P 0 8 0;2=4,4=1
P 4.63965 1.84343002 10 P 0 8 0;0,2=5,4=0
L 4.63965 1.84343002 4.65933002 1.86311004 1 P 0 
P 4.815 1.93 11 P 0 8 0;2=1,4=1
P 4.885 3.46 11 P 0 8 0;2=7,4=1
P 4.835 3.504 58 P 0 8 0;0,2=2,4=0
L 4.835 3.504 4.835 3.46001004 1 P 0 
L 4.835 3.46001004 4.83501004 3.46 1 P 0 
P 4.61996004 1.86311004 9 P 0 8 0;2=4,4=1
P 4.83501004 3.46 11 P 0 8 0;2=1,4=1
L 4.60028002 1.84343002 4.61996004 1.86311004 1 P 0 
P 4.60028002 1.84343002 10 P 0 8 0;0,2=5,4=0
P 3.125 2.254 11 P 0 8 0;2=7,4=1
L 3.159 2.254 3.125 2.254 1 P 0 
P 3.159 2.209 63 P 0 8 0;0,2=2,4=0
P 3.159 2.254 63 P 0 8 0;0,2=2,4=0
L 3.159 2.209 3.159 2.254 1 P 0 
P 4.28531998 1.84343002 10 P 0 8 0;0,2=5,4=0
L 4.28531998 1.84343002 4.26563996 1.86311004 1 P 0 
P 4.26563996 1.86311004 9 P 0 8 0;2=15,4=1
P 3.12 2.69 11 P 0 8 0;2=7,4=1
L 1.3825 3.7225 1.3825 3.8085 1 P 0 
L 1.3825 3.8085 1.425 3.851 1 P 0 
L 4.566 2.995 4.566 3.054 1 P 0 
L 4.566 3.054 4.565 3.055 1 P 0 
P 4.565 3.055 11 P 0 8 0;2=7,4=1
P 4.3 3.81 11 P 0 8 0;2=1,4=1
P 1.3825 3.7225 9 P 0 8 0;2=26,4=1
P 1.425 3.851 63 P 0 8 0;0,2=2,4=0
P 5.905 3.015 9 P 0 8 0;2=24,4=1
P 6.01843996 3.015 43 P 0 8 0;0,2=37,4=0
L 5.905 3.015 6.01843996 3.015 1 P 0 
P 5.41 0.96 11 P 0 8 0;2=8,4=0
P 4.85033002 1.74933996 11 P 0 8 0;2=7,4=1
L 4.52153996 1.76468996 4.54121998 1.78436998 1 P 0 
P 4.52153996 1.76468996 10 P 0 8 0;0,2=5,4=0
P 4.54121998 1.78436998 9 P 0 8 0;2=4,4=1
L 4.566 2.995 4.58661998 2.995 1 P 0 
L 4.58661998 2.995 4.64243002 2.93918996 1 P 0 
L 4.64243002 2.93918996 5.24418996 2.93918996 1 P 0 
L 5.24418996 2.93918996 5.26 2.955 1 P 0 
P 4.566 2.995 63 P 0 8 0;0,2=2,4=0
P 5.26 2.955 11 P 0 8 0;2=7,4=1
L 6.30728996 2.20183996 6.30728996 2.22378996 3 P 0 
A 6.30728996 2.22378996 6.29533996 2.23573996 6.29533996 2.22378996 3 P 0 N
A 6.29533996 2.23573996 6.2872 2.24388002 6.29533996 2.24387992 3 P 0 Y
L 6.2872 2.24388002 6.2872 2.25416998 3 P 0 
A 6.2872 2.25416998 6.2667 2.272 6.2667 2.2513001 3 P 0 N
L 6.2667 2.272 6.21105 2.272 3 P 0 
A 6.21105 2.272 6.20693002 2.27253002 6.2110376 2.28818179 3 P 0 Y
L 6.20693002 2.27253002 6.19961004 2.27673996 3 P 0 
L 3.58206998 1.92336004 3.60336004 1.92336004 3 P 0 
L 3.60336004 1.92336004 3.60411004 1.92411004 3 P 0 
L 3.60411004 1.92411004 3.6116 1.92411004 3 P 0 
A 3.6116 1.92411004 3.6323 1.94481004 3.6116 1.94481004 3 P 0 N
L 3.6323 1.94481004 3.6323 2.00521004 3 P 0 
A 3.6323 2.00521004 3.62776004 2.01938996 3.60798189 2.00524085 3 P 0 N
A 3.62776004 2.01938996 3.60226998 2.03778002 3.58758907 1.99057057 3 P 0 N
A 3.60226998 2.03778002 3.59216004 2.0393 3.59222106 2.00532362 3 P 0 N
L 3.59216004 2.0393 3.44463002 2.0393 3 P 0 
A 3.44463002 2.0393 3.42956004 2.03541004 3.4445938 2.00830413 3 P 0 N
A 3.42956004 2.03541004 3.40083002 1.99598002 3.45772618 1.98470541 3 P 0 N
A 3.40083002 1.99598002 3.4 1.98738002 3.44418622 1.98745541 3 P 0 N
L 3.4 1.98738002 3.4 1.38846998 3 P 0 
A 3.4 1.38846998 3.41963002 1.34106998 3.46702096 1.38846093 3 P 0 N
L 3.41963002 1.34106998 3.59948996 1.16121004 3 P 0 
A 3.59948996 1.16121004 3.6335 1.07911998 3.51741063 1.07911417 3 P 0 Y
L 3.6335 1.07911998 3.6335 0.93498996 3 P 0 
A 3.6335 0.93498996 3.63348996 0.93455 3.65292283 0.93432657 3 P 0 N
L 3.63348996 0.93455 3.6335 0.93451998 3 P 0 
A 3.6335 0.93451998 3.625 0.92 3.60143071 0.94354537 3 P 0 Y
P 3.625 0.92 9 P 0 8 0;2=38,4=1
P 3.58206998 1.92336004 69 P 0 8 0;0,2=55,4=0
P 6.19961004 2.27673996 9 P 0 8 0;2=38,4=1
L 6.30728996 2.20183996 6.30728996 2.16388996 3 P 0 
A 6.30728996 2.16388996 6.30608996 2.15836004 6.29400984 2.16387657 3 P 0 Y
A 6.30608996 2.15836004 6.30198002 2.1544 6.29899055 2.16161535 3 P 0 Y
L 6.30198002 2.1544 6.29625 2.15201998 3 P 0 
A 6.29625 2.15201998 6.28738002 2.15023996 6.28736634 2.17329783 3 P 0 Y
A 6.28738002 2.15023996 6.27813002 2.14641004 6.28737992 2.13715492 3 P 0 N
L 6.27813002 2.14641004 6.27008996 2.13836998 3 P 0 
A 6.27008996 2.13836998 6.2661 2.12873996 6.27972274 2.1287372 3 P 0 N
L 6.2661 2.12873996 6.2661 2.11683002 3 P 0 
A 6.2661 2.11683002 6.26766004 2.11133996 6.27652185 2.1168247 3 P 0 N
A 6.26766004 2.11133996 6.27993002 2.1045 6.27992992 2.1189253 3 P 0 N
L 6.27993002 2.1045 6.30913996 2.1045 3 P 0 
A 6.30913996 2.1045 6.31213996 2.1075 6.30913996 2.1075 3 P 0 N
A 6.31213996 2.1075 6.31513996 2.1105 6.31513996 2.1075 3 P 0 Y
L 6.31513996 2.1105 6.33193996 2.1105 3 P 0 
A 6.33193996 2.1105 6.33493996 2.1075 6.33193996 2.1075 3 P 0 Y
A 6.33493996 2.1075 6.33793996 2.1045 6.33793996 2.1075 3 P 0 N
L 6.33793996 2.1045 6.3656 2.1045 3 P 0 
A 6.3656 2.1045 6.36676998 2.10446998 6.36565413 2.08379921 3 P 0 Y
A 6.36676998 2.10446998 6.36793002 2.10536004 6.36391152 2.10939646 3 P 0 N
L 6.36793002 2.10536004 6.37113996 2.10856998 3 P 0 
A 6.37113996 2.10856998 6.37516998 2.11023996 6.37516988 2.10454242 3 P 0 Y
L 6.37516998 2.11023996 6.4105 2.11023996 3 P 0 
P 6.30728996 2.20183996 53 P 0 8 0;0,2=6,4=0
P 6.4105 2.11023996 87 P 0 8 0;0,2=56,4=0
L 6.23248996 2.20183996 6.23248996 2.23003996 3 P 0 
A 6.23248996 2.23003996 6.24118996 2.23873996 6.24118996 2.23003996 3 P 0 Y
L 6.24118996 2.23873996 6.2665 2.23873996 3 P 0 
A 6.2665 2.23873996 6.2722 2.24443996 6.2665 2.24443996 3 P 0 N
L 6.2722 2.24443996 6.2722 2.25278996 3 P 0 
A 6.2722 2.25278996 6.2667 2.257 6.2666999 2.25130236 3 P 0 N
L 6.2667 2.257 6.21253002 2.257 3 P 0 
L 6.21253002 2.257 6.20973996 2.25486998 3 P 0 
L 6.20973996 2.25486998 6.19961004 2.24473996 3 P 0 
P 6.23248996 2.20183996 53 P 0 8 0;0,2=6,4=0
P 6.4105 2.08465 87 P 0 8 0;0,2=56,4=0
L 6.23248996 2.20183996 6.23248996 2.15071998 3 P 0 
A 6.23248996 2.15071998 6.2349 2.1449 6.24072008 2.150719 3 P 0 N
L 6.2349 2.1449 6.24473002 2.13506004 3 P 0 
L 6.24473002 2.13506004 6.24943996 2.13033002 3 P 0 
A 6.24943996 2.13033002 6.2511 2.1263 6.24537815 2.1262999 3 P 0 Y
L 6.2511 2.1263 6.2511 2.11683996 3 P 0 
A 6.2511 2.11683996 6.2549 2.10345 6.27652264 2.11682057 3 P 0 N
A 6.2549 2.10345 6.27993002 2.0895 6.27992992 2.11893022 3 P 0 N
L 6.27993002 2.0895 6.3656 2.0895 3 P 0 
A 6.3656 2.0895 6.36963002 2.08783002 6.3656 2.08380246 3 P 0 Y
L 6.36963002 2.08783002 6.37113996 2.08631998 3 P 0 
A 6.37113996 2.08631998 6.37516998 2.08465 6.37516988 2.09034754 3 P 0 N
L 6.37516998 2.08465 6.4105 2.08465 3 P 0 
P 3.58206998 1.93911004 69 P 0 8 0;0,2=55,4=0
P 3.657 0.92 9 P 0 8 0;2=38,4=1
L 3.58206998 1.93911004 3.6116 1.93911004 3 P 0 
A 3.6116 1.93911004 3.6173 1.94481004 3.6116 1.94481004 3 P 0 N
L 3.6173 1.94481004 3.6173 2.00521004 3 P 0 
A 3.6173 2.00521004 3.61556004 2.01063996 3.60798858 2.00521998 3 P 0 N
A 3.61556004 2.01063996 3.59783002 2.02345 3.5875747 1.9905812 3 P 0 N
A 3.59783002 2.02345 3.59218002 2.0243 3.59221417 2.00532431 3 P 0 N
L 3.59218002 2.0243 3.44461998 2.0243 3 P 0 
A 3.44461998 2.0243 3.43685 2.02228996 3.44461181 2.00830876 3 P 0 N
A 3.43685 2.02228996 3.41555 1.99306998 3.4577252 1.98469951 3 P 0 N
A 3.41555 1.99306998 3.415 1.98738996 3.44418376 1.98743071 3 P 0 N
L 3.415 1.98738996 3.415 1.75015 3 P 0 
A 3.415 1.75015 3.41895 1.7462 3.41895 1.75015 3 P 0 N
A 3.41895 1.7462 3.4229 1.74225 3.41895 1.74225 3 P 0 Y
L 3.4229 1.74225 3.4229 1.72735 3 P 0 
A 3.4229 1.72735 3.41895 1.7234 3.41895 1.72735 3 P 0 Y
A 3.41895 1.7234 3.415 1.71945 3.41895 1.71945 3 P 0 N
L 3.415 1.71945 3.415 1.70455 3 P 0 
A 3.415 1.70455 3.41895 1.7006 3.41895 1.70455 3 P 0 N
A 3.41895 1.7006 3.4229 1.69665 3.41895 1.69665 3 P 0 Y
L 3.4229 1.69665 3.4229 1.68175 3 P 0 
A 3.4229 1.68175 3.41895 1.6778 3.41895 1.68175 3 P 0 Y
A 3.41895 1.6778 3.415 1.67385 3.41895 1.67385 3 P 0 N
L 3.415 1.67385 3.415 1.65895 3 P 0 
A 3.415 1.65895 3.41895 1.655 3.41895 1.65895 3 P 0 N
A 3.41895 1.655 3.4229 1.65105 3.41895 1.65105 3 P 0 Y
L 3.4229 1.65105 3.4229 1.63615 3 P 0 
A 3.4229 1.63615 3.41895 1.6322 3.41895 1.63615 3 P 0 Y
A 3.41895 1.6322 3.415 1.62825 3.41895 1.62825 3 P 0 N
L 3.415 1.62825 3.415 1.61335 3 P 0 
A 3.415 1.61335 3.41895 1.6094 3.41895 1.61335 3 P 0 N
A 3.41895 1.6094 3.4229 1.60545 3.41895 1.60545 3 P 0 Y
L 3.4229 1.60545 3.4229 1.59055 3 P 0 
A 3.4229 1.59055 3.41895 1.5866 3.41895 1.59055 3 P 0 Y
A 3.41895 1.5866 3.415 1.58265 3.41895 1.58265 3 P 0 N
L 3.415 1.58265 3.415 1.56775 3 P 0 
A 3.415 1.56775 3.41895 1.5638 3.41895 1.56775 3 P 0 N
A 3.41895 1.5638 3.4229 1.55985 3.41895 1.55985 3 P 0 Y
L 3.4229 1.55985 3.4229 1.54495 3 P 0 
A 3.4229 1.54495 3.41895 1.541 3.41895 1.54495 3 P 0 Y
A 3.41895 1.541 3.415 1.53705 3.41895 1.53705 3 P 0 N
L 3.415 1.53705 3.415 1.52215 3 P 0 
A 3.415 1.52215 3.41895 1.5182 3.41895 1.52215 3 P 0 N
A 3.41895 1.5182 3.4229 1.51425 3.41895 1.51425 3 P 0 Y
L 3.4229 1.51425 3.4229 1.49935 3 P 0 
A 3.4229 1.49935 3.41895 1.4954 3.41895 1.49935 3 P 0 Y
A 3.41895 1.4954 3.415 1.49145 3.41895 1.49145 3 P 0 N
L 3.415 1.49145 3.415 1.47655 3 P 0 
A 3.415 1.47655 3.41895 1.4726 3.41895 1.47655 3 P 0 N
A 3.41895 1.4726 3.4229 1.46865 3.41895 1.46865 3 P 0 Y
L 3.4229 1.46865 3.4229 1.45375 3 P 0 
A 3.4229 1.45375 3.41895 1.4498 3.41895 1.45375 3 P 0 Y
A 3.41895 1.4498 3.415 1.44585 3.41895 1.44585 3 P 0 N
L 3.415 1.44585 3.415 1.38846998 3 P 0 
A 3.415 1.38846998 3.43023996 1.35168002 3.46701939 1.38846703 3 P 0 N
L 3.43023996 1.35168002 3.6101 1.17181998 3 P 0 
A 3.6101 1.17181998 3.6485 1.07911998 3.51740817 1.07911988 3 P 0 Y
L 3.6485 1.07911998 3.6485 0.93491004 3 P 0 
A 3.6485 0.93491004 3.6485 0.93476004 3.65293248 0.93483504 3 P 0 N
L 3.6485 0.93476004 3.6485 0.93451998 3 P 0 
A 3.6485 0.93451998 3.657 0.92 3.68052726 0.94352077 3 P 0 N
P 6.19961004 2.24473996 9 P 0 8 0;2=38,4=1
L 3.3255 2.1355 3.296 2.165 1 P 0 
L 3.38016004 2.22296004 3.38016004 2.17216004 1 P 0 
L 3.38016004 2.17216004 3.3435 2.1355 1 P 0 
L 3.3435 2.1355 3.3255 2.1355 1 P 0 
P 3.3255 2.1355 11 P 0 8 0;2=1,4=1
L 3.296 2.165 3.296 2.16351998 1 P 0 
L 3.296 2.16351998 3.27248002 2.14 1 P 0 
L 3.27248002 2.14 3.225 2.14 1 P 0 
L 3.225 2.14 3.201 2.164 1 P 0 
P 3.201 2.164 63 P 0 8 0;0,2=2,4=0
P 3.296 2.165 63 P 0 8 0;0,2=2,4=0
P 3.38016004 2.22296004 30 P 0 8 0;0,2=50,4=0
L 3.35153002 2.17875 3.36046998 2.18768996 1 P 0 
L 3.36046998 2.18768996 3.36046998 2.22296004 1 P 0 
P 3.36046998 2.22296004 30 P 0 8 0;0,2=50,4=0
P 3.35153002 2.17875 11 P 0 8 0;2=7,4=1
P 3.44 2.95 9 P 0 8 0;2=9,4=1
L 3.27923002 2.21576998 3.28888002 2.22541998 1 P 0 
L 3.28888002 2.22541998 3.32848002 2.22541998 1 P 0 
P 3.32848002 2.22541998 60 P 0 8 0;0,2=49,4=0
P 3.27923002 2.21576998 11 P 0 8 0;2=7,4=1
P 3.3435 2.82 9 P 0 8 0;2=9,4=1
P 4.41975 2.90553002 65 P 0 8 0;0,2=53,4=0
L 4.46 2.94 4.46 2.92596998 1 P 0 
L 4.46 2.92596998 4.43956004 2.90553002 1 P 0 
L 4.43956004 2.90553002 4.41975 2.90553002 1 P 0 
L 4.524 2.945 4.47903002 2.945 1 P 0 
L 4.47903002 2.945 4.47403002 2.94 1 P 0 
L 4.47403002 2.94 4.46 2.94 1 P 0 
P 4.46 2.94 11 P 0 8 0;2=1,4=1
P 4.524 2.945 63 P 0 8 0;0,2=2,4=0
P 4.41975 2.84646998 65 P 0 8 0;0,2=53,4=0
P 4.524 2.845 63 P 0 8 0;0,2=2,4=0
L 4.47 2.83 4.45353002 2.84646998 1 P 0 
L 4.45353002 2.84646998 4.41975 2.84646998 1 P 0 
L 4.524 2.845 4.485 2.845 1 P 0 
L 4.485 2.845 4.47 2.83 1 P 0 
P 4.47 2.83 11 P 0 8 0;2=1,4=1
L 5.914 0.965 5.88 0.965 8 P 0 
L 5.9945 1.27063002 5.92 1.27063002 8 P 0 
P 5.995 1.165 11 P 0 8 0;2=7,4=1
L 5.956 1.125 5.956 1.126 8 P 0 
L 5.956 1.126 5.995 1.165 8 P 0 
P 5.956 1.125 63 P 0 8 0;0,2=2,4=0
P 3.106 3.26 11 P 0 8 0;2=7,4=1
P 3.222 3.385 9 P 0 8 0;2=26,4=1
P 3.106 3.35 9 P 0 8 0;2=26,4=1
P 1.959 3.325 11 P 0 8 0;2=7,4=1
P 1.959 3.289 58 P 0 8 0;0,2=2,4=0
L 1.959 3.289 1.959 3.325 8 P 0 
P 3.222 3.205 9 P 0 8 0;2=26,4=1
P 3.49 2.955 11 P 0 8 0;2=7,4=1
L 3.98 3.4056 3.98 3.365 8 P 0 
P 3.98 3.365 11 P 0 8 0;2=7,4=1
P 3.98 3.4056 49 P 0 8 0;0,2=11,4=0
P 3.7 3.37 11 P 0 8 0;2=7,4=1
P 3.55 3.37 11 P 0 8 0;2=7,4=1
P 4.175 3.37 11 P 0 8 0;2=7,4=1
L 4.175 3.4076 4.175 3.37 8 P 0 
P 4.175 3.4076 49 P 0 8 0;0,2=11,4=0
P 3.71 3.26 11 P 0 8 0;2=7,4=1
P 3.55 3.28 9 P 0 8 0;2=26,4=1
P 3.414 3.235 11 P 0 8 0;2=7,4=1
L 3.481 3.235 3.414 3.235 8 P 0 
P 3.481 3.235 102 P 0 8 0;0,2=39,4=0
P 3.41 3.04 11 P 0 8 0;2=7,4=1
L 3.41 3.04 3.414 3.044 8 P 0 
L 3.414 3.044 3.414 3.235 8 P 0 
P 3.582 2.856 58 P 0 8 0;0,2=2,4=0
L 3.582 2.856 3.548 2.856 8 P 0 
L 3.582 2.803 3.582 2.856 8 P 0 
P 3.582 2.803 58 P 0 8 0;0,2=2,4=0
P 3.548 2.856 9 P 0 8 0;2=26,4=1
P 3.689 2.71 63 P 0 8 0;0,2=2,4=0
P 3.5768 2.7178 11 P 0 8 0;2=7,4=1
L 3.5768 2.7178 3.6472 2.7178 8 P 0 
L 3.6472 2.7178 3.655 2.71 8 P 0 
L 3.655 2.71 3.689 2.71 8 P 0 
P 3.395 2.82 11 P 0 8 0;2=7,4=1
S P 0
OB 3.478 2.624 I
OS 3.55 2.624
OS 3.55523996063 2.61876003937
OS 3.55513996063 2.6178
OC 3.554980019685 2.615 3.579998523622 2.614975492126 N
OC 3.56 2.599969980315 3.579990059055 2.614999901575 N
OS 3.56 2.547019980315
OS 3.534 2.547019980315
OC 3.5267 2.54563996063 3.534004035433 2.527000787402 N
OS 3.52635 2.5455
OS 3.4795 2.5455
OS 3.472 2.553
OS 3.472 2.606
OS 3.4725 2.6065
OS 3.4725 2.6185
OS 3.478 2.624
OE
SE
L 3.58 2.615 3.575 2.615 8 P 0 
L 3.575 2.615 3.56 2.6 8 P 0 
L 3.56 2.6 3.525 2.6 8 P 0 
L 3.546 2.555 3.541 2.56 8 P 0 
L 3.541 2.56 3.494 2.56 8 P 0 
L 3.494 2.56 3.491 2.563 8 P 0 
L 3.491 2.563 3.491 2.594 8 P 0 
L 3.491 2.594 3.485 2.6 8 P 0 
P 3.58 2.615 11 P 0 8 0;2=8,4=0
P 3.485 2.6 11 P 0 8 0;2=7,4=1
P 3.525 2.6 11 P 0 8 0;2=7,4=1
P 3.546 2.555 58 P 0 8 0;0,2=2,4=0
P 3.491 2.563 67 P 0 8 0;0,2=19,4=0
P 3.335 2.553 58 P 0 8 0;0,2=2,4=0
P 3.335 2.589 11 P 0 8 0;2=7,4=1
L 3.335 2.589 3.335 2.553 8 P 0 
L 3.24 2.2075 3.2375 2.2075 8 P 0 
L 3.2375 2.2075 3.236 2.209 8 P 0 
L 3.236 2.209 3.201 2.209 8 P 0 
L 3.254 2.165 3.254 2.191 8 P 0 
L 3.254 2.191 3.24 2.205 8 P 0 
L 3.24 2.205 3.24 2.2075 8 P 0 
P 3.24 2.2075 11 P 0 8 0;2=7,4=1
P 3.201 2.209 63 P 0 8 0;0,2=2,4=0
P 3.254 2.165 63 P 0 8 0;0,2=2,4=0
L 4.905 2.1675 4.926 2.1465 8 P 0 
L 4.926 2.1465 4.926 2.115 8 P 0 
P 4.905 2.1675 11 P 0 8 0;2=7,4=1
P 4.926 2.115 63 P 0 8 0;0,2=2,4=0
P 4.85 2.02738996 11 P 0 8 0;2=7,4=1
P 4.965 1.975 11 P 0 8 0;2=7,4=1
P 3.49128002 1.86628002 11 P 0 8 0;2=7,4=1
L 3.49128002 1.86628002 3.48501004 1.87255 5 P 0 
L 3.48501004 1.87255 3.48501004 1.88386998 5 P 0 
L 3.48501004 1.88386998 3.49301004 1.89186998 5 P 0 
L 3.49301004 1.89186998 3.50595 1.89186998 5 P 0 
P 3.50595 1.89186998 69 P 0 8 0;0,2=55,4=0
P 4.65933002 1.66626998 9 P 0 8 0;2=4,4=1
P 4.63965 1.68595 10 P 0 8 0;0,2=5,4=0
L 4.63965 1.68595 4.65933002 1.66626998 8 P 0 
L 3.76 2.384 3.786 2.384 8 P 0 
L 3.786 2.384 3.795 2.375 8 P 0 
P 3.76 2.384 58 P 0 8 0;0,2=2,4=0
P 3.795 2.375 11 P 0 8 0;2=7,4=1
P 3.99005 2.02058996 9 P 0 8 0;2=4,4=1
L 4.00973002 2.00091004 3.99005 2.02058996 8 P 0 
P 4.00973002 2.00091004 10 P 0 8 0;0,2=5,4=0
P 4.34436998 1.86311004 9 P 0 8 0;2=4,4=1
L 4.32468996 1.84343002 4.34436998 1.86311004 8 P 0 
P 4.32468996 1.84343002 10 P 0 8 0;0,2=5,4=0
P 4.02941998 1.90248002 9 P 0 8 0;2=4,4=1
L 4.0491 1.8828 4.02941998 1.90248002 8 P 0 
P 4.0491 1.8828 10 P 0 8 0;0,2=5,4=0
P 3.855 1.96153996 9 P 0 8 0;2=4,4=1
L 3.89161004 1.96153996 3.855 1.96153996 8 P 0 
P 3.89161004 1.96153996 10 P 0 8 0;0,2=5,4=0
P 3.9113 1.86311004 9 P 0 8 0;2=4,4=1
L 3.93098002 1.84343002 3.9113 1.86311004 8 P 0 
P 3.93098002 1.84343002 10 P 0 8 0;0,2=5,4=0
P 4.06878996 1.78436998 9 P 0 8 0;2=4,4=1
L 4.08846998 1.76468996 4.06878996 1.78436998 8 P 0 
P 4.08846998 1.76468996 10 P 0 8 0;0,2=5,4=0
P 4.1869 1.82373996 9 P 0 8 0;2=4,4=1
L 4.20658002 1.80406004 4.1869 1.82373996 8 P 0 
P 4.20658002 1.80406004 10 P 0 8 0;0,2=5,4=0
S P 0
OB 4.785 2.38 I
OS 4.705 2.38
OS 4.684 2.401
OS 4.684 2.461
OS 4.687 2.464
OS 4.793 2.464
OS 4.798 2.459
OS 4.798 2.393
OS 4.785 2.38
OE
SE
S P 0
OB 4.1785 2.9725 I
OS 4.17863996063 2.97263996063
OS 4.30236003937 2.97263996063
OS 4.309 2.966
OS 4.309 2.817
OS 4.305 2.813
OS 4.274 2.813
OS 4.267 2.806
OS 4.267 2.762
OS 4.262 2.757
OS 4.18 2.757
OS 4.17356003937 2.76343996063
OC 4.173519980315 2.766230019685 4.174974507874 2.764855610236 Y
OC 4.179019980315 2.78 4.159004429134 2.780011220472 N
OS 4.179019980315 2.804
OC 4.176580019685 2.813580019685 4.158993405512 2.804000098425 N
OS 4.1785 2.8155
OS 4.1785 2.9725
OE
SE
L 3.86 2.552 3.86 2.5925 8 P 0 
P 3.86 2.5925 11 P 0 8 0;2=7,4=1
P 4.29225 2.82678996 65 P 0 8 0;0,2=53,4=0
P 4.29225 2.84646998 65 P 0 8 0;0,2=53,4=0
P 4.29225 2.86616004 65 P 0 8 0;0,2=53,4=0
P 4.29225 2.88583996 65 P 0 8 0;0,2=53,4=0
P 4.29225 2.90553002 65 P 0 8 0;0,2=53,4=0
P 4.29225 2.92521004 65 P 0 8 0;0,2=53,4=0
P 4.575 2.461 58 P 0 8 0;0,2=2,4=0
L 4.575 2.461 4.575 2.5 8 P 0 
L 4.209 2.552 4.209 2.59 8 P 0 
L 3.801 2.552 3.758 2.552 8 P 0 
P 3.758 2.552 11 P 0 8 0;2=7,4=1
P 4.209 2.59 11 P 0 8 0;2=7,4=1
L 4.15 2.552 4.209 2.552 8 P 0 
P 4.209 2.552 58 P 0 8 0;0,2=2,4=0
L 4.093 2.552 4.15 2.552 8 P 0 
P 4.15 2.552 58 P 0 8 0;0,2=2,4=0
L 4.037 2.552 4.093 2.552 8 P 0 
P 4.093 2.552 58 P 0 8 0;0,2=2,4=0
L 3.978 2.552 4.037 2.552 8 P 0 
P 4.037 2.552 58 P 0 8 0;0,2=2,4=0
L 3.919 2.552 3.978 2.552 8 P 0 
P 3.978 2.552 58 P 0 8 0;0,2=2,4=0
L 3.86 2.552 3.919 2.552 8 P 0 
P 3.919 2.552 58 P 0 8 0;0,2=2,4=0
P 3.801 2.552 58 P 0 8 0;0,2=2,4=0
L 3.801 2.552 3.86 2.552 8 P 0 
P 3.86 2.552 58 P 0 8 0;0,2=2,4=0
P 4.65933002 2.09933002 9 P 0 8 0;2=4,4=1
P 4.54121998 2.05996004 9 P 0 8 0;2=4,4=1
P 4.50185 2.17806998 9 P 0 8 0;2=4,4=1
P 4.46248002 1.90248002 9 P 0 8 0;2=4,4=1
P 4.42311004 2.02058996 9 P 0 8 0;2=4,4=1
P 4.38373996 2.1387 9 P 0 8 0;2=4,4=1
P 4.26563996 1.98121998 9 P 0 8 0;2=4,4=1
P 4.22626998 2.09933002 9 P 0 8 0;2=4,4=1
P 4.14753002 1.94185 9 P 0 8 0;2=4,4=1
P 4.10816004 2.05996004 9 P 0 8 0;2=4,4=1
P 4.06878996 2.17806998 9 P 0 8 0;2=4,4=1
P 3.95066998 2.1387 9 P 0 8 0;2=4,4=1
P 4.6987 1.98121998 9 P 0 8 0;2=4,4=1
P 4.58058996 1.94185 9 P 0 8 0;2=4,4=1
P 4.73806998 1.86311004 9 P 0 8 0;2=4,4=1
P 4.61996004 1.82373996 9 P 0 8 0;2=4,4=1
P 4.50185 1.78436998 9 P 0 8 0;2=4,4=1
P 4.187 2.792 63 P 0 8 0;0,2=2,4=0
P 4.2 2.855 71 P 0 8 0;0,2=21,4=0
P 4.2 2.936 71 P 0 8 0;0,2=21,4=0
P 4.249 2.929 11 P 0 8 0;2=1,4=1
P 4.239 2.785 11 P 0 8 0;2=1,4=1
P 4.249 2.843 11 P 0 8 0;2=1,4=1
P 4.575 2.5 11 P 0 8 0;2=7,4=1
P 4.395 2.461 58 P 0 8 0;0,2=2,4=0
L 4.395 2.461 4.395 2.5 8 P 0 
P 4.395 2.5 11 P 0 8 0;2=7,4=1
P 4.77 2.39 11 P 0 8 0;2=7,4=1
P 4.71 2.39 11 P 0 8 0;2=7,4=1
P 4.74 2.4365 28 P 0 8 0;0,2=57,4=0
L 4.48216998 1.76468996 4.50185 1.78436998 8 P 0 
P 4.48216998 1.76468996 10 P 0 8 0;0,2=5,4=0
L 4.60028002 1.80406004 4.61996004 1.82373996 8 P 0 
P 4.60028002 1.80406004 10 P 0 8 0;0,2=5,4=0
L 4.16721004 1.92216998 4.14753002 1.94185 8 P 0 
P 4.16721004 1.92216998 10 P 0 8 0;0,2=5,4=0
L 4.28531998 1.96153996 4.26563996 1.98121998 8 P 0 
P 4.28531998 1.96153996 10 P 0 8 0;0,2=5,4=0
L 4.40343002 2.00091004 4.42311004 2.02058996 8 P 0 
P 4.40343002 2.00091004 10 P 0 8 0;0,2=5,4=0
L 4.4428 1.8828 4.46248002 1.90248002 8 P 0 
P 4.4428 1.8828 10 P 0 8 0;0,2=5,4=0
L 4.56091004 1.92216998 4.58058996 1.94185 8 P 0 
P 4.56091004 1.92216998 10 P 0 8 0;0,2=5,4=0
L 4.71838996 1.84343002 4.73806998 1.86311004 8 P 0 
P 4.71838996 1.84343002 10 P 0 8 0;0,2=5,4=0
L 4.67901998 1.96153996 4.6987 1.98121998 8 P 0 
P 4.67901998 1.96153996 10 P 0 8 0;0,2=5,4=0
L 3.97035 2.11901998 3.95066998 2.1387 8 P 0 
P 3.97035 2.11901998 10 P 0 8 0;0,2=5,4=0
L 4.08846998 2.15838996 4.06878996 2.17806998 8 P 0 
P 4.08846998 2.15838996 10 P 0 8 0;0,2=5,4=0
L 4.12783996 2.04028002 4.10816004 2.05996004 8 P 0 
P 4.12783996 2.04028002 10 P 0 8 0;0,2=5,4=0
L 4.24595 2.07965 4.22626998 2.09933002 8 P 0 
P 4.24595 2.07965 10 P 0 8 0;0,2=5,4=0
L 4.36406004 2.11901998 4.38373996 2.1387 8 P 0 
P 4.36406004 2.11901998 10 P 0 8 0;0,2=5,4=0
L 4.48216998 2.15838996 4.50185 2.17806998 8 P 0 
P 4.48216998 2.15838996 10 P 0 8 0;0,2=5,4=0
L 4.52153996 2.04028002 4.54121998 2.05996004 8 P 0 
P 4.52153996 2.04028002 10 P 0 8 0;0,2=5,4=0
L 4.63965 2.07965 4.65933002 2.09933002 8 P 0 
P 4.63965 2.07965 10 P 0 8 0;0,2=5,4=0
P 4.075 2.25 11 P 0 8 0;2=7,4=1
L 3.7326 2.4724 3.735 2.47 8 P 0 
L 3.7326 2.4724 3.73191004 2.47171004 8 P 0 
L 3.73191004 2.47171004 3.71068996 2.47171004 8 P 0 
L 3.71068996 2.47171004 3.695 2.4874 8 P 0 
L 3.695 2.4874 3.695 2.5135 8 P 0 
L 3.7324 2.5135 3.7324 2.4726 8 P 0 
L 3.7324 2.4726 3.7326 2.4724 8 P 0 
P 3.695 2.5135 53 P 0 8 0;0,2=6,4=0
P 3.735 2.47 11 P 0 8 0;2=7,4=1
P 3.7324 2.5135 53 P 0 8 0;0,2=6,4=0
L 5.001 1.335 5.0395 1.335 8 P 0 
P 5.001 1.335 63 P 0 8 0;0,2=2,4=0
L 5.001 1.385 5.001 1.335 8 P 0 
P 5.001 1.385 63 P 0 8 0;0,2=2,4=0
P 5.0395 1.335 11 P 0 8 0;2=7,4=1
P 4.926 1.765 63 P 0 8 0;0,2=2,4=0
P 4.97 1.75 11 P 0 8 0;2=1,4=1
P 4.96 1.63 11 P 0 8 0;2=7,4=1
L 4.926 1.765 4.955 1.765 8 P 0 
L 4.955 1.765 4.97 1.75 8 P 0 
L 4.97 1.75 4.97 1.71 8 P 0 
L 4.97 1.71 4.9875 1.6925 8 P 0 
L 4.9875 1.6925 4.9875 1.6636 8 P 0 
L 4.9875 1.6636 4.96 1.6361 8 P 0 
L 4.96 1.6361 4.96 1.63 8 P 0 
L 4.49 3.7 4.426 3.7 8 P 0 
S P 0
OB 4.585 3.875 I
OS 4.61 3.875
OS 4.61 3.815
OS 4.625 3.8
OS 4.625 3.495
OS 4.74 3.38
OS 4.74 3.05
OS 4.665 2.975
OS 4.63825 2.975
OS 4.602430019685 3.01081003937
OC 4.59885 3.013719980315 4.586610925197 2.995005413386 N
OC 4.58836003937 3.025180019685 4.580000688976 3.006997244094 N
OS 4.58836003937 3.03613996063
OS 4.588780019685 3.036680019685
OC 4.59501003937 3.054230019685 4.565000492126 3.05500226378 N
OS 4.595030019685 3.055030019685
OS 4.620480019685 3.080480019685
OS 4.62106003937 3.0806
OC 4.645019980315 3.11 4.61500246063 3.11 N
OC 4.625 3.13831003937 4.614993602362 3.110000098425 N
OS 4.625 3.21893996063
OC 4.625019980315 3.22 4.595000688976 3.220035629921 N
OC 4.625 3.22106003937 4.595000688976 3.219964370079 N
OS 4.625 3.27
OS 4.595 3.3
OS 4.57375 3.3
OC 4.565 3.302019980315 4.564987106299 3.282002952756 N
OS 4.537 3.302019980315
OC 4.52825 3.3 4.537012893701 3.282002952756 N
OS 4.495 3.3
OS 4.48 3.315
OS 4.48 3.425
OS 4.52 3.465
OS 4.52 3.605
OS 4.475 3.65
OS 4.475 3.719
OC 4.49001003937 3.744230019685 4.460001082677 3.745003248031 N
OS 4.490030019685 3.745030019685
OS 4.52 3.775
OS 4.52 3.856980019685
OS 4.542 3.856980019685
OC 4.55208996063 3.85971003937 4.541999901575 3.876991141732 N
OS 4.55255 3.859980019685
OS 4.55828996063 3.859980019685
OS 4.55831003937 3.86
OS 4.57 3.86
OS 4.585 3.875
OE
SE
L 4.505 3.685 4.49 3.7 8 P 0 
P 6.22 1.27063002 11 P 0 8 0;2=7,4=1
P 3.839 3.846 11 P 0 8 0;2=7,4=1
P 4.384 3.824 11 P 0 8 0;2=7,4=1
L 4.384 3.79 4.384 3.824 8 P 0 
L 4.2745 3.76456998 4.31956998 3.76456998 8 P 0 
L 4.31956998 3.76456998 4.345 3.79 8 P 0 
L 4.345 3.79 4.384 3.79 8 P 0 
P 4.384 3.79 63 P 0 8 0;0,2=2,4=0
P 4.2745 3.76456998 94 P 0 8 0;0,2=10,4=0
L 5.375 3.04 5.225 3.04 8 P 0 
L 5.225 3.04 5.19 3.075 8 P 0 
L 4.935 3.504 4.935 3.475 8 P 0 
L 4.935 3.475 4.95 3.46 8 P 0 
P 4.95 3.46 11 P 0 8 0;2=7,4=1
P 4.935 3.504 58 P 0 8 0;0,2=2,4=0
P 5.94003002 1.87 11 P 0 8 0;2=7,4=1
P 6.379 1.169 11 P 0 8 0;2=7,4=1
L 6.379 1.135 6.379 1.169 8 P 0 
P 6.2655 1.0834 93 P 0 8 0;0,2=42,4=0
P 6.379 1.135 63 P 0 8 0;0,2=2,4=0
P 6.105 1.905 11 P 0 8 0;2=7,4=1
P 5.92 1.27063002 11 P 0 8 0;2=7,4=1
P 5.9945 1.27063002 107 P 0 8 0;0,2=34,4=0
P 5.88 0.965 11 P 0 8 0;2=7,4=1
L 6.421 1.02 6.421 0.965 8 P 0 
P 6.421 0.965 63 P 0 8 0;0,2=2,4=0
L 6.421 1.08 6.421 1.02 8 P 0 
P 6.421 1.02 63 P 0 8 0;0,2=2,4=0
P 6.47 1.08 11 P 0 8 0;2=7,4=1
L 6.421 1.08 6.47 1.08 8 P 0 
P 6.421 1.08 63 P 0 8 0;0,2=2,4=0
L 6.14 2.321 6.137 2.324 9 P 0 
L 6.137 2.324 6.087 2.324 9 P 0 
P 6.087 2.324 64 P 0 8 0;0,2=19,4=0
P 5.19 3.075 11 P 0 8 0;2=7,4=1
P 5.375 3.04 11 P 0 8 0;2=7,4=1
P 5.41 2.815 11 P 0 8 0;2=7,4=1
P 5.544 2.675 11 P 0 8 0;2=7,4=1
P 6.1865 2.493 11 P 0 8 0;2=7,4=1
P 6.141 2.32 58 P 0 8 0;0,2=2,4=0
P 6.141 2.364 11 P 0 8 0;2=7,4=1
P 5.85 2.265 11 P 0 8 0;2=7,4=1
P 5.89953002 2.239 63 P 0 8 0;0,2=2,4=0
P 5.62 2.5487 11 P 0 8 0;2=7,4=1
P 5.42 2.9645 11 P 0 8 0;2=7,4=1
L 5.85 2.265 5.876 2.239 8 P 0 
L 5.876 2.239 5.89953002 2.239 8 P 0 
L 6.141 2.32 6.14 2.321 9 P 0 
L 6.141 2.364 6.141 2.322 9 P 0 
L 6.141 2.322 6.14 2.321 9 P 0 
L 5.96901998 1.90865 5.96901998 1.90088996 8 P 0 
L 5.96901998 1.90088996 5.94003002 1.8719 8 P 0 
L 5.94003002 1.8719 5.94003002 1.87 8 P 0 
P 5.96901998 1.90865 58 P 0 8 0;0,2=2,4=0
P 4.645 2.985 11 P 0 8 0;2=7,4=1
L 6.2655 1.0834 6.2884 1.0834 8 P 0 
L 6.2884 1.0834 6.34 1.135 8 P 0 
L 6.34 1.135 6.379 1.135 8 P 0 
P 4.2391 3.97231004 85 P 0 8 0;0,2=0,4=0
P 4.61 3.025 11 P 0 8 0;2=7,4=1
P 4.43 3.865 9 P 0 8 0;2=26,4=1
L 4.396 3.865 4.43 3.865 8 P 0 
P 4.396 3.865 63 P 0 8 0;0,2=2,4=0
P 5.221 4.165 11 P 0 8 0;2=7,4=1
P 4.354 3.965 63 P 0 8 0;0,2=2,4=0
L 4.2391 3.97231004 4.31268996 3.97231004 6 P 0 
L 4.31268996 3.97231004 4.32 3.965 6 P 0 
L 4.32 3.965 4.354 3.965 8 P 0 
P 4.32 3.965 9 P 0 8 0;2=26,4=1
P 4.535 3.815 11 P 0 8 0;2=7,4=1
P 4.53 3.849 58 P 0 8 0;0,2=2,4=0
P 4.598 3.86 64 P 0 8 0;0,2=19,4=0
P 4.4085 3.24556998 94 P 0 8 0;0,2=10,4=0
P 4.509 3.27 63 P 0 8 0;0,2=2,4=0
L 4.509 3.27 4.48 3.27 8 P 0 
L 4.48 3.27 4.45556998 3.24556998 8 P 0 
L 4.45556998 3.24556998 4.4085 3.24556998 8 P 0 
L 4.509 3.27 4.509 3.309 8 P 0 
P 4.509 3.309 11 P 0 8 0;2=7,4=1
P 4.235 4.155 11 P 0 8 0;2=7,4=1
P 4.505 3.685 11 P 0 8 0;2=7,4=1
P 4.426 3.7 63 P 0 8 0;0,2=2,4=0
P 5.975 4.219 11 P 0 8 0;2=7,4=1
P 5.84 4.219 11 P 0 8 0;2=7,4=1
P 6.145 3.98 11 P 0 8 0;2=7,4=1
L 6.14648002 1.27063002 6.22 1.27063002 8 P 0 
P 6.14648002 1.27063002 110 P 0 8 0;0,2=35,4=0
P 4.694 0.865 63 P 0 8 0;0,2=2,4=0
P 4.694 0.785 63 P 0 8 0;0,2=2,4=0
P 4.655 0.785 11 P 0 8 0;2=7,4=1
L 4.694 0.785 4.655 0.785 8 P 0 
L 4.655 0.785 4.655 0.826 8 P 0 
L 4.655 0.826 4.694 0.865 8 P 0 
P 4.635 0.92 11 P 0 8 0;2=7,4=1
P 5.1245 0.91956998 94 P 0 8 0;0,2=10,4=0
P 5.249 0.92 63 P 0 8 0;0,2=2,4=0
P 5.249 0.99 11 P 0 8 0;2=7,4=1
L 5.249 0.92 5.159 0.92 8 P 0 
L 5.159 0.92 5.15856998 0.91956998 8 P 0 
L 5.15856998 0.91956998 5.1245 0.91956998 8 P 0 
P 5.53 1.085 11 P 0 8 0;2=7,4=1
L 5.249 0.99 5.249 0.92 8 P 0 
P 5.291 0.82 63 P 0 8 0;0,2=2,4=0
P 5.33 0.82 11 P 0 8 0;2=7,4=1
L 5.291 0.82 5.33 0.82 8 P 0 
P 5.291 0.76 63 P 0 8 0;0,2=2,4=0
P 5.265 0.675 11 P 0 8 0;2=7,4=1
L 5.265 0.675 5.28 0.69 8 P 0 
L 5.28 0.69 5.28 0.7128 8 P 0 
L 5.28 0.7128 5.291 0.7238 8 P 0 
L 5.291 0.7238 5.291 0.76 8 P 0 
P 2.964 0.702 11 P 0 8 0;2=7,4=1
L 2.9552 0.6678 2.9552 0.6212 8 P 0 
L 2.9552 0.6212 2.955 0.621 8 P 0 
P 2.848 0.63058996 70 P 0 8 0;0,2=58,4=0
L 2.848 0.63058996 2.89141004 0.63058996 7 P 0 
L 2.89141004 0.63058996 2.901 0.621 7 P 0 
L 2.901 0.621 2.955 0.621 7 P 0 
P 2.955 0.621 63 P 0 8 0;0,2=2,4=0
L 2.9552 0.6678 2.9552 0.6932 8 P 0 
L 2.9552 0.6932 2.964 0.702 8 P 0 
P 2.9552 0.6678 63 P 0 8 0;0,2=2,4=0
P 5.515 0.59596998 11 P 0 8 0;2=7,4=1
L 2.0477 0.6778 2.0504 0.6805 8 P 0 
L 2.0504 0.6805 2.0775 0.6805 8 P 0 
L 2.0775 0.6805 2.138 0.741 8 P 0 
L 2.138 0.741 2.269 0.741 8 P 0 
L 2.269 0.741 2.278 0.75 8 P 0 
L 2.278 0.75 2.28 0.75 8 P 0 
L 2.28 0.75 2.285 0.755 8 P 0 
P 2.0477 0.6778 11 P 0 8 0;2=7,4=1
P 2.285 0.79 11 P 0 8 0;2=7,4=1
P 2.285 0.755 11 P 0 8 0;2=7,4=1
L 2.0477 0.632 2.0477 0.6778 8 P 0 
P 2.0477 0.632 58 P 0 8 0;0,2=2,4=0
P 3.09 1.645 11 P 0 8 0;2=7,4=1
L 3.124 1.645 3.09 1.645 8 P 0 
P 3.124 1.645 63 P 0 8 0;0,2=2,4=0
L 1.548 0.6212 1.5815 0.6212 8 P 0 
L 1.5815 0.6212 1.6127 0.59 8 P 0 
L 1.6127 0.59 1.6622 0.59 8 P 0 
L 1.25 0.765 1.2386 0.7536 8 P 0 
L 1.2386 0.7536 1.2157 0.7536 8 P 0 
P 1.605 0.715 11 P 0 8 0;2=7,4=1
P 1.605 0.755 11 P 0 8 0;2=7,4=1
P 1.826 2.895 11 P 0 8 0;2=7,4=1
L 1.401 3.069 1.401 3.154 8 P 0 
L 1.401 3.154 1.439 3.192 8 P 0 
L 1.439 3.192 1.455 3.192 8 P 0 
P 1.401 3.069 11 P 0 8 0;2=7,4=1
P 1.455 3.192 67 P 0 8 0;0,2=19,4=0
P 2.218 2.973 58 P 0 8 0;0,2=2,4=0
P 3.159 2.434 63 P 0 8 0;0,2=2,4=0
L 3.159 2.389 3.159 2.434 8 P 0 
P 3.159 2.389 63 P 0 8 0;0,2=2,4=0
L 3.159 2.434 3.119 2.434 8 P 0 
P 3.119 2.434 11 P 0 8 0;2=7,4=1
P 2.245 3.02 9 P 0 8 0;2=26,4=1
P 2.49 2.903 11 P 0 8 0;2=7,4=1
P 2.128 2.895 9 P 0 8 0;2=26,4=1
L 2.128 2.931 2.173 2.931 8 P 0 
P 2.173 2.931 58 P 0 8 0;0,2=2,4=0
P 2.083 2.931 58 P 0 8 0;0,2=2,4=0
L 2.083 2.931 2.128 2.931 8 P 0 
P 2.128 2.931 58 P 0 8 0;0,2=2,4=0
L 2.128 2.895 2.128 2.931 8 P 0 
L 2.218 2.973 2.232 2.973 8 P 0 
L 2.232 2.973 2.247 2.988 8 P 0 
L 2.247 2.988 2.247 3.018 8 P 0 
L 2.247 3.018 2.245 3.02 8 P 0 
L 2.1734 3.0845 2.1734 3.0666 8 P 0 
L 2.1734 3.0666 2.218 3.022 8 P 0 
L 2.218 3.022 2.218 2.973 8 P 0 
P 2.1734 3.0845 50 P 0 8 0;0,2=42,4=0
P 0.08251998 3.23523996 51 P 0 8 0;0,2=41,4=0
L 0.08251998 3.23523996 0.11976004 3.23523996 8 P 0 
P 0.11976004 3.23523996 11 P 0 8 0;2=7,4=1
P 0.78 2.915 11 P 0 8 0;2=7,4=1
P 0.241 3.109 11 P 0 8 0;2=7,4=1
P 0.16 2.975 11 P 0 8 0;2=7,4=1
P 0.374 2.829 11 P 0 8 0;2=7,4=1
L 0.5459 2.6687 0.578 2.6366 8 P 0 
L 0.578 2.6366 0.578 2.611 8 P 0 
P 0.5459 2.6687 11 P 0 8 0;2=7,4=1
P 0.578 2.611 58 P 0 8 0;0,2=2,4=0
L 0.57676004 2.35866004 0.57676004 2.34823996 6 P 0 
L 0.57676004 2.34823996 0.64 2.285 6 P 0 
L 0.64 2.285 0.64 2.271 6 P 0 
P 0.674 2.271 11 P 0 8 0;2=7,4=1
L 0.64 2.271 0.674 2.271 8 P 0 
P 0.57676004 2.35866004 35 P 0 8 0;0,2=43,4=0
P 0.64 2.271 58 P 0 8 0;0,2=2,4=0
P 0.857 2.365 11 P 0 8 0;2=7,4=1
P 0.677 2.402 11 P 0 8 0;2=7,4=1
P 0.08251998 2.66436998 51 P 0 8 0;0,2=41,4=0
P 0.11963002 2.66436998 11 P 0 8 0;2=7,4=1
L 0.08251998 2.66436998 0.11963002 2.66436998 8 P 0 
P 0.51451998 2.233 58 P 0 8 0;0,2=2,4=0
P 0.51451998 2.199 11 P 0 8 0;2=7,4=1
L 0.51451998 2.233 0.51451998 2.199 7 P 0 
P 0.575 2.091 58 P 0 8 0;0,2=2,4=0
P 0.58 2.135 11 P 0 8 0;2=7,4=1
L 0.575 2.091 0.575 2.13 6 P 0 
L 0.575 2.13 0.58 2.135 6 P 0 
P 0.08251998 2.09351004 51 P 0 8 0;0,2=41,4=0
P 0.125 2.095 11 P 0 8 0;2=7,4=1
L 0.08251998 2.09351004 0.12351004 2.09351004 8 P 0 
L 0.12351004 2.09351004 0.125 2.095 8 P 0 
P 0.57676004 1.78778996 35 P 0 8 0;0,2=43,4=0
P 0.606 1.68945 58 P 0 8 0;0,2=2,4=0
L 0.606 1.68945 0.606 1.71901004 6 P 0 
L 0.606 1.71901004 0.57676004 1.74825 6 P 0 
L 0.57676004 1.74825 0.57676004 1.78778996 6 P 0 
L 0.606 1.68945 0.64445 1.68945 8 P 0 
P 0.64445 1.68945 11 P 0 8 0;2=7,4=1
P 0.884 1.549 11 P 0 8 0;2=7,4=1
P 0.883 1.639 9 P 0 8 0;2=26,4=1
P 0.514 1.65 63 P 0 8 0;0,2=2,4=0
L 0.514 1.65 0.514 1.616 8 P 0 
P 0.514 1.616 11 P 0 8 0;2=7,4=1
P 0.605 1.52 11 P 0 8 0;2=7,4=1
P 0.58 1.486 58 P 0 8 0;0,2=2,4=0
L 0.58 1.486 0.58 1.495 6 P 0 
L 0.58 1.495 0.605 1.52 6 P 0 
P 0.08251998 1.52263996 51 P 0 8 0;0,2=41,4=0
L 0.08251998 1.52263996 0.11263996 1.52263996 8 P 0 
P 0.11263996 1.52263996 11 P 0 8 0;2=7,4=1
P 0.57676004 1.21691998 35 P 0 8 0;0,2=43,4=0
P 0.625 1.126 58 P 0 8 0;0,2=2,4=0
L 0.625 1.126 0.61991998 1.126 7 P 0 
L 0.61991998 1.126 0.57676004 1.16916004 7 P 0 
L 0.57676004 1.16916004 0.57676004 1.21691998 7 P 0 
L 0.625 1.126 0.625 1.17 8 P 0 
P 0.625 1.17 11 P 0 8 0;2=7,4=1
P 0.59 0.965 11 P 0 8 0;2=1,4=1
P 0.58 0.926 58 P 0 8 0;0,2=2,4=0
L 0.59 0.965 0.58 0.955 8 P 0 
L 0.58 0.955 0.58 0.926 8 P 0 
P 0.505 1.0839 58 P 0 8 0;0,2=2,4=0
P 0.505 1.048 11 P 0 8 0;2=7,4=1
L 0.505 1.0839 0.505 1.048 8 P 0 
P 0.08251998 0.95176998 51 P 0 8 0;0,2=41,4=0
P 0.125 0.96 11 P 0 8 0;2=7,4=1
L 0.125 0.96 0.11676998 0.95176998 8 P 0 
L 0.11676998 0.95176998 0.08251998 0.95176998 8 P 0 
P 0.81338996 0.7085 46 P 0 8 0;0,2=31,4=0
L 0.81338996 0.7085 0.81338996 0.78538996 8 P 0 
L 0.81338996 0.78538996 0.821 0.793 8 P 0 
P 0.821 0.793 11 P 0 8 0;2=7,4=1
P 0.764 0.872 11 P 0 8 0;2=7,4=1
P 1.2157 0.7536 63 P 0 8 0;0,2=2,4=0
P 1.2157 0.7086 63 P 0 8 0;0,2=2,4=0
P 1.25 0.765 11 P 0 8 0;2=7,4=1
L 1.2157 0.7536 1.2157 0.7086 8 P 0 
P 1.0705 0.6536 83 P 0 8 0;0,2=6,4=0
P 1.1133 0.5981 11 P 0 8 0;2=7,4=1
L 1.1737 0.6136 1.1288 0.6136 8 P 0 
L 1.1288 0.6136 1.1133 0.5981 8 P 0 
P 1.1737 0.6136 63 P 0 8 0;0,2=2,4=0
L 1.1133 0.5981 1.0985 0.5981 8 P 0 
L 1.0985 0.5981 1.0705 0.6261 8 P 0 
L 1.0705 0.6261 1.0705 0.6536 8 P 0 
P 0.86 0.631 11 P 0 8 0;2=7,4=1
P 0.601 0.73 11 P 0 8 0;2=7,4=1
P 0.57676004 0.64606004 35 P 0 8 0;0,2=43,4=0
P 0.596 0.602 11 P 0 8 0;2=7,4=1
L 0.596 0.602 0.596 0.604 6 P 0 
L 0.596 0.604 0.57676004 0.62323996 6 P 0 
L 0.57676004 0.62323996 0.57676004 0.64606004 6 P 0 
P 1.548 0.6212 58 P 0 8 0;0,2=2,4=0
P 1.6622 0.59 97 P 0 8 0;0,2=59,4=0
L 1.548 0.6212 1.548 0.5993 8 P 0 
L 1.548 0.5993 1.5327 0.584 8 P 0 
P 1.5327 0.584 11 P 0 8 0;2=7,4=1
P 5.914 0.965 63 P 0 8 0;0,2=2,4=0
L 5.914 0.965 5.914 1.025 8 P 0 
P 5.914 1.025 63 P 0 8 0;0,2=2,4=0
P 4.6987 1.54816004 9 P 0 8 0;2=4,4=1
P 4.67901998 1.56783996 10 P 0 8 0;0,2=5,4=0
L 4.67901998 1.56783996 4.6987 1.54816004 8 P 0 
P 4.58058996 1.50878996 9 P 0 8 0;2=4,4=1
P 4.56091004 1.52846998 10 P 0 8 0;0,2=5,4=0
L 4.56091004 1.52846998 4.58058996 1.50878996 8 P 0 
P 4.14753002 1.50878996 9 P 0 8 0;2=4,4=1
P 4.16721004 1.52846998 10 P 0 8 0;0,2=5,4=0
L 4.16721004 1.52846998 4.14753002 1.50878996 8 P 0 
P 4.73806998 1.43005 9 P 0 8 0;2=4,4=1
P 4.71838996 1.44973002 10 P 0 8 0;0,2=5,4=0
L 4.71838996 1.44973002 4.73806998 1.43005 8 P 0 
P 4.61996004 1.39066998 9 P 0 8 0;2=4,4=1
P 4.60028002 1.41035 10 P 0 8 0;0,2=5,4=0
L 4.60028002 1.41035 4.61996004 1.39066998 8 P 0 
P 4.50185 1.3513 9 P 0 8 0;2=4,4=1
P 4.48216998 1.37098002 10 P 0 8 0;0,2=5,4=0
L 4.48216998 1.37098002 4.50185 1.3513 8 P 0 
P 4.46248002 1.46941998 9 P 0 8 0;2=4,4=1
P 4.4428 1.4891 10 P 0 8 0;0,2=5,4=0
L 4.4428 1.4891 4.46248002 1.46941998 8 P 0 
P 4.38373996 1.31193002 9 P 0 8 0;2=4,4=1
P 4.36406004 1.33161004 10 P 0 8 0;0,2=5,4=0
L 4.36406004 1.33161004 4.38373996 1.31193002 8 P 0 
P 4.34436998 1.43005 9 P 0 8 0;2=4,4=1
P 4.32468996 1.44973002 10 P 0 8 0;0,2=5,4=0
L 4.32468996 1.44973002 4.34436998 1.43005 8 P 0 
P 4.1869 1.39066998 9 P 0 8 0;2=4,4=1
P 4.20658002 1.41035 10 P 0 8 0;0,2=5,4=0
L 4.20658002 1.41035 4.1869 1.39066998 8 P 0 
P 4.06878996 1.3513 9 P 0 8 0;2=4,4=1
P 4.08846998 1.37098002 10 P 0 8 0;0,2=5,4=0
L 4.08846998 1.37098002 4.06878996 1.3513 8 P 0 
P 3.95066998 1.31193002 9 P 0 8 0;2=4,4=1
P 3.97035 1.33161004 10 P 0 8 0;0,2=5,4=0
L 3.97035 1.33161004 3.95066998 1.31193002 8 P 0 
L 5.0386 1.2415 5.0215 1.2415 8 P 0 
L 5.0215 1.2415 4.999 1.264 8 P 0 
L 4.999 1.264 5.0219 1.2869 8 P 0 
L 5.0219 1.2869 5.039 1.2869 8 P 0 
P 4.999 1.264 71 P 0 8 0;0,2=21,4=0
P 5.039 1.2869 11 P 0 8 0;2=7,4=1
P 5.0386 1.2415 11 P 0 8 0;2=7,4=1
L 4.625 1.17 4.625 1.16 8 P 0 
L 4.625 1.16 4.604 1.139 8 P 0 
L 4.604 1.139 4.585 1.139 8 P 0 
P 4.625 1.17 11 P 0 8 0;2=7,4=1
P 4.53 1.139 58 P 0 8 0;0,2=2,4=0
L 4.53 1.139 4.585 1.139 8 P 0 
P 4.585 1.139 58 P 0 8 0;0,2=2,4=0
P 4.485 1.005 11 P 0 8 0;2=7,4=1
P 3.69171998 1.02828002 11 P 0 8 0;2=7,4=1
P 3.6931 1.095 11 P 0 8 0;2=7,4=1
L 3.732 1.06 3.733 1.06 8 P 0 
L 3.733 1.06 3.698 1.095 8 P 0 
L 3.698 1.095 3.6931 1.095 8 P 0 
L 3.69171998 1.02828002 3.70193996 1.0385 8 P 0 
L 3.70193996 1.0385 3.7095 1.0385 8 P 0 
L 3.7095 1.0385 3.731 1.06 8 P 0 
L 3.731 1.06 3.732 1.06 8 P 0 
P 3.732 1.06 71 P 0 8 0;0,2=21,4=0
L 3.795 4.175 3.795 3.895 8 P 0 
L 3.795 3.895 3.736 3.836 8 P 0 
L 3.736 3.836 3.736 3.681 8 P 0 
L 3.736 3.681 3.66 3.605 8 P 0 
L 3.66 3.605 3.66 3.5085 8 P 0 
S P 0
OB 5.435 0.89 I
OS 5.503 0.89
OS 5.503 0.828
OS 5.524 0.807
OS 5.538 0.807
OS 5.544 0.801
OS 5.544 0.752
OS 5.552 0.744
OS 5.583 0.744
OS 5.587 0.74
OS 5.587 0.693
OS 5.585 0.691
OS 5.524 0.691
OS 5.517019980315 0.697980019685
OS 5.51688996063 0.698569980315
OC 5.499569980315 0.71588996063 5.495 0.694 N
OS 5.498980019685 0.716019980315
OS 5.425 0.79
OS 5.425 0.88
OS 5.435 0.89
OE
SE
P 6.04 3.98 11 P 0 8 0;2=7,4=1
P 5.445 0.795 11 P 0 8 0;2=8,4=0
L 5.445 0.795 5.404 0.754 8 P 0 
L 5.404 0.754 5.404 0.69 8 P 0 
P 5.404 0.69 63 P 0 8 0;0,2=2,4=0
P 5.56533002 0.69868996 75 P 0 8 0;0,2=22,4=0
P 5.527 0.792 63 P 0 8 0;0,2=2,4=0
P 5.484 0.863 71 P 0 8 0;0,2=21,4=0
P 5.494 0.816 11 P 0 8 0;2=7,4=1
P 5.443 0.871 11 P 0 8 0;2=7,4=1
P 5.56533002 0.72288002 117 P 0 8 0;0,2=23,4=0
P 5.49 0.78223002 11 P 0 8 0;2=7,4=1
P 3.795 4.175 11 P 0 8 0;2=7,4=1
P 3.66 3.5085 11 P 0 8 0;2=7,4=1
P 3.105 3.21 11 P 0 8 0;2=7,4=1
P 5.55 4.02 11 P 0 8 0;2=7,4=1
S P 0
OB 5.022 2.693 I
OS 5.068 2.693
OS 5.068 2.632
OS 5.06415 2.62815
OS 5.0637 2.628
OC 5.049980019685 2.609 5.069995964567 2.609 N
OS 5.049980019685 2.585
OC 5.05111003937 2.5784 5.06999488189 2.58503011811 N
OC 5.041619980315 2.56601003937 5.060997637795 2.560997244094 N
OS 5.04148996063 2.56548996063
OS 5.0355 2.5595
OS 5.0355 2.511
OS 5.030519980315 2.506019980315
OS 5 2.506019980315
OC 4.993980019685 2.50508996063 5.000010728346 2.486001673228 N
OS 4.993680019685 2.505
OS 4.916 2.505
OS 4.909 2.512
OS 4.909 2.549
OS 4.919 2.559
OS 4.979 2.559
OS 4.993 2.573
OS 4.993 2.664
OS 5.022 2.693
OE
SE
P 5.04833002 2.68731004 75 P 0 8 0;0,2=22,4=0
P 5.04833002 2.66311998 114 P 0 8 0;0,2=32,4=0
P 5.01 2.635 11 P 0 8 0;2=1,4=1
L 5.004 2.594 4.96 2.594 9 P 0 
P 4.96 2.594 58 P 0 8 0;0,2=2,4=0
P 4.933 2.52 67 P 0 8 0;0,2=19,4=0
P 5.014 2.534 71 P 0 8 0;0,2=21,4=0
P 5.042 2.597 63 P 0 8 0;0,2=2,4=0
P 5.04833002 2.75088002 117 P 0 8 0;0,2=23,4=0
L 5.04833002 2.74638002 5.00405 2.74638002 7 P 0 
L 5.00405 2.74638002 4.97343002 2.777 7 P 0 
P 5 2.78798996 9 P 0 8 0;2=24,4=1
L 5 2.78798996 4.98441998 2.78798996 7 P 0 
L 4.98441998 2.78798996 4.97343002 2.777 7 P 0 
P 4.97343002 2.777 33 P 0 8 0;0,2=14,4=0
L 5.226 2.762 5.24 2.748 1 P 0 
L 5.24 2.748 5.24 2.735 1 P 0 
L 5.24 2.735 5.25 2.725 1 P 0 
L 5.25 2.725 5.26956998 2.725 1 P 0 
P 5.16766998 2.72668996 75 P 0 8 0;0,2=22,4=0
L 5.16766998 2.72668996 5.19068996 2.72668996 1 P 0 
L 5.19068996 2.72668996 5.226 2.762 1 P 0 
P 5.226 2.762 9 P 0 8 0;2=24,4=1
L 5.27 2.769 5.27 2.72543002 1 P 0 
L 5.27 2.72543002 5.26956998 2.725 1 P 0 
P 5.26956998 2.725 33 P 0 8 0;0,2=14,4=0
P 5.315 2.769 58 P 0 8 0;0,2=2,4=0
L 5.315 2.769 5.27 2.769 1 P 0 
P 5.27 2.769 58 P 0 8 0;0,2=2,4=0
S P 0
OB 3.685 2.28 I
OS 3.775 2.28
OS 3.795 2.26
OS 3.795 2.175
OS 3.785 2.165
OS 3.68 2.165
OS 3.68 2.275
OS 3.685 2.28
OE
SE
P 3.682 2.205 64 P 0 8 0;0,2=19,4=0
P 3.775 2.235 11 P 0 8 0;2=7,4=1
P 3.775 2.265 11 P 0 8 0;2=1,4=1
P 3.775 2.21 11 P 0 8 0;2=7,4=1
P 3.775 2.185 11 P 0 8 0;2=7,4=1
P 4.40343002 1.76468996 10 P 0 8 0;0,2=5,4=0
L 4.40343002 1.76468996 4.42311004 1.78436998 8 P 0 
P 4.42311004 1.78436998 9 P 0 8 0;2=4,4=1
P 4.46248002 1.70563996 9 P 0 8 0;2=4,4=1
P 4.4428 1.72531998 10 P 0 8 0;0,2=5,4=0
L 4.4428 1.72531998 4.46248002 1.70563996 8 P 0 
P 4.34436998 1.78436998 9 P 0 8 0;2=4,4=1
L 4.32468996 1.76468996 4.34436998 1.78436998 8 P 0 
P 4.32468996 1.76468996 10 P 0 8 0;0,2=5,4=0
L 4.24595 1.76468996 4.22626998 1.78436998 8 P 0 
P 4.24595 1.76468996 10 P 0 8 0;0,2=5,4=0
P 4.22626998 1.78436998 9 P 0 8 0;2=4,4=1
P 4.22626998 1.66626998 9 P 0 8 0;2=4,4=1
P 4.24595 1.68595 10 P 0 8 0;0,2=5,4=0
L 4.24595 1.68595 4.22626998 1.66626998 8 P 0 
P 4.14753002 1.78436998 9 P 0 8 0;2=4,4=1
L 4.16721004 1.76468996 4.14753002 1.78436998 8 P 0 
P 4.16721004 1.76468996 10 P 0 8 0;0,2=5,4=0
P 4.02941998 1.78436998 9 P 0 8 0;2=4,4=1
L 4.0491 1.76468996 4.02941998 1.78436998 8 P 0 
P 4.0491 1.76468996 10 P 0 8 0;0,2=5,4=0
L 5.31 2.855 5.251 2.914 1 P 0 
L 5.251 2.914 4.636 2.914 1 P 0 
L 4.636 2.914 4.608 2.942 1 P 0 
L 5.315 2.811 5.315 2.85 1 P 0 
L 5.315 2.85 5.31 2.855 1 P 0 
P 5.315 2.811 58 P 0 8 0;0,2=2,4=0
P 5.765 0.98 11 P 0 8 0;2=8,4=0
P 1.385 3.875 9 P 0 8 0;2=24,4=1
P 5.31 2.855 11 P 0 8 0;2=7,4=1
P 4.608 2.942 11 P 0 8 0;2=7,4=1
P 4.25 3.81 11 P 0 8 0;2=7,4=1
S P 0
OB 0.9425 2.6485 I
OS 0.9945 2.6485
OS 1.001 2.642
OS 1.001 2.566
OS 0.993 2.558
OS 0.943 2.558
OS 0.939719980315 2.561280019685
OS 0.940080019685 2.56243996063
OC 0.941019980315 2.568480019685 0.921003444882 2.568501870079 N
OS 0.941019980315 2.592480019685
OC 0.938269980315 2.60258996063 0.921004232283 2.592464566929 N
OS 0.938 2.60306003937
OS 0.938 2.60968996063
OS 0.939019980315 2.61071003937
OS 0.939019980315 2.64501003937
OS 0.9425 2.6485
OE
SE
P 0.95248002 2.632 64 P 0 8 0;0,2=19,4=0
P 0.949 2.58048002 63 P 0 8 0;0,2=2,4=0
P 0.99 2.60025 11 P 0 8 0;2=7,4=1
P 0.985 2.56661004 11 P 0 8 0;2=7,4=1
S P 0
OB 3.54748996063 2.267480019685 I
OS 3.62751003937 2.267480019685
OS 3.63 2.265
OS 3.63 2.165
OS 3.55 2.165
OS 3.54 2.175
OS 3.54 2.26
OS 3.54748996063 2.267480019685
OE
SE
P 3.628 2.205 64 P 0 8 0;0,2=19,4=0
P 3.555 2.23 11 P 0 8 0;2=7,4=1
P 3.555 2.255 11 P 0 8 0;2=7,4=1
P 3.555 2.205 11 P 0 8 0;2=7,4=1
P 3.555 2.18 11 P 0 8 0;2=7,4=1
L 5.249 2.611 5.278 2.611 7 P 0 
S P 0
OB 5.231 2.66321003937 I
OS 5.231 2.631
OS 5.236 2.626
OS 5.250580019685 2.626
OC 5.250980019685 2.62555 5.265849114173 2.639169783465 N
OS 5.250980019685 2.597
OC 5.25696003937 2.58501003937 5.265990059055 2.597 N
OS 5.257080019685 2.584919980315
OS 5.266 2.576
OS 5.266 2.574
OS 5.27518996063 2.56481003937
OS 5.27533996063 2.5644
OC 5.29 2.54798996063 5.303498720472 2.57480246063 N
OS 5.29 2.475
OS 5.265 2.45
OS 5.225 2.45
OS 5.207 2.468
OS 5.207 2.548
OS 5.1996 2.5554
OS 5.19945 2.55576003937
OC 5.193519980315 2.563619980315 5.180997047244 2.54800492126 N
OC 5.19268996063 2.56895 5.196021161417 2.566739074803 Y
OC 5.196019980315 2.58 5.176001771654 2.580005905512 N
OS 5.196019980315 2.604
OC 5.189 2.619219980315 5.176010826772 2.604 N
OS 5.189 2.634
OS 5.181 2.642
OS 5.15 2.642
OS 5.146 2.646
OS 5.146 2.693
OS 5.148 2.695
OS 5.200919980315 2.695
OC 5.2056 2.6886 5.224016141732 2.706977952756 N
OS 5.231 2.66321003937
OE
SE
L 5.243 2.617 5.249 2.611 7 P 0 
P 5.16766998 2.68731004 75 P 0 8 0;0,2=22,4=0
P 5.16766998 2.66311998 118 P 0 8 0;0,2=23,4=0
L 5.265 2.54 5.341 2.54 8 P 0 
L 5.341 2.54 5.345 2.536 8 P 0 
P 5.345 2.536 11 P 0 8 0;2=8,4=0
P 5.22 2.47 11 P 0 8 0;2=7,4=1
P 5.254 2.47 11 P 0 8 0;2=7,4=1
P 5.239 2.571 11 P 0 8 0;2=7,4=1
P 5.243 2.617 11 P 0 8 0;2=7,4=1
P 5.278 2.611 58 P 0 8 0;0,2=2,4=0
P 5.204 2.592 63 P 0 8 0;0,2=2,4=0
P 5.228 2.521 71 P 0 8 0;0,2=21,4=0
P 5.16766998 2.707 75 P 0 8 0;0,2=22,4=0
L 5.224 2.707 5.16766998 2.707 7 P 0 
L 5.224 2.707 5.278 2.653 7 P 0 
P 5.278 2.653 58 P 0 8 0;0,2=2,4=0
L 5.278 2.653 5.328 2.653 7 P 0 
P 5.328 2.653 58 P 0 8 0;0,2=2,4=0
P 5.224 2.707 9 P 0 8 0;2=24,4=1
P 5.04833002 2.72668996 75 P 0 8 0;0,2=22,4=0
L 4.961 2.686 4.97635 2.70135 1 P 0 
L 4.97635 2.70135 4.99535 2.70135 1 P 0 
L 4.99535 2.70135 5.005 2.711 1 P 0 
L 5.04833002 2.72668996 5.02068996 2.72668996 1 P 0 
L 5.02068996 2.72668996 5.005 2.711 1 P 0 
P 5.005 2.711 9 P 0 8 0;2=24,4=1
L 4.961 2.686 4.889 2.686 1 P 0 
P 4.889 2.686 58 P 0 8 0;0,2=2,4=0
P 4.961 2.686 58 P 0 8 0;0,2=2,4=0
L 4.961 2.686 4.961 2.637 1 P 0 
L 4.961 2.637 4.96 2.636 1 P 0 
P 4.96 2.636 58 P 0 8 0;0,2=2,4=0
S P 0
OB 3.697 3.12 I
OS 3.731 3.12
OS 3.733 3.118
OS 3.733 3.11243996063
OS 3.7325 3.111869980315
OC 3.724980019685 3.092 3.754991141732 3.092 N
OC 3.746430019685 3.063230019685 3.754999015748 3.092 N
OS 3.746919980315 3.063080019685
OS 3.75 3.06
OS 3.77826003937 3.06
OC 3.779 3.059980019685 3.779170177165 3.079995374016 N
OS 3.807 3.059980019685
OC 3.80773996063 3.06 3.806829822835 3.079995374016 N
OS 3.82026003937 3.06
OC 3.821 3.059980019685 3.821170177165 3.079995374016 N
OS 3.849 3.059980019685
OC 3.84973996063 3.06 3.848829822835 3.079995374016 N
OS 3.87 3.06
OS 3.898 3.032
OS 3.898 2.985
OS 3.897 2.984
OS 3.838 2.984
OS 3.823 2.999
OS 3.82103996063 2.999
OS 3.820519980315 2.99936003937
OC 3.809 3.003019980315 3.808982677165 2.983005511811 N
OS 3.785 3.003019980315
OC 3.772980019685 2.999 3.785011909449 2.983004035433 N
OS 3.706 2.999
OS 3.703 3.002
OS 3.703 3.039
OS 3.693 3.049
OS 3.693 3.116
OS 3.697 3.12
OE
SE
P 3.708 3.099 64 P 0 8 0;0,2=19,4=0
P 3.797 3.011 58 P 0 8 0;0,2=2,4=0
P 3.732 3.018 88 P 0 8 0;0,2=21,4=0
P 3.89231004 3.00466998 36 P 0 8 0;0,2=22,4=0
P 3.86811998 3.00466998 115 P 0 8 0;0,2=32,4=0
P 3.793 3.05 9 P 0 8 0;2=9,4=1
L 3.96981004 3.04481998 3.982 3.05701004 7 P 0 
L 3.982 3.05701004 3.982 3.07956998 7 P 0 
L 3.95138002 3.00466998 3.95138002 3.02638996 7 P 0 
L 3.95138002 3.02638996 3.96981004 3.04481998 7 P 0 
P 3.96981004 3.04481998 11 P 0 8 0;2=1,4=1
P 3.95588002 3.00466998 119 P 0 8 0;0,2=23,4=0
P 3.982 3.07956998 47 P 0 8 0;0,2=14,4=0
L 3.93168996 2.88533002 3.93168996 2.84831998 1 P 0 
L 3.93168996 2.84831998 3.948 2.83201004 1 P 0 
L 3.948 2.83201004 3.948 2.813 1 P 0 
L 3.948 2.813 3.948 2.808 1 P 0 
L 3.948 2.808 3.94156998 2.80156998 1 P 0 
L 3.94156998 2.80156998 3.94156998 2.774 1 P 0 
P 3.948 2.813 11 P 0 8 0;2=1,4=1
P 3.926 2.68 63 P 0 8 0;0,2=2,4=0
L 3.926 2.68 3.926 2.725 1 P 0 
L 3.926 2.725 3.926 2.75843002 1 P 0 
L 3.926 2.75843002 3.94156998 2.774 1 P 0 
P 3.93168996 2.88533002 36 P 0 8 0;0,2=22,4=0
P 3.94156998 2.774 33 P 0 8 0;0,2=14,4=0
P 3.926 2.725 63 P 0 8 0;0,2=2,4=0
L 4.831 2.728 4.663 2.728 1 P 0 
L 4.663 2.728 4.645 2.71 1 P 0 
L 4.645 2.71 4.645 2.67 1 P 0 
L 4.645 2.67 4.62 2.645 1 P 0 
L 4.62 2.645 4.62 2.58 1 P 0 
L 4.62 2.58 4.595 2.555 1 P 0 
L 4.595 2.555 4.37 2.555 1 P 0 
L 4.37 2.555 4.27 2.655 1 P 0 
L 4.27 2.655 4.038 2.655 1 P 0 
L 4.038 2.655 3.968 2.725 1 P 0 
L 4.889 2.728 4.831 2.728 1 P 0 
P 4.831 2.728 11 P 0 8 0;2=8,4=0
P 3.968 2.725 63 P 0 8 0;0,2=2,4=0
P 4.889 2.728 58 P 0 8 0;0,2=2,4=0
P 3.55 1.415 11 P 0 8 0;2=7,4=1
P 3.525 1.415 11 P 0 8 0;2=7,4=1
P 3.5 1.415 11 P 0 8 0;2=7,4=1
P 3.475 1.415 11 P 0 8 0;2=7,4=1
L 3.781 2.775 3.816 2.775 8 P 0 
L 3.816 2.804 3.822 2.81 8 P 0 
S P 0
OB 3.802 2.802019980315 I
OC 3.786980019685 2.787 3.802 2.787 N
OS 3.786980019685 2.768880019685
OC 3.782630019685 2.7649 3.782980511811 2.768884153543 Y
OC 3.78 2.765019980315 3.779948326772 2.735002362205 N
OC 3.75168996063 2.745 3.779999901575 2.734993602362 N
OS 3.65135 2.745
OS 3.65121003937 2.745019980315
OC 3.6472 2.745319980315 3.647157677165 2.717803149606 N
OS 3.644680019685 2.745319980315
OS 3.634 2.756
OS 3.634 2.815
OS 3.642 2.823
OS 3.763 2.823
OS 3.774 2.834
OS 3.774 2.84223996063
OS 3.774180019685 2.842630019685
OC 3.776019980315 2.851 3.756002854331 2.851013090551 N
OS 3.776019980315 2.85351003937
OC 3.78083996063 2.857419980315 3.780017224409 2.853508267717 Y
OC 3.785 2.856980019685 3.785013877953 2.876998523622 N
OS 3.809 2.856980019685
OC 3.824219980315 2.864 3.809 2.876989173228 N
OS 3.839 2.864
OS 3.847 2.872
OS 3.847 2.9
OS 3.852 2.905
OS 3.898 2.905
OS 3.898 2.855
OS 3.865 2.822
OS 3.836 2.822
OS 3.831 2.817
OS 3.831 2.802419980315
OC 3.83055 2.802019980315 3.844169783465 2.787150885827 N
OS 3.802 2.802019980315
OE
SE
L 3.816 2.775 3.816 2.804 8 P 0 
P 3.655 2.795 11 P 0 8 0;2=8,4=0
L 3.78 2.774 3.781 2.775 8 P 0 
P 3.816 2.775 63 P 0 8 0;0,2=2,4=0
P 3.89231004 2.88533002 36 P 0 8 0;0,2=22,4=0
P 3.797 2.849 58 P 0 8 0;0,2=2,4=0
P 3.86811998 2.88533002 120 P 0 8 0;0,2=23,4=0
P 3.729 2.804 88 P 0 8 0;0,2=21,4=0
P 3.745 2.76 11 P 0 8 0;2=7,4=1
P 3.7 2.76 11 P 0 8 0;2=7,4=1
P 3.822 2.81 11 P 0 8 0;2=7,4=1
P 3.78 2.81 11 P 0 8 0;2=7,4=1
P 3.858 2.68 63 P 0 8 0;0,2=2,4=0
L 3.894 2.811 3.858 2.775 7 P 0 
L 3.858 2.725 3.858 2.68 8 P 0 
L 3.858 2.725 3.858 2.775 8 P 0 
L 3.912 2.88533002 3.912 2.829 7 P 0 
L 3.912 2.829 3.894 2.811 7 P 0 
P 3.894 2.811 11 P 0 8 0;2=1,4=1
P 3.912 2.88533002 36 P 0 8 0;0,2=22,4=0
P 3.858 2.775 63 P 0 8 0;0,2=2,4=0
P 3.858 2.725 63 P 0 8 0;0,2=2,4=0
L 3.891 3.092 3.835 3.092 1 P 0 
P 3.835 3.092 63 P 0 8 0;0,2=2,4=0
L 3.891 3.092 3.90635 3.07665 1 P 0 
L 3.90635 3.07665 3.90635 3.05765 1 P 0 
L 3.90635 3.05765 3.916 3.048 1 P 0 
P 3.93168996 3.00466998 36 P 0 8 0;0,2=22,4=0
L 3.93168996 3.00466998 3.93168996 3.03231004 1 P 0 
L 3.93168996 3.03231004 3.916 3.048 1 P 0 
P 3.916 3.048 9 P 0 8 0;2=9,4=1
P 3.891 3.092 63 P 0 8 0;0,2=2,4=0
S P 0
OB 5.56 2.19 I
OS 5.59 2.19
OS 5.595 2.185
OS 5.595 2.17916003937
OS 5.594980019685 2.17915
OS 5.594980019685 2.16085
OS 5.595 2.16083996063
OS 5.595 2.055
OS 5.642 2.008
OS 5.67 2.008
OS 5.67 1.9075
OS 5.525 1.9075
OS 5.525 2.025
OS 5.555 2.055
OS 5.555 2.09083996063
OS 5.555019980315 2.09085
OS 5.555019980315 2.14415
OS 5.555 2.14416003937
OS 5.555 2.16083996063
OS 5.555019980315 2.16085
OS 5.555019980315 2.17915
OS 5.555 2.17916003937
OS 5.555 2.185
OS 5.56 2.19
OE
SE
P 5.597 1.94528996 41 P 0 8 0;0,2=60,4=0
P 5.589 2.025 11 P 0 8 0;2=1,4=1
P 5.546 2.024 11 P 0 8 0;2=7,4=1
P 5.5622 2.13138002 108 P 0 8 0;0,2=61,4=0
P 5.5878 2.13138002 108 P 0 8 0;0,2=61,4=0
L 5.56516004 2.21996004 5.56516004 2.28516004 6 P 0 
L 5.56516004 2.28516004 5.6 2.32 6 P 0 
L 5.6 2.32 5.6 2.324 6 P 0 
P 5.56516004 2.21996004 31 P 0 8 0;0,2=62,4=0
P 5.6 2.324 58 P 0 8 0;0,2=2,4=0
L 5.69943002 2.233 5.717 2.233 7 P 0 
L 5.717 2.233 5.729 2.245 7 P 0 
L 5.62913002 2.21996004 5.64216998 2.233 7 P 0 
L 5.64216998 2.233 5.69943002 2.233 7 P 0 
P 5.69943002 2.233 11 P 0 8 0;2=1,4=1
P 5.62913002 2.21996004 52 P 0 8 0;0,2=63,4=0
P 5.729 2.245 63 P 0 8 0;0,2=2,4=0
L 5.465 2.324 5.465 2.29691004 1 P 0 
L 5.465 2.29691004 5.48158002 2.28033002 1 P 0 
P 5.52086998 2.21996004 52 P 0 8 0;0,2=63,4=0
L 5.52086998 2.21996004 5.52086998 2.24103996 1 P 0 
L 5.52086998 2.24103996 5.48158002 2.28033002 1 P 0 
P 5.48158002 2.28033002 9 P 0 8 0;2=24,4=1
P 5.51 2.32956998 47 P 0 8 0;0,2=14,4=0
L 5.51 2.32956998 5.47056998 2.32956998 1 P 0 
L 5.47056998 2.32956998 5.465 2.324 1 P 0 
P 5.465 2.324 58 P 0 8 0;0,2=2,4=0
P 4.50185 1.66626998 9 P 0 8 0;2=4,4=1
L 4.48216998 1.68595 4.50185 1.66626998 8 P 0 
P 4.48216998 1.68595 10 P 0 8 0;0,2=5,4=0
P 4.42311004 1.66626998 9 P 0 8 0;2=4,4=1
L 4.40343002 1.68595 4.42311004 1.66626998 8 P 0 
P 4.40343002 1.68595 10 P 0 8 0;0,2=5,4=0
P 4.38373996 1.70563996 9 P 0 8 0;2=4,4=1
L 4.36406004 1.72531998 4.38373996 1.70563996 8 P 0 
P 4.36406004 1.72531998 10 P 0 8 0;0,2=5,4=0
P 4.26563996 1.70563996 9 P 0 8 0;2=4,4=1
L 4.28531998 1.72531998 4.26563996 1.70563996 8 P 0 
P 4.28531998 1.72531998 10 P 0 8 0;0,2=5,4=0
P 4.14753002 1.66626998 9 P 0 8 0;2=4,4=1
L 4.16721004 1.68595 4.14753002 1.66626998 8 P 0 
P 4.16721004 1.68595 10 P 0 8 0;0,2=5,4=0
P 4.1869 1.70563996 9 P 0 8 0;2=4,4=1
L 4.20658002 1.72531998 4.1869 1.70563996 8 P 0 
P 4.20658002 1.72531998 10 P 0 8 0;0,2=5,4=0
P 4.50185 1.58753002 9 P 0 8 0;2=4,4=1
L 4.48216998 1.60721004 4.50185 1.58753002 8 P 0 
P 4.48216998 1.60721004 10 P 0 8 0;0,2=5,4=0
P 4.46248002 1.6269 9 P 0 8 0;2=4,4=1
L 4.4428 1.64658002 4.46248002 1.6269 8 P 0 
P 4.4428 1.64658002 10 P 0 8 0;0,2=5,4=0
P 4.46248002 1.54816004 9 P 0 8 0;2=4,4=1
L 4.4428 1.56783996 4.46248002 1.54816004 8 P 0 
P 4.4428 1.56783996 10 P 0 8 0;0,2=5,4=0
P 4.38373996 1.54816004 9 P 0 8 0;2=4,4=1
L 4.36406004 1.56783996 4.38373996 1.54816004 8 P 0 
P 4.36406004 1.56783996 10 P 0 8 0;0,2=5,4=0
P 4.42311004 1.58753002 9 P 0 8 0;2=4,4=1
L 4.40343002 1.60721004 4.42311004 1.58753002 8 P 0 
P 4.40343002 1.60721004 10 P 0 8 0;0,2=5,4=0
P 4.34436998 1.58753002 9 P 0 8 0;2=4,4=1
L 4.32468996 1.60721004 4.34436998 1.58753002 8 P 0 
P 4.32468996 1.60721004 10 P 0 8 0;0,2=5,4=0
P 4.26563996 1.54816004 9 P 0 8 0;2=4,4=1
L 4.28531998 1.56783996 4.26563996 1.54816004 8 P 0 
P 4.28531998 1.56783996 10 P 0 8 0;0,2=5,4=0
P 4.22626998 1.58753002 9 P 0 8 0;2=4,4=1
L 4.24595 1.60721004 4.22626998 1.58753002 8 P 0 
P 4.24595 1.60721004 10 P 0 8 0;0,2=5,4=0
P 4.14753002 1.58753002 9 P 0 8 0;2=4,4=1
L 4.16721004 1.60721004 4.14753002 1.58753002 8 P 0 
P 4.16721004 1.60721004 10 P 0 8 0;0,2=5,4=0
P 4.1869 1.6269 9 P 0 8 0;2=4,4=1
L 4.20658002 1.64658002 4.1869 1.6269 8 P 0 
P 4.20658002 1.64658002 10 P 0 8 0;0,2=5,4=0
P 4.1869 1.54816004 9 P 0 8 0;2=4,4=1
L 4.20658002 1.56783996 4.1869 1.54816004 8 P 0 
P 4.20658002 1.56783996 10 P 0 8 0;0,2=5,4=0
S P 0
OB 5.115 1.765 I
OS 5.185 1.765
OS 5.185 1.675
OS 5.215 1.645
OS 5.215 1.28
OS 5.22 1.275
OS 5.22 1.215
OS 5.145 1.215
OS 5.12 1.24
OS 5.12 1.605
OS 5.11236003937 1.61263996063
OS 5.11236003937 1.685
OC 5.11 1.69501003937 5.089997440945 1.685010826772 N
OS 5.11 1.76
OS 5.115 1.765
OE
SE
P 5.183 1.725 64 P 0 8 0;0,2=19,4=0
P 5.145 1.57 11 P 0 8 0;2=7,4=1
P 5.145 1.54 11 P 0 8 0;2=7,4=1
P 5.1925 1.345 78 P 0 8 0;0,2=57,4=0
P 5.207 1.24 71 P 0 8 0;0,2=21,4=0
P 5.1925 1.47 78 P 0 8 0;0,2=57,4=0
P 5.1925 1.595 78 P 0 8 0;0,2=57,4=0
P 5.145 1.44 11 P 0 8 0;2=1,4=1
P 5.145 1.48 11 P 0 8 0;2=7,4=1
P 5.145 1.51 11 P 0 8 0;2=7,4=1
L 5.76 2.465 5.745 2.48 1 P 0 
L 5.745 2.48 5.579 2.48 1 P 0 
L 5.579 2.48 5.465 2.366 1 P 0 
P 5.76 2.465 11 P 0 8 0;2=8,4=0
P 4.2136 3.5997 9 P 0 8 0;2=9,4=1
P 5.465 2.366 58 P 0 8 0;0,2=2,4=0
L 3.793 3.092 3.755 3.092 1 P 0 
P 3.755 3.092 11 P 0 8 0;2=7,4=1
P 3.793 3.092 63 P 0 8 0;0,2=2,4=0
P 3.99005 1.66626998 9 P 0 8 0;2=4,4=1
L 4.00973002 1.68595 3.99005 1.66626998 8 P 0 
P 4.00973002 1.68595 10 P 0 8 0;0,2=5,4=0
P 4.06878996 1.54816004 9 P 0 8 0;2=4,4=1
L 4.08846998 1.56783996 4.06878996 1.54816004 8 P 0 
P 4.08846998 1.56783996 10 P 0 8 0;0,2=5,4=0
P 4.06878996 1.6269 9 P 0 8 0;2=4,4=1
L 4.08846998 1.64658002 4.06878996 1.6269 8 P 0 
P 4.08846998 1.64658002 10 P 0 8 0;0,2=5,4=0
P 4.02941998 1.58753002 9 P 0 8 0;2=4,4=1
L 4.0491 1.60721004 4.02941998 1.58753002 8 P 0 
P 4.0491 1.60721004 10 P 0 8 0;0,2=5,4=0
P 3.99005 1.50878996 9 P 0 8 0;2=4,4=1
P 4.00973002 1.52846998 10 P 0 8 0;0,2=5,4=0
L 4.00973002 1.52846998 3.99005 1.50878996 8 P 0 
P 3.679 1.54228002 11 P 0 8 0;2=7,4=1
P 3.714 1.543 11 P 0 8 0;2=7,4=1
P 3.784 1.543 11 P 0 8 0;2=7,4=1
P 3.749 1.54228002 11 P 0 8 0;2=7,4=1
P 3.672 1.47 64 P 0 8 0;0,2=19,4=0
P 3.705 1.582 88 P 0 8 0;0,2=21,4=0
S P 0
OB 3.67 1.445 I
OS 3.67 1.585
OS 3.79 1.585
OS 3.795 1.58
OS 3.795 1.478119980315
OS 3.78133996063 1.46446003937
OS 3.75096003937 1.46446003937
OS 3.7315 1.445
OS 3.67 1.445
OE
SE
S P 0
OB 3.49 1.585 I
OS 3.59 1.585
OS 3.62 1.555
OS 3.62 1.44
OS 3.566619980315 1.44
OC 3.56288996063 1.44211003937 3.550011909449 1.414992913386 N
OS 3.49 1.515
OS 3.49 1.585
OE
SE
P 3.618 1.47 64 P 0 8 0;0,2=19,4=0
P 3.575 1.579 58 P 0 8 0;0,2=2,4=0
P 3.515 1.582 88 P 0 8 0;0,2=21,4=0
P 3.605 1.545 11 P 0 8 0;2=7,4=1
P 3.50085 1.543 11 P 0 8 0;2=7,4=1
P 3.53481998 1.54156998 11 P 0 8 0;2=7,4=1
P 3.57 1.542 11 P 0 8 0;2=7,4=1
S P 0
OB 5.67 1.78 I
OS 5.67 1.59
OS 5.66 1.58
OS 5.545 1.58
OS 5.48 1.645
OS 5.365 1.645
OS 5.325 1.685
OS 5.235 1.685
OS 5.235 1.785
OS 5.25 1.8
OS 5.65 1.8
OS 5.67 1.78
OE
SE
P 5.237 1.725 64 P 0 8 0;0,2=19,4=0
P 5.597 1.73071998 41 P 0 8 0;0,2=60,4=0
P 5.4227 1.724 11 P 0 8 0;2=7,4=1
P 5.3977 1.724 11 P 0 8 0;2=7,4=1
P 5.58 1.615 11 P 0 8 0;2=8,4=0
P 5.3977 1.699 11 P 0 8 0;2=7,4=1
P 5.3977 1.749 11 P 0 8 0;2=7,4=1
P 5.4227 1.699 11 P 0 8 0;2=7,4=1
P 5.41 1.794 58 P 0 8 0;0,2=2,4=0
P 5.657 1.61 71 P 0 8 0;0,2=21,4=0
P 5.39 1.663 88 P 0 8 0;0,2=21,4=0
P 5.35 1.787 88 P 0 8 0;0,2=21,4=0
P 5.654 2.4 63 P 0 8 0;0,2=2,4=0
L 5.654 2.4 5.654 2.447 8 P 0 
P 5.4352 1.7497 11 P 0 8 0;2=7,4=1
P 5.654 2.447 11 P 0 8 0;2=7,4=1
L 5.695 2.33456998 5.667 2.30656998 6 P 0 
L 5.667 2.30656998 5.667 2.275 6 P 0 
L 5.667 2.275 5.635 2.275 6 P 0 
L 5.635 2.275 5.60453002 2.24453002 6 P 0 
L 5.60453002 2.24453002 5.60453002 2.21996004 6 P 0 
L 5.695 2.33456998 5.70556998 2.324 6 P 0 
L 5.70556998 2.324 5.754 2.324 6 P 0 
P 5.667 2.275 9 P 0 8 0;2=24,4=1
P 5.60453002 2.21996004 31 P 0 8 0;0,2=62,4=0
P 5.695 2.33456998 47 P 0 8 0;0,2=14,4=0
P 5.754 2.324 58 P 0 8 0;0,2=2,4=0
L 5.64 2.32956998 5.64 2.31 6 P 0 
L 5.64 2.31 5.615 2.285 6 P 0 
L 5.615 2.285 5.6 2.285 6 P 0 
L 5.6 2.285 5.595 2.28 6 P 0 
L 5.595 2.28 5.595 2.265 6 P 0 
L 5.595 2.265 5.58483996 2.25483996 6 P 0 
L 5.58483996 2.25483996 5.58483996 2.21996004 6 P 0 
P 5.595 2.28 9 P 0 8 0;2=24,4=1
P 5.58483996 2.21996004 31 P 0 8 0;0,2=62,4=0
P 5.64 2.32956998 47 P 0 8 0;0,2=14,4=0
L 5.483 2.226 5.483 2.212 7 P 0 
L 5.483 2.212 5.5026 2.1924 7 P 0 
L 5.5026 2.1924 5.51003996 2.1924 7 P 0 
P 5.483 2.226 11 P 0 8 0;2=1,4=1
P 5.51003996 2.1924 56 P 0 8 0;0,2=64,4=0
L 5.6695 2.2 5.664 2.2 7 P 0 
L 5.664 2.2 5.6564 2.1924 7 P 0 
L 5.6564 2.1924 5.63996004 2.1924 7 P 0 
L 5.6 2.366 5.62443002 2.366 6 P 0 
L 5.62443002 2.366 5.64 2.35043002 6 P 0 
P 5.63996004 2.1924 56 P 0 8 0;0,2=64,4=0
P 5.6695 2.2 11 P 0 8 0;2=7,4=1
P 5.771 2.245 63 P 0 8 0;0,2=2,4=0
L 5.771 2.245 5.771 2.279 6 P 0 
P 5.771 2.279 9 P 0 8 0;2=24,4=1
P 5.789 2.366 11 P 0 8 0;2=7,4=1
L 5.6 2.366 5.6 2.4 8 P 0 
P 5.6 2.4 11 P 0 8 0;2=7,4=1
P 5.6 2.366 58 P 0 8 0;0,2=2,4=0
P 5.64 2.35043002 47 P 0 8 0;0,2=14,4=0
P 5.55568996 3.83456004 42 P 0 8 0;0,2=65,4=0
L 5.559 3.915 5.559 3.96 1 P 0 
L 5.559 3.96 5.559 3.969 1 P 0 
L 5.559 3.969 5.6 4.01 1 P 0 
P 5.6 4.01 11 P 0 8 0;2=8,4=0
L 5.55568996 3.88051004 5.56 3.88481998 1 P 0 
L 5.56 3.88481998 5.56 3.89563996 1 P 0 
L 5.56 3.89563996 5.559 3.89663996 1 P 0 
L 5.559 3.89663996 5.559 3.915 1 P 0 
P 5.55568996 3.88051004 9 P 0 8 0;2=9,4=1
P 5.559 3.96 63 P 0 8 0;0,2=2,4=0
L 5.55568996 3.83456004 5.55568996 3.88051004 1 P 0 
P 5.559 3.915 63 P 0 8 0;0,2=2,4=0
S P 0
OB 5.377 2.244 I
OS 5.453 2.244
OS 5.46 2.237
OS 5.46 2.19
OS 5.47 2.18
OS 5.54 2.18
OS 5.545 2.175
OS 5.545 2.165
OS 5.54 2.16
OS 5.476 2.16
OS 5.47 2.154
OS 5.47 2.129
OS 5.463 2.122
OS 5.432119980315 2.122
OS 5.425119980315 2.115
OS 5.425 2.115
OS 5.41 2.1
OS 5.36 2.1
OS 5.352 2.108
OS 5.352 2.16768996063
OS 5.366019980315 2.18171003937
OS 5.366019980315 2.184019980315
OS 5.37 2.188
OS 5.37 2.237
OS 5.377 2.244
OE
SE
S P 0
OB 5.73236003937 2.212 I
OS 5.76 2.212
OS 5.766 2.206
OS 5.766 2.151
OS 5.75 2.135
OS 5.687 2.135
OS 5.683 2.139
OS 5.683 2.144
OS 5.667 2.16
OS 5.66016003937 2.16
OS 5.66015 2.160019980315
OS 5.609980019685 2.160019980315
OS 5.605 2.165
OS 5.605 2.175
OS 5.61 2.18
OS 5.675 2.18
OS 5.68 2.185
OS 5.68 2.19071003937
OC 5.683519980315 2.199730019685 5.669501870079 2.200003641732 N
OS 5.683530019685 2.200530019685
OS 5.691269980315 2.208269980315
OS 5.6924 2.20795
OC 5.699430019685 2.206980019685 5.699438090551 2.232998917323 N
OS 5.717 2.206980019685
OC 5.73236003937 2.212 5.717000098425 2.232988976378 N
OE
SE
P 5.395 2.229 67 P 0 8 0;0,2=19,4=0
P 5.765 2.197 11 P 0 8 0;2=1,4=1
P 5.71 2.179 11 P 0 8 0;2=7,4=1
P 5.76 2.153 88 P 0 8 0;0,2=21,4=0
P 5.62913002 2.16878002 80 P 0 8 0;0,2=66,4=0
P 5.7 2.151 58 P 0 8 0;0,2=2,4=0
P 5.41 2.164 11 P 0 8 0;2=1,4=1
P 5.385 2.123 88 P 0 8 0;0,2=21,4=0
P 5.52086998 2.16878002 80 P 0 8 0;0,2=66,4=0
P 5.45 2.131 58 P 0 8 0;0,2=2,4=0
P 5.458 2.165 11 P 0 8 0;2=7,4=1
P 5.465 2.405 11 P 0 8 0;2=7,4=1
P 5.555 2.324 58 P 0 8 0;0,2=2,4=0
L 5.555 2.324 5.555 2.30356998 1 P 0 
L 5.555 2.30356998 5.53121998 2.27978996 1 P 0 
P 5.54546998 2.21996004 31 P 0 8 0;0,2=62,4=0
L 5.54546998 2.21996004 5.54546998 2.26553996 1 P 0 
L 5.54546998 2.26553996 5.53121998 2.27978996 1 P 0 
P 5.53121998 2.27978996 9 P 0 8 0;2=24,4=1
L 5.696 2.4 5.695 2.399 7 P 0 
L 5.695 2.399 5.695 2.35543002 7 P 0 
L 5.695 2.35543002 5.723 2.35543002 6 P 0 
L 5.723 2.35543002 5.73356998 2.366 6 P 0 
L 5.73356998 2.366 5.754 2.366 6 P 0 
P 5.696 2.4 63 P 0 8 0;0,2=2,4=0
P 5.754 2.366 58 P 0 8 0;0,2=2,4=0
P 5.695 2.35543002 47 P 0 8 0;0,2=14,4=0
P 3.817 0.924 9 P 0 8 0;2=24,4=1
P 3.869 0.97 63 P 0 8 0;0,2=2,4=0
L 3.869 0.97 3.811 0.97 1 P 0 
P 3.811 0.97 63 P 0 8 0;0,2=2,4=0
L 3.811 0.97 3.817 0.964 1 P 0 
L 3.817 0.964 3.817 0.924 1 P 0 
L 3.817 0.924 3.84316998 0.89783002 1 P 0 
L 3.84316998 0.89783002 3.88 0.89783002 1 P 0 
P 3.77 0.916 58 P 0 8 0;0,2=2,4=0
L 3.77 0.916 3.809 0.916 1 P 0 
L 3.809 0.916 3.817 0.924 1 P 0 
P 3.88 0.89783002 90 P 0 8 0;0,2=13,4=0
L 4.205 0.921 4.22 0.921 8 P 0 
L 4.22 0.921 4.25 0.891 8 P 0 
L 4.25 0.891 4.25 0.877 8 P 0 
L 4.314 0.90633996 4.28466004 0.877 8 P 0 
L 4.28466004 0.877 4.25 0.877 8 P 0 
P 4.25 0.877 11 P 0 8 0;2=1,4=1
P 4.205 0.921 58 P 0 8 0;0,2=2,4=0
P 4.314 0.90633996 59 P 0 8 0;0,2=12,4=0
L 5.56533002 0.679 5.51 0.679 1 P 0 
L 5.51 0.679 5.495 0.694 1 P 0 
L 5.495 0.694 5.45 0.694 1 P 0 
L 5.45 0.694 5.446 0.69 1 P 0 
P 5.446 0.69 63 P 0 8 0;0,2=2,4=0
P 5.56533002 0.679 75 P 0 8 0;0,2=22,4=0
P 5.495 0.694 9 P 0 8 0;2=24,4=1
L 5.49 0.635 5.46043002 0.635 1 P 0 
L 5.56533002 0.65931004 5.52431004 0.65931004 1 P 0 
L 5.52431004 0.65931004 5.5 0.635 1 P 0 
L 5.5 0.635 5.49 0.635 1 P 0 
P 5.49 0.635 11 P 0 8 0;2=1,4=1
P 5.46043002 0.635 33 P 0 8 0;0,2=14,4=0
P 5.56533002 0.65931004 75 P 0 8 0;0,2=22,4=0
L 5.725 0.60301004 5.75358002 0.60301004 7 P 0 
L 5.75358002 0.60301004 5.75956998 0.609 7 P 0 
L 5.68466998 0.63961998 5.72895 0.63961998 7 P 0 
L 5.72895 0.63961998 5.75956998 0.609 7 P 0 
P 5.725 0.60301004 9 P 0 8 0;2=24,4=1
P 5.68466998 0.63511998 118 P 0 8 0;0,2=23,4=0
P 5.75956998 0.609 33 P 0 8 0;0,2=14,4=0
S P 0
OB 5.662 0.693 I
OS 5.662 0.751
OS 5.679 0.768
OS 5.679 0.945
OS 5.684 0.95
OS 5.719 0.95
OS 5.727 0.942
OS 5.727 0.897
OS 5.74 0.884
OS 5.74 0.695
OS 5.736 0.691
OS 5.664 0.691
OS 5.662 0.693
OE
SE
L 5.731 0.796 5.775 0.796 6 P 0 
P 5.775 0.796 58 P 0 8 0;0,2=2,4=0
P 5.7 0.933 67 P 0 8 0;0,2=19,4=0
P 5.691 0.792 63 P 0 8 0;0,2=2,4=0
P 5.698 0.859 71 P 0 8 0;0,2=21,4=0
P 5.68466998 0.69868996 75 P 0 8 0;0,2=22,4=0
P 5.68466998 0.72288002 113 P 0 8 0;0,2=32,4=0
P 5.686 0.76 9 P 0 8 0;2=24,4=1
P 5.775 0.754 58 P 0 8 0;0,2=2,4=0
L 5.775 0.754 5.775 0.703 1 P 0 
L 5.775 0.703 5.772 0.7 1 P 0 
P 5.68466998 0.65931004 75 P 0 8 0;0,2=22,4=0
L 5.68466998 0.65931004 5.71231004 0.65931004 1 P 0 
L 5.71231004 0.65931004 5.7287 0.6757 1 P 0 
L 5.772 0.7 5.7477 0.6757 1 P 0 
L 5.7477 0.6757 5.7287 0.6757 1 P 0 
P 5.772 0.7 58 P 0 8 0;0,2=2,4=0
P 5.7287 0.6757 9 P 0 8 0;2=24,4=1
L 5.43503996 4.13778996 5.38558002 4.13778996 1 P 0 
P 5.38558002 4.13778996 11 P 0 8 0;2=1,4=1
P 5.43503996 4.13778996 24 P 0 8 0;0,2=36,4=0
L 5.485 4.11 5.51278996 4.13778996 1 P 0 
L 5.51278996 4.13778996 5.55315 4.13778996 1 P 0 
P 5.485 4.11 11 P 0 8 0;2=1,4=1
P 5.55315 4.13778996 24 P 0 8 0;0,2=36,4=0
L 5.725 4.135 5.72778996 4.13778996 1 P 0 
L 5.72778996 4.13778996 5.78936998 4.13778996 1 P 0 
P 5.725 4.135 11 P 0 8 0;2=1,4=1
P 5.78936998 4.13778996 24 P 0 8 0;0,2=36,4=0
L 5.67126004 4.13778996 5.6218 4.13778996 1 P 0 
P 5.6218 4.13778996 11 P 0 8 0;2=1,4=1
P 5.67126004 4.13778996 24 P 0 8 0;0,2=36,4=0
P 5.323 4.257 9 P 0 8 0;2=24,4=1
L 5.283 4.20953002 5.323 4.24953002 1 P 0 
L 5.323 4.24953002 5.323 4.257 1 P 0 
P 5.283 4.20953002 24 P 0 8 0;0,2=36,4=0
P 3.83 3.335 9 P 0 8 0;2=9,4=1
L 3.769 3.335 3.83 3.335 1 P 0 
P 3.769 3.335 102 P 0 8 0;0,2=39,4=0
P 3.415 3.285 9 P 0 8 0;2=9,4=1
L 3.481 3.285 3.415 3.285 1 P 0 
P 3.481 3.285 102 P 0 8 0;0,2=39,4=0
P 3.83 3.285 9 P 0 8 0;2=9,4=1
L 3.769 3.285 3.83 3.285 1 P 0 
P 3.769 3.285 102 P 0 8 0;0,2=39,4=0
P 3.415 3.385 9 P 0 8 0;2=9,4=1
L 3.481 3.385 3.415 3.385 1 P 0 
P 3.481 3.385 102 P 0 8 0;0,2=39,4=0
L 4.83871004 1.98241004 4.83871004 1.95651998 1 P 0 
L 4.83871004 1.95651998 4.84523002 1.95 1 P 0 
L 4.84523002 1.95 4.8793 1.95 1 P 0 
L 4.8793 1.95 4.884 1.9547 1 P 0 
L 4.884 1.9547 4.884 1.975 1 P 0 
L 4.71838996 2.00091004 4.72518002 2.0077 1 P 0 
L 4.72518002 2.0077 4.81341998 2.0077 1 P 0 
L 4.81341998 2.0077 4.83871004 1.98241004 1 P 0 
P 4.83871004 1.98241004 11 P 0 8 0;2=1,4=1
P 4.71838996 2.00091004 10 P 0 8 0;0,2=5,4=0
P 4.884 1.975 63 P 0 8 0;0,2=2,4=0
L 4.80288002 2.03788002 4.8079 2.03788002 1 P 0 
L 4.8079 2.03788002 4.84078002 2.005 1 P 0 
L 4.84078002 2.005 4.86 2.005 1 P 0 
L 4.86 2.005 4.88 2.025 1 P 0 
L 4.88 2.025 4.884 2.025 1 P 0 
L 4.80288002 2.03788002 4.78908002 2.02408002 1 P 0 
L 4.78908002 2.02408002 4.70218996 2.02408002 1 P 0 
L 4.70218996 2.02408002 4.67901998 2.00091004 1 P 0 
P 4.80288002 2.03788002 11 P 0 8 0;2=1,4=1
P 4.884 2.025 63 P 0 8 0;0,2=2,4=0
P 4.67901998 2.00091004 10 P 0 8 0;0,2=5,4=0
P 4.97 3.41 11 P 0 8 0;2=1,4=1
L 4.36406004 1.8828 4.38373996 1.90248002 1 P 0 
P 4.36406004 1.8828 10 P 0 8 0;0,2=5,4=0
P 4.38373996 1.90248002 9 P 0 8 0;2=4,4=1
P 4.81 3.41 11 P 0 8 0;2=7,4=1
P 4.42311004 2.09933002 9 P 0 8 0;2=15,4=1
L 4.40343002 2.07965 4.42311004 2.09933002 1 P 0 
P 4.40343002 2.07965 10 P 0 8 0;0,2=5,4=0
L 3.41796004 4.06613002 3.44976004 4.06613002 1 P 0 
L 3.44976004 4.06613002 3.48863002 4.105 1 P 0 
L 3.48863002 4.105 3.50463002 4.121 1 P 0 
L 3.50463002 4.121 3.52656998 4.121 1 P 0 
P 3.48863002 4.105 11 P 0 8 0;2=1,4=1
P 3.52656998 4.121 33 P 0 8 0;0,2=14,4=0
P 3.41796004 4.06613002 57 P 0 8 0;0,2=63,4=0
P 2.937 3.259 63 P 0 8 0;0,2=2,4=0
L 2.937 3.259 2.963 3.259 1 P 0 
L 2.963 3.259 2.987 3.235 1 P 0 
P 2.987 3.235 9 P 0 8 0;2=26,4=1
L 2.987 3.235 3.00301998 3.25101998 1 P 0 
L 3.00301998 3.25101998 3.0425 3.25101998 1 P 0 
P 3.0425 3.25101998 94 P 0 8 0;0,2=10,4=0
P 0.7595 1.642 9 P 0 8 0;2=24,4=1
L 2.987 3.27 2.983 3.27 1 P 0 
L 2.983 3.27 2.953 3.3 1 P 0 
L 2.953 3.3 2.953 3.317 1 P 0 
L 2.953 3.317 2.938 3.332 1 P 0 
P 2.987 3.27 9 P 0 8 0;2=26,4=1
L 2.987 3.27 2.99361004 3.27661004 1 P 0 
L 2.99361004 3.27661004 3.0425 3.27661004 1 P 0 
P 3.0425 3.27661004 94 P 0 8 0;0,2=10,4=0
P 2.938 3.332 63 P 0 8 0;0,2=2,4=0
P 0.761 1.544 9 P 0 8 0;2=24,4=1
P 4.54121998 1.82373996 9 P 0 8 0;2=4,4=1
P 4.79246004 1.78463996 11 P 0 8 0;2=1,4=1
P 4.52153996 1.80406004 10 P 0 8 0;0,2=5,4=0
L 4.52153996 1.80406004 4.54121998 1.82373996 1 P 0 
P 4.54121998 2.17806998 9 P 0 8 0;2=15,4=1
L 4.52153996 2.15838996 4.54121998 2.17806998 1 P 0 
P 4.52153996 2.15838996 10 P 0 8 0;0,2=5,4=0
L 1.512 0.75191004 1.56518996 0.75191004 1 P 0 
L 1.56518996 0.75191004 1.573 0.7441 1 P 0 
L 1.573 0.7441 1.573 0.73 1 P 0 
L 1.573 0.73 1.5683 0.7253 1 P 0 
L 1.5683 0.7253 1.4764 0.7253 1 P 0 
L 1.4764 0.7253 1.4717 0.7206 1 P 0 
L 1.4717 0.7206 1.4717 0.7053 1 P 0 
L 1.4717 0.7053 1.4764 0.7006 1 P 0 
L 1.4764 0.7006 1.581 0.7006 1 P 0 
L 1.581 0.7006 1.5916 0.69 1 P 0 
L 1.5916 0.69 1.5916 0.6447 1 P 0 
L 1.5916 0.6447 1.5963 0.64 1 P 0 
L 1.5963 0.64 1.6622 0.64 1 P 0 
P 0.955 1.455 11 P 0 8 0;2=1,4=1
P 1.512 0.75191004 11 P 0 8 0;2=7,4=1
P 1.6622 0.64 97 P 0 8 0;0,2=59,4=0
P 1.8091 0.6339 9 P 0 8 0;2=24,4=1
L 1.8091 0.6339 1.8152 0.64 1 P 0 
L 1.8152 0.64 1.8832 0.64 1 P 0 
L 1.459 0.752 1.485 0.778 1 P 0 
L 1.485 0.778 1.7024 0.778 1 P 0 
L 1.7024 0.778 1.7724 0.708 1 P 0 
L 1.7724 0.708 1.7724 0.6706 1 P 0 
L 1.7724 0.6706 1.8091 0.6339 1 P 0 
P 1.8832 0.64 97 P 0 8 0;0,2=59,4=0
P 1.459 0.752 9 P 0 8 0;2=26,4=1
P 0.905 1.445 11 P 0 8 0;2=7,4=1
P 2.40508002 0.731 9 P 0 8 0;2=26,4=1
L 4.08846998 1.68595 4.06878996 1.66626998 0 P 0 
P 4.06878996 1.66626998 9 P 0 8 0;2=67,4=1
P 4.08846998 1.68595 10 P 0 8 0;0,2=5,4=0
P 2.40508002 0.699 9 P 0 8 0;2=26,4=1
L 4.0491 1.68595 4.02941998 1.66626998 0 P 0 
P 4.02941998 1.66626998 9 P 0 8 0;2=67,4=1
P 4.0491 1.68595 10 P 0 8 0;0,2=5,4=0
L 4.414 0.90633996 4.414 0.90906004 0 P 0 
A 4.414 0.90906004 4.41261998 0.91238002 4.40930246 0.90905413 0 P 0 N
L 4.41261998 0.91238002 4.39948996 0.92551004 0 P 0 
A 4.39948996 0.92551004 4.3953 0.93561998 4.4095999 0.93562313 0 P 0 Y
L 4.3953 0.93561998 4.3953 0.94405 0 P 0 
A 4.3953 0.94405 4.39971998 0.95471998 4.41038888 0.9440499 0 P 0 Y
L 4.39971998 0.95471998 4.418 0.973 0 P 0 
P 4.414 0.90633996 59 P 0 8 0;0,2=12,4=0
L 4.418 0.973 4.40093002 0.99006998 0 P 0 
A 4.40093002 0.99006998 4.3975 0.99835 4.40920896 0.99835 0 P 0 Y
L 4.3975 0.99835 4.3975 1.00641998 0 P 0 
A 4.3975 1.00641998 4.40321998 1.02021998 4.41700689 1.00641998 0 P 0 Y
L 4.40321998 1.02021998 4.414 1.031 0 P 0 
P 4.414 1.031 58 P 0 8 0;0,2=2,4=0
P 4.418 0.973 63 P 0 8 0;0,2=2,4=0
L 4.364 0.90633996 4.364 0.91056004 0 P 0 
A 4.364 0.91056004 4.36643996 0.91643996 4.37231782 0.91055463 0 P 0 Y
L 4.36643996 0.91643996 4.37928002 0.92928002 0 P 0 
A 4.37928002 0.92928002 4.3833 0.93513002 4.36548396 0.94306654 0 P 0 N
A 4.3833 0.93513002 4.3833 0.93561004 4.40960217 0.93536998 0 P 0 Y
L 4.3833 0.93561004 4.3833 0.95121004 0 P 0 
A 4.3833 0.95121004 4.38153996 0.95546004 4.37728858 0.95120994 0 P 0 N
L 4.38153996 0.95546004 4.364 0.973 0 P 0 
L 4.364 0.973 4.37978002 0.98878002 0 P 0 
A 4.37978002 0.98878002 4.3855 1.00258002 4.36599311 1.00257992 0 P 0 N
L 4.3855 1.00258002 4.3855 1.00641998 0 P 0 
A 4.3855 1.00641998 4.37978002 1.02021998 4.36599311 1.00641998 0 P 0 N
L 4.37978002 1.02021998 4.369 1.031 0 P 0 
P 4.369 1.031 58 P 0 8 0;0,2=2,4=0
P 4.364 0.90633996 59 P 0 8 0;0,2=12,4=0
P 4.364 0.973 63 P 0 8 0;0,2=2,4=0
L 4.059 0.97 4.04571998 0.98328002 0 P 0 
A 4.04571998 0.98328002 4.04 0.99708002 4.05950689 0.99707992 0 P 0 Y
L 4.04 0.99708002 4.04 1.00591998 0 P 0 
A 4.04 1.00591998 4.04571998 1.01971998 4.05950689 1.00591998 0 P 0 Y
L 4.04571998 1.01971998 4.055 1.029 0 P 0 
P 4.055 1.029 58 P 0 8 0;0,2=2,4=0
P 4.08 0.89783002 90 P 0 8 0;0,2=13,4=0
L 4.08 0.89783002 4.045 0.89783002 0 P 0 
A 4.045 0.89783002 4.03653996 0.90628996 4.0449999 0.90628996 0 P 0 Y
L 4.03653996 0.90628996 4.03653996 0.93946004 0 P 0 
A 4.03653996 0.93946004 4.04226004 0.95326004 4.05604685 0.93945994 0 P 0 Y
L 4.04226004 0.95326004 4.059 0.97 0 P 0 
P 4.059 0.97 63 P 0 8 0;0,2=2,4=0
L 4.006 0.97 4.01828002 0.98228002 0 P 0 
A 4.01828002 0.98228002 4.024 0.99608002 4.00449311 0.99607992 0 P 0 N
L 4.024 0.99608002 4.024 1.00691998 0 P 0 
A 4.024 1.00691998 4.01828002 1.02071998 4.00449311 1.00691998 0 P 0 N
L 4.01828002 1.02071998 4.01 1.029 0 P 0 
P 4.01 1.029 58 P 0 8 0;0,2=2,4=0
P 3.98 0.89783002 90 P 0 8 0;0,2=13,4=0
L 3.98 0.89783002 4.02 0.89783002 0 P 0 
A 4.02 0.89783002 4.02453996 0.90236998 4.02 0.90236998 0 P 0 N
L 4.02453996 0.90236998 4.02453996 0.94338002 0 P 0 
A 4.02453996 0.94338002 4.01881998 0.95718002 4.00503317 0.94338002 0 P 0 N
L 4.01881998 0.95718002 4.006 0.97 0 P 0 
P 4.006 0.97 63 P 0 8 0;0,2=2,4=0
L 4.414 1.073 4.40135 1.08565 0 P 0 
L 4.40135 1.08565 4.3995 1.08751004 0 P 0 
A 4.3995 1.08751004 4.3976 1.09208002 4.40406644 1.09208848 0 P 0 Y
L 4.3976 1.09208002 4.3976 1.10143002 0 P 0 
A 4.3976 1.10143002 4.39948996 1.10598996 4.40404596 1.10142992 0 P 0 Y
L 4.39948996 1.10598996 4.4165 1.123 0 P 0 
L 4.4165 1.123 4.40003996 1.13946004 0 P 0 
A 4.40003996 1.13946004 4.398 1.14438996 4.40497707 1.14438996 0 P 0 Y
L 4.398 1.14438996 4.398 1.15386998 0 P 0 
A 4.398 1.15386998 4.39915 1.15663996 4.40191102 1.15386988 0 P 0 Y
L 4.39915 1.15663996 4.4085 1.16598996 0 P 0 
P 4.4085 1.16598996 9 P 0 8 0;2=26,4=1
P 4.414 1.073 58 P 0 8 0;0,2=2,4=0
P 4.4165 1.123 63 P 0 8 0;0,2=2,4=0
P 4.46248002 1.43005 9 P 0 8 0;2=67,4=1
P 4.4428 1.44973002 10 P 0 8 0;0,2=5,4=0
L 4.4428 1.44973002 4.46248002 1.43005 0 P 0 
L 4.3665 1.123 4.38385 1.10563996 0 P 0 
A 4.38385 1.10563996 4.3856 1.10143002 4.37964311 1.10142244 0 P 0 Y
L 4.3856 1.10143002 4.3856 1.09208002 0 P 0 
A 4.3856 1.09208002 4.38385 1.08783996 4.37960689 1.09207234 0 P 0 Y
L 4.38385 1.08783996 4.38125 1.08525 0 P 0 
L 4.38125 1.08525 4.369 1.073 0 P 0 
L 4.3665 1.123 4.38485 1.14135 0 P 0 
A 4.38485 1.14135 4.386 1.14411998 4.38208898 1.14411998 0 P 0 N
L 4.386 1.14411998 4.386 1.1536 0 P 0 
A 4.386 1.1536 4.38396004 1.15853002 4.37902293 1.1536 0 P 0 N
L 4.38396004 1.15853002 4.3765 1.16598996 0 P 0 
P 4.3765 1.16598996 9 P 0 8 0;2=26,4=1
P 4.369 1.073 58 P 0 8 0;0,2=2,4=0
P 4.3665 1.123 63 P 0 8 0;0,2=2,4=0
P 4.50185 1.43005 9 P 0 8 0;2=67,4=1
P 4.48216998 1.44973002 10 P 0 8 0;0,2=5,4=0
L 4.48216998 1.44973002 4.50185 1.43005 0 P 0 
A 4.0485 1.16098996 4.038 1.13563996 4.0738501 1.13564035 0 P 0 N
L 4.038 1.13563996 4.038 1.09586004 0 P 0 
A 4.038 1.09586004 4.04356004 1.08243996 4.05697569 1.09585994 0 P 0 N
L 4.04356004 1.08243996 4.055 1.071 0 P 0 
P 4.055 1.071 58 P 0 8 0;0,2=2,4=0
P 4.0485 1.16098996 9 P 0 8 0;2=26,4=1
L 4.08846998 1.52846998 4.06878996 1.50878996 0 P 0 
P 4.06878996 1.50878996 9 P 0 8 0;2=67,4=1
P 4.08846998 1.52846998 10 P 0 8 0;0,2=5,4=0
A 4.0165 1.16098996 4.026 1.13805 3.99355965 1.13805266 0 P 0 Y
L 4.026 1.13805 4.026 1.09508002 0 P 0 
A 4.026 1.09508002 4.02028002 1.08128002 4.00649311 1.09507992 0 P 0 Y
L 4.02028002 1.08128002 4.01 1.071 0 P 0 
P 4.01 1.071 58 P 0 8 0;0,2=2,4=0
P 4.0165 1.16098996 9 P 0 8 0;2=26,4=1
L 4.0491 1.52846998 4.02941998 1.50878996 0 P 0 
P 4.02941998 1.50878996 9 P 0 8 0;2=67,4=1
P 4.0491 1.52846998 10 P 0 8 0;0,2=5,4=0
L 4.884 2.115 4.83 2.115 1 P 0 
L 4.83 2.115 4.82 2.125 1 P 0 
L 4.884 2.115 4.884 2.07 1 P 0 
P 4.82 2.125 11 P 0 8 0;2=8,4=0
P 4.884 2.115 63 P 0 8 0;0,2=2,4=0
P 4.884 2.07 63 P 0 8 0;0,2=2,4=0
P 4.38373996 1.78436998 9 P 0 8 0;2=4,4=1
L 4.36406004 1.76468996 4.38373996 1.78436998 1 P 0 
P 4.36406004 1.76468996 10 P 0 8 0;0,2=5,4=0
P 3.54663996 1.04706998 9 P 0 8 0;2=26,4=1
L 3.259 2.106 3.26268002 2.10231004 0 P 0 
A 3.26268002 2.10231004 3.29 2.091 3.28999242 2.12963317 0 P 0 N
L 3.29 2.091 3.33 2.091 0 P 0 
A 3.33 2.091 3.367 2.054 3.33 2.054 0 P 0 Y
L 3.367 2.054 3.367 1.36308002 0 P 0 
A 3.367 1.36308002 3.3784 1.33558002 3.40588829 1.36308799 0 P 0 N
L 3.3784 1.33558002 3.53005 1.18393996 0 P 0 
A 3.53005 1.18393996 3.535 1.17193996 3.51802982 1.17196063 0 P 0 Y
L 3.535 1.17193996 3.535 1.06656998 0 P 0 
A 3.535 1.06656998 3.54055 1.05316998 3.55395157 1.06656988 0 P 0 N
L 3.54055 1.05316998 3.54663996 1.04708002 0 P 0 
L 3.54663996 1.04708002 3.54663996 1.04706998 0 P 0 
P 4.6987 1.46941998 9 P 0 8 0;2=67,4=1
L 4.67901998 1.4891 4.6987 1.46941998 0 P 0 
P 4.67901998 1.4891 10 P 0 8 0;0,2=5,4=0
P 3.259 2.106 58 P 0 8 0;0,2=2,4=0
P 3.21 2.11 63 P 0 8 0;0,2=2,4=0
L 3.259 2.106 3.24733002 2.09433002 0 P 0 
A 3.24733002 2.09433002 3.23688996 2.09 3.23688317 2.10476722 0 P 0 Y
L 3.23688996 2.09 3.23611004 2.09 0 P 0 
A 3.23611004 2.09 3.22566998 2.09433002 3.23611673 2.10476722 0 P 0 Y
L 3.22566998 2.09433002 3.21 2.11 0 P 0 
P 3.51463996 1.04706998 9 P 0 8 0;2=26,4=1
L 3.259 2.064 3.26268002 2.06768996 0 P 0 
A 3.26268002 2.06768996 3.29 2.079 3.28999242 2.04036683 0 P 0 Y
L 3.29 2.079 3.33 2.079 0 P 0 
A 3.33 2.079 3.355 2.054 3.33 2.054 0 P 0 Y
L 3.355 2.054 3.355 1.36308002 0 P 0 
A 3.355 1.36308002 3.36991004 1.32708996 3.40589163 1.36307992 0 P 0 N
L 3.36991004 1.32708996 3.52155 1.17545 0 P 0 
A 3.52155 1.17545 3.523 1.17193996 3.51803435 1.17194311 0 P 0 Y
L 3.523 1.17193996 3.523 1.06096004 0 P 0 
A 3.523 1.06096004 3.51908996 1.05151998 3.50964941 1.06095994 0 P 0 Y
L 3.51908996 1.05151998 3.51463996 1.04706998 0 P 0 
P 4.73806998 1.46941998 9 P 0 8 0;2=67,4=1
L 4.71838996 1.4891 4.73806998 1.46941998 0 P 0 
P 4.71838996 1.4891 10 P 0 8 0;0,2=5,4=0
P 3.259 2.064 58 P 0 8 0;0,2=2,4=0
P 3.21 2.06 63 P 0 8 0;0,2=2,4=0
L 3.259 2.064 3.25071998 2.07228002 0 P 0 
A 3.25071998 2.07228002 3.23691998 2.078 3.23691998 2.05849311 0 P 0 N
L 3.23691998 2.078 3.23608002 2.078 0 P 0 
A 3.23608002 2.078 3.22228002 2.07228002 3.23607992 2.05849311 0 P 0 N
L 3.22228002 2.07228002 3.21 2.06 0 P 0 
P 3.44998996 1.085 9 P 0 8 0;2=26,4=1
L 3.259 2.011 3.26353996 2.00646998 0 P 0 
A 3.26353996 2.00646998 3.2888 1.996 3.28880827 2.03172648 0 P 0 N
L 3.2888 1.996 3.3 1.996 0 P 0 
A 3.3 1.996 3.32806004 1.96793996 3.3 1.96793996 0 P 0 Y
L 3.32806004 1.96793996 3.32806004 1.32553996 0 P 0 
A 3.32806004 1.32553996 3.32921004 1.32276998 3.33196457 1.3255372 0 P 0 N
L 3.32921004 1.32276998 3.43428996 1.21768996 0 P 0 
A 3.43428996 1.21768996 3.44 1.20388996 3.42048848 1.20389793 0 P 0 Y
L 3.44 1.20388996 3.44 1.10168996 0 P 0 
A 3.44 1.10168996 3.44473002 1.09026998 3.45615108 1.10168996 0 P 0 N
L 3.44473002 1.09026998 3.44998996 1.08501004 0 P 0 
L 3.44998996 1.08501004 3.44998996 1.085 0 P 0 
P 4.73806998 1.39066998 9 P 0 8 0;2=67,4=1
L 4.71838996 1.41035 4.73806998 1.39066998 0 P 0 
P 4.71838996 1.41035 10 P 0 8 0;0,2=5,4=0
P 3.259 2.011 58 P 0 8 0;0,2=2,4=0
P 3.21 2.015 63 P 0 8 0;0,2=2,4=0
L 3.259 2.011 3.24733002 1.99933002 0 P 0 
A 3.24733002 1.99933002 3.23688996 1.995 3.23688317 2.00976722 0 P 0 Y
L 3.23688996 1.995 3.23611004 1.995 0 P 0 
A 3.23611004 1.995 3.22566998 1.99933002 3.23611673 2.00976722 0 P 0 Y
L 3.22566998 1.99933002 3.21 2.015 0 P 0 
P 3.41798996 1.085 9 P 0 8 0;2=26,4=1
L 3.259 1.969 3.26353996 1.97353002 0 P 0 
A 3.26353996 1.97353002 3.28878996 1.984 3.28880827 1.94827352 0 P 0 Y
L 3.28878996 1.984 3.3 1.984 0 P 0 
A 3.3 1.984 3.31606004 1.96793996 3.3 1.96793996 0 P 0 Y
L 3.31606004 1.96793996 3.31606004 1.32555 0 P 0 
A 3.31606004 1.32555 3.32071998 1.31426998 3.33197136 1.32552057 0 P 0 N
L 3.32071998 1.31426998 3.33345 1.30153996 0 P 0 
A 3.33345 1.30153996 3.33345 1.2983 3.33183002 1.29991998 0 P 0 Y
L 3.33345 1.2983 3.33343996 1.29828996 0 P 0 
A 3.33343996 1.29828996 3.33343996 1.29505 3.33506004 1.29666998 0 P 0 N
L 3.33343996 1.29505 3.34123996 1.28726004 0 P 0 
A 3.34123996 1.28726004 3.34448002 1.28726004 3.34285994 1.28888002 0 P 0 N
L 3.34448002 1.28726004 3.34448996 1.28726998 0 P 0 
A 3.34448996 1.28726998 3.34773002 1.28726998 3.34610994 1.28565 0 P 0 Y
L 3.34773002 1.28726998 3.35553002 1.27948002 0 P 0 
A 3.35553002 1.27948002 3.35553002 1.27623996 3.35391004 1.27785994 0 P 0 Y
L 3.35553002 1.27623996 3.35551998 1.27623002 0 P 0 
A 3.35551998 1.27623002 3.35551998 1.27298996 3.35713996 1.27460994 0 P 0 N
L 3.35551998 1.27298996 3.36331998 1.2652 0 P 0 
A 3.36331998 1.2652 3.36656004 1.2652 3.36493996 1.26681998 0 P 0 N
L 3.36656004 1.2652 3.36656998 1.26521004 0 P 0 
A 3.36656998 1.26521004 3.36981004 1.26521004 3.36818996 1.26358996 0 P 0 Y
L 3.36981004 1.26521004 3.4258 1.2092 0 P 0 
A 3.4258 1.2092 3.428 1.20388996 3.42049183 1.20388996 0 P 0 Y
L 3.428 1.20388996 3.428 1.18406004 0 P 0 
A 3.428 1.18406004 3.4258 1.18186004 3.4258 1.18406004 0 P 0 Y
A 3.4258 1.18186004 3.4236 1.17966004 3.4258 1.17966004 0 P 0 N
L 3.4236 1.17966004 3.4236 1.16846004 0 P 0 
A 3.4236 1.16846004 3.4258 1.16626004 3.4258 1.16846004 0 P 0 N
A 3.4258 1.16626004 3.428 1.16406004 3.4258 1.16406004 0 P 0 Y
L 3.428 1.16406004 3.428 1.1017 0 P 0 
A 3.428 1.1017 3.42326998 1.09028002 3.41184892 1.1017 0 P 0 Y
L 3.42326998 1.09028002 3.41798996 1.085 0 P 0 
P 4.73806998 1.3513 9 P 0 8 0;2=67,4=1
L 4.71838996 1.37098002 4.73806998 1.3513 0 P 0 
P 4.71838996 1.37098002 10 P 0 8 0;0,2=5,4=0
P 3.259 1.969 58 P 0 8 0;0,2=2,4=0
P 3.21 1.965 63 P 0 8 0;0,2=2,4=0
L 3.259 1.969 3.25071998 1.97728002 0 P 0 
A 3.25071998 1.97728002 3.23691998 1.983 3.23691998 1.96349311 0 P 0 N
L 3.23691998 1.983 3.23608002 1.983 0 P 0 
A 3.23608002 1.983 3.22228002 1.97728002 3.23607992 1.96349311 0 P 0 N
L 3.22228002 1.97728002 3.21 1.965 0 P 0 
P 3.445 1.815 11 P 0 8 0;2=7,4=1
P 4.58058996 1.90248002 9 P 0 8 0;2=4,4=1
L 4.56091004 1.8828 4.58058996 1.90248002 1 P 0 
P 4.56091004 1.8828 10 P 0 8 0;0,2=5,4=0
L 4.785 3.46 4.785 3.504 1 P 0 
P 4.785 3.504 58 P 0 8 0;0,2=2,4=0
P 4.65933002 1.94185 9 P 0 8 0;2=4,4=1
L 4.63965 1.92216998 4.65933002 1.94185 1 P 0 
P 4.63965 1.92216998 10 P 0 8 0;0,2=5,4=0
P 4.785 3.46 11 P 0 8 0;2=1,4=1
L 3.93098002 1.72531998 3.9113 1.70563996 8 P 0 
P 3.93098002 1.72531998 10 P 0 8 0;0,2=5,4=0
P 3.9113 1.70563996 9 P 0 8 0;2=4,4=1
P 3.674 1.744 11 P 0 8 0;2=7,4=1
P 3.95066998 1.58753002 9 P 0 8 0;2=4,4=1
L 3.97035 1.60721004 3.95066998 1.58753002 8 P 0 
P 3.97035 1.60721004 10 P 0 8 0;0,2=5,4=0
P 3.9113 1.54816004 9 P 0 8 0;2=4,4=1
L 3.93098002 1.56783996 3.9113 1.54816004 8 P 0 
P 3.93098002 1.56783996 10 P 0 8 0;0,2=5,4=0
P 3.9113 1.6269 9 P 0 8 0;2=4,4=1
L 3.93098002 1.64658002 3.9113 1.6269 8 P 0 
P 3.93098002 1.64658002 10 P 0 8 0;0,2=5,4=0
L 3.97035 1.44973002 3.95066998 1.43005 8 P 0 
P 3.95066998 1.43005 9 P 0 8 0;2=4,4=1
P 3.97035 1.44973002 10 P 0 8 0;0,2=5,4=0
P 3.9113 1.46941998 9 P 0 8 0;2=4,4=1
P 3.93098002 1.4891 10 P 0 8 0;0,2=5,4=0
L 3.93098002 1.4891 3.9113 1.46941998 8 P 0 
P 3.82 1.42 11 P 0 8 0;2=1,4=1
P 3.79 1.41 11 P 0 8 0;2=7,4=1
P 3.74 1.41 11 P 0 8 0;2=7,4=1
P 3.765 1.41 11 P 0 8 0;2=7,4=1
L 4.959 1.385 4.9097 1.385 1 P 0 
P 4.54121998 1.6269 9 P 0 8 0;2=4,4=1
L 4.959 1.43 4.959 1.385 1 P 0 
L 4.52153996 1.64658002 4.54121998 1.6269 1 P 0 
P 4.52153996 1.64658002 10 P 0 8 0;0,2=5,4=0
P 4.959 1.43 63 P 0 8 0;0,2=2,4=0
P 4.9097 1.385 9 P 0 8 0;2=24,4=1
P 4.959 1.385 63 P 0 8 0;0,2=2,4=0
P 4.54121998 1.66626998 9 P 0 8 0;2=4,4=1
L 4.54121998 1.66626998 4.52373996 1.68373996 1 P 0 
L 4.52373996 1.68373996 4.52153996 1.68595 1 P 0 
P 4.52153996 1.68595 10 P 0 8 0;0,2=5,4=0
P 4.84 1.66 11 P 0 8 0;2=1,4=1
L 4.884 1.72 4.815 1.72 1 P 0 
L 4.815 1.72 4.81 1.725 1 P 0 
L 4.81 1.725 4.79 1.745 1 P 0 
L 4.79 1.745 4.54121998 1.745 1 P 0 
L 4.54121998 1.745 4.52153996 1.72531998 1 P 0 
P 4.81 1.725 11 P 0 8 0;2=1,4=1
P 4.52153996 1.72531998 10 P 0 8 0;0,2=5,4=0
P 4.884 1.72 63 P 0 8 0;0,2=2,4=0
L 4.884 1.72 4.884 1.765 1 P 0 
P 4.884 1.765 63 P 0 8 0;0,2=2,4=0
P 3.375 1.194 9 P 0 8 0;2=26,4=1
L 4.5413 1.22166998 4.54911004 1.21386004 0 P 0 
A 4.54911004 1.21386004 4.551 1.2093 4.54455404 1.2093 0 P 0 Y
L 4.551 1.2093 4.551 1.20586004 0 P 0 
A 4.551 1.20586004 4.54826998 1.19926998 4.5416811 1.20585994 0 P 0 Y
L 4.54826998 1.19926998 4.53 1.181 0 P 0 
P 4.5413 1.22166998 9 P 0 8 0;2=26,4=1
P 4.53 1.181 58 P 0 8 0;0,2=2,4=0
P 4.61996004 1.31193002 9 P 0 8 0;2=67,4=1
P 4.60028002 1.33161004 10 P 0 8 0;0,2=5,4=0
L 4.60028002 1.33161004 4.61996004 1.31193002 0 P 0 
L 3.165 1.8 3.17896998 1.78603002 0 P 0 
A 3.17896998 1.78603002 3.19111004 1.781 3.19110994 1.79816506 0 P 0 N
L 3.19111004 1.781 3.24591004 1.781 0 P 0 
A 3.24591004 1.781 3.25971004 1.77528996 3.24591801 1.76148848 0 P 0 Y
L 3.25971004 1.77528996 3.26428996 1.77071004 0 P 0 
A 3.26428996 1.77071004 3.27 1.75691004 3.25048848 1.75691801 0 P 0 Y
L 3.27 1.75691004 3.27 1.2281 0 P 0 
A 3.27 1.2281 3.27221004 1.22278996 3.27750354 1.22810797 0 P 0 N
L 3.27221004 1.22278996 3.30778996 1.18721004 0 P 0 
A 3.30778996 1.18721004 3.3131 1.185 3.31310797 1.19250354 0 P 0 N
L 3.3131 1.185 3.36 1.185 0 P 0 
A 3.36 1.185 3.37021998 1.18923002 3.3599999 1.19946112 0 P 0 N
L 3.37021998 1.18923002 3.37498996 1.194 0 P 0 
L 3.37498996 1.194 3.375 1.194 0 P 0 
P 3.165 1.8 63 P 0 8 0;0,2=2,4=0
P 3.375 1.162 9 P 0 8 0;2=26,4=1
L 4.5733 1.22166998 4.56415 1.21251998 0 P 0 
A 4.56415 1.21251998 4.563 1.20975 4.56691102 1.2097499 0 P 0 N
L 4.563 1.20975 4.563 1.20573002 0 P 0 
A 4.563 1.20573002 4.56493002 1.20106998 4.56959085 1.20572992 0 P 0 N
L 4.56493002 1.20106998 4.585 1.181 0 P 0 
P 4.5733 1.22166998 9 P 0 8 0;2=26,4=1
P 4.585 1.181 58 P 0 8 0;0,2=2,4=0
P 4.65933002 1.31193002 9 P 0 8 0;2=67,4=1
P 4.63965 1.33161004 10 P 0 8 0;0,2=5,4=0
L 4.63965 1.33161004 4.65933002 1.31193002 0 P 0 
L 3.165 1.75 3.17896998 1.76396998 0 P 0 
A 3.17896998 1.76396998 3.19111004 1.769 3.19110994 1.75183494 0 P 0 Y
L 3.19111004 1.769 3.24591004 1.769 0 P 0 
A 3.24591004 1.769 3.25121998 1.7668 3.24590994 1.76149183 0 P 0 Y
L 3.25121998 1.7668 3.2558 1.76221998 0 P 0 
A 3.2558 1.76221998 3.258 1.75691004 3.25049183 1.75690994 0 P 0 Y
L 3.258 1.75691004 3.258 1.2281 0 P 0 
A 3.258 1.2281 3.26371998 1.2143 3.27750689 1.2280999 0 P 0 N
L 3.26371998 1.2143 3.2993 1.17871998 0 P 0 
A 3.2993 1.17871998 3.3131 1.173 3.3130999 1.19250689 0 P 0 N
L 3.3131 1.173 3.35661004 1.173 0 P 0 
A 3.35661004 1.173 3.36923002 1.16776998 3.35660994 1.15515896 0 P 0 Y
L 3.36923002 1.16776998 3.375 1.162 0 P 0 
P 3.165 1.75 63 P 0 8 0;0,2=2,4=0
L 4.12783996 1.72531998 4.10816004 1.70563996 1 P 0 
P 5.3 4.065 11 P 0 8 0;2=8,4=0
P 4.10816004 1.70563996 9 P 0 8 0;2=4,4=1
P 4.12783996 1.72531998 10 P 0 8 0;0,2=5,4=0
L 4.395 2.419 4.395 2.36 1 P 0 
L 4.395 2.36 4.365 2.33 1 P 0 
P 4.44 2.419 58 P 0 8 0;0,2=2,4=0
L 4.44 2.419 4.395 2.419 1 P 0 
P 4.365 2.33 11 P 0 8 0;2=7,4=1
P 4.395 2.419 58 P 0 8 0;0,2=2,4=0
P 4.38373996 2.02058996 9 P 0 8 0;2=15,4=1
L 4.36406004 2.00091004 4.38373996 2.02058996 1 P 0 
P 4.36406004 2.00091004 10 P 0 8 0;0,2=5,4=0
P 4.38373996 2.05996004 9 P 0 8 0;2=4,4=1
P 4.36406004 2.04028002 10 P 0 8 0;0,2=5,4=0
L 4.36406004 2.04028002 4.38373996 2.05996004 1 P 0 
P 4.485 2.375 11 P 0 8 0;2=1,4=1
P 4.38373996 2.09933002 9 P 0 8 0;2=4,4=1
P 4.36406004 2.07965 10 P 0 8 0;0,2=5,4=0
L 4.36406004 2.07965 4.38373996 2.09933002 1 P 0 
L 4.959 1.335 4.9097 1.335 1 P 0 
P 4.54121998 1.58753002 9 P 0 8 0;2=4,4=1
P 4.52153996 1.60721004 10 P 0 8 0;0,2=5,4=0
L 4.52153996 1.60721004 4.54121998 1.58753002 1 P 0 
P 4.9097 1.335 9 P 0 8 0;2=24,4=1
P 4.959 1.335 63 P 0 8 0;0,2=2,4=0
P 4.26563996 1.78436998 9 P 0 8 0;2=4,4=1
P 4.365 2.375 11 P 0 8 0;2=1,4=1
L 4.28531998 1.76468996 4.26563996 1.78436998 1 P 0 
P 4.28531998 1.76468996 10 P 0 8 0;0,2=5,4=0
P 0.1975 1.0435 74 P 0 8 0;0,2=45,4=0
P 0.1975 2.1835 74 P 0 8 0;0,2=45,4=0
P 3.465 1.74 11 P 0 8 0;2=7,4=1
P 3.44 1.03 11 P 0 8 0;2=1,4=1
L 3.53613996 1.88543002 3.53613996 1.835 1 P 0 
L 3.53613996 1.835 3.554 1.81713996 1 P 0 
L 3.554 1.81713996 3.554 1.78748996 1 P 0 
L 3.554 1.78748996 3.51248996 1.78748996 1 P 0 
L 3.51248996 1.78748996 3.465 1.74 1 P 0 
P 3.554 1.78748996 58 P 0 8 0;0,2=2,4=0
P 3.53613996 1.88543002 109 P 0 8 0;0,2=68,4=0
P 6.285 1.895 11 P 0 8 0;2=7,4=1
S P 0
OB 6.368980019685 2.050780019685 I
OC 6.366980019685 2.04873996063 6.366981692913 2.050738681102 Y
OS 6.363 2.04873996063
OS 6.323 2.00873996063
OS 6.2583 2.00873996063
OS 6.25801003937 2.008830019685
OC 6.252 2.00976003937 6.251979527559 1.989743208661 N
OS 6.198 2.00976003937
OC 6.19373996063 2.0093 6.198006988189 1.989740748031 N
OS 6.192680019685 2.00906003937
OS 6.188 2.01373996063
OS 6.188 2.06073996063
OS 6.196 2.06873996063
OS 6.26523996063 2.06873996063
OC 6.27988996063 2.06663996063 6.279910433071 2.118933070866 N
OS 6.35925 2.06663996063
OC 6.368980019685 2.062469980315 6.37516988189 2.09034980315 N
OS 6.368980019685 2.050780019685
OE
SE
L 6.4105 2.05906004 6.335 2.05906004 8 P 0 
P 6.26988996 2.20183996 53 P 0 8 0;0,2=6,4=0
P 6.258 2.15873996 9 P 0 8 0;2=26,4=1
L 6.26988996 2.20183996 6.26988996 2.17063002 8 P 0 
L 6.26988996 2.17063002 6.258 2.15873996 8 P 0 
P 6.4105 2.05906004 87 P 0 8 0;0,2=56,4=0
P 6.275 2.05373996 11 P 0 8 0;2=7,4=1
P 6.289 2.01273996 58 P 0 8 0;0,2=2,4=0
P 6.225 2.03673996 88 P 0 8 0;0,2=21,4=0
P 6.335 2.05906004 9 P 0 8 0;2=24,4=1
S P 0
OB 1.776 3.996 I
OS 1.776 4.046
OS 1.78 4.05
OS 1.8935 4.05
OS 1.8935 3.9045
OS 1.7795 3.9045
OS 1.735 3.949
OS 1.618 3.949
OS 1.611 3.956
OS 1.611 3.981
OS 1.616 3.986
OS 1.766 3.986
OS 1.776 3.996
OE
SE
L 1.84386998 3.976 1.774 3.976 8 P 0 
L 1.774 3.976 1.77 3.98 8 P 0 
P 1.77 3.98 11 P 0 8 0;2=1,4=1
P 1.84386998 3.976 112 P 0 8 0;0,2=69,4=0
P 1.75 3.945 11 P 0 8 0;2=7,4=1
P 1.66961998 3.9532 29 P 0 8 0;0,2=61,4=0
P 1.66961998 3.9788 29 P 0 8 0;0,2=61,4=0
P 1.5315 3.9459 9 P 0 8 0;2=24,4=1
L 1.5315 3.9459 1.54176004 3.95616004 6 P 0 
L 1.54176004 3.95616004 1.58103996 3.95616004 6 P 0 
L 1.477 3.991 1.492 3.976 7 P 0 
L 1.492 3.976 1.5014 3.976 7 P 0 
L 1.5014 3.976 1.5315 3.9459 7 P 0 
P 1.477 3.991 63 P 0 8 0;0,2=2,4=0
P 1.58103996 3.95616004 55 P 0 8 0;0,2=62,4=0
L 1.517 4.113 1.524 4.12 8 P 0 
L 1.524 4.12 1.556 4.12 8 P 0 
L 1.517 4.113 1.517 4.104 6 P 0 
L 1.517 4.104 1.555 4.066 6 P 0 
L 1.555 4.066 1.555 4.04616998 6 P 0 
L 1.555 4.04616998 1.58103996 4.02013002 6 P 0 
P 1.517 4.113 11 P 0 8 0;2=1,4=1
P 1.556 4.12 58 P 0 8 0;0,2=2,4=0
P 1.58103996 4.02013002 57 P 0 8 0;0,2=63,4=0
L 1.51116998 3.86283002 1.511 3.863 1 P 0 
L 1.51116998 3.86283002 1.49933996 3.851 1 P 0 
L 1.49933996 3.851 1.467 3.851 1 P 0 
L 1.58103996 3.91186998 1.54916998 3.88 1 P 0 
L 1.54916998 3.88 1.538 3.88 1 P 0 
L 1.538 3.88 1.52083002 3.86283002 1 P 0 
L 1.52083002 3.86283002 1.51116998 3.86283002 1 P 0 
L 1.47143002 3.901 1.47143002 3.87978996 1 P 0 
L 1.47143002 3.87978996 1.467 3.87536004 1 P 0 
L 1.467 3.87536004 1.467 3.851 1 P 0 
P 1.467 3.851 63 P 0 8 0;0,2=2,4=0
P 1.511 3.863 9 P 0 8 0;2=24,4=1
P 1.58103996 3.91186998 57 P 0 8 0;0,2=63,4=0
P 1.47143002 3.901 33 P 0 8 0;0,2=14,4=0
L 1.5153 4.063 1.5153 4.0347 6 P 0 
L 1.5153 4.0347 1.55446998 3.99553002 6 P 0 
L 1.55446998 3.99553002 1.58103996 3.99553002 6 P 0 
L 1.46643002 4.086 1.48943002 4.063 6 P 0 
L 1.48943002 4.063 1.5153 4.063 6 P 0 
P 1.477 4.142 63 P 0 8 0;0,2=2,4=0
P 1.5153 4.063 9 P 0 8 0;2=24,4=1
L 1.477 4.142 1.46643002 4.13143002 6 P 0 
L 1.46643002 4.13143002 1.46643002 4.086 6 P 0 
P 1.46643002 4.086 33 P 0 8 0;0,2=14,4=0
P 1.58103996 3.99553002 55 P 0 8 0;0,2=62,4=0
L 1.521 3.993 1.53816004 3.97583996 5 P 0 
L 1.53816004 3.97583996 1.58103996 3.97583996 5 P 0 
P 1.47143002 4.031 33 P 0 8 0;0,2=14,4=0
L 1.47143002 4.031 1.483 4.031 5 P 0 
L 1.483 4.031 1.521 3.993 5 P 0 
P 1.58103996 3.97583996 55 P 0 8 0;0,2=62,4=0
P 1.521 3.993 9 P 0 8 0;2=24,4=1
L 1.6086 3.90103996 1.6086 3.8966 5 P 0 
L 1.6086 3.8966 1.586 3.874 5 P 0 
L 1.586 3.874 1.579 3.874 5 P 0 
P 1.579 3.874 11 P 0 8 0;2=1,4=1
P 1.6086 3.90103996 34 P 0 8 0;0,2=64,4=0
P 1.585 4.052 11 P 0 8 0;2=7,4=1
L 1.6086 4.03096004 1.58756004 4.052 6 P 0 
L 1.58756004 4.052 1.585 4.052 6 P 0 
P 1.6086 4.03096004 34 P 0 8 0;0,2=64,4=0
P 1.435 4.18 11 P 0 8 0;2=7,4=1
P 1.522 4.163 9 P 0 8 0;2=24,4=1
L 1.556 4.162 1.523 4.162 8 P 0 
L 1.523 4.162 1.522 4.163 8 P 0 
P 1.556 4.162 58 P 0 8 0;0,2=2,4=0
P 1.4 4.01 11 P 0 8 0;2=7,4=1
L 1.435 3.991 1.419 3.991 8 P 0 
L 1.419 3.991 1.4 4.01 8 P 0 
P 1.45056998 4.031 33 P 0 8 0;0,2=14,4=0
L 1.45056998 4.031 1.435 4.01543002 7 P 0 
L 1.435 4.01543002 1.435 3.991 7 P 0 
P 1.435 3.991 63 P 0 8 0;0,2=2,4=0
P 5.14 3.74 11 P 0 8 0;2=7,4=1
P 5.175 3.74 11 P 0 8 0;2=7,4=1
P 5.131 3.775 63 P 0 8 0;0,2=2,4=0
P 5.12 3.853 67 P 0 8 0;0,2=19,4=0
P 5.18 3.825 11 P 0 8 0;2=7,4=1
P 5.675 4.03 11 P 0 8 0;2=7,4=1
S P 0
OB 5.105 3.865 I
OS 5.19 3.865
OS 5.20235 3.85265
OS 5.201980019685 3.85228996063
OS 5.201980019685 3.726980019685
OS 5.2 3.725
OS 5.13 3.725
OS 5.125 3.73
OS 5.125 3.795
OS 5.105 3.815
OS 5.105 3.865
OE
SE
S P 0
OB 1.543 3.292 I
OS 1.554 3.303
OS 1.605 3.303
OS 1.621 3.287
OS 1.621 3.242
OS 1.615 3.236
OS 1.558 3.236
OS 1.543 3.251
OS 1.543 3.292
OE
SE
P 1.56 3.29 11 P 0 8 0;2=7,4=1
P 1.59668996 3.27 23 P 0 8 0;0,2=16,4=0
P 1.56 3.25 11 P 0 8 0;2=7,4=1
P 3.245 2.955 11 P 0 8 0;2=7,4=1
P 3.21 2.955 11 P 0 8 0;2=7,4=1
P 3.175 2.955 11 P 0 8 0;2=7,4=1
P 2.59 3.445 11 P 0 8 0;2=7,4=1
P 2.55 3.445 11 P 0 8 0;2=7,4=1
P 2.51 3.445 11 P 0 8 0;2=7,4=1
P 2.47 3.445 11 P 0 8 0;2=7,4=1
S P 0
OB 2.031 4.056 I
OS 2.28 4.056
OS 2.288 4.048
OS 2.288 3.89
OS 2.274 3.876
OS 2.19856003937 3.876
OC 2.188 3.879019980315 2.1879875 3.859003543307 N
OS 2.164 3.879019980315
OC 2.15343996063 3.876 2.1640125 3.859003543307 N
OS 2.031 3.876
OS 2.021 3.886
OS 2.021 4.046
OS 2.031 4.056
OE
SE
P 2.2 3.96 11 P 0 8 0;2=7,4=1
P 2.25 3.96 11 P 0 8 0;2=8,4=0
P 2.176 3.887 58 P 0 8 0;0,2=2,4=0
P 2.236 3.894 88 P 0 8 0;0,2=21,4=0
P 2.261 4.038 88 P 0 8 0;0,2=21,4=0
P 2.186 4.038 88 P 0 8 0;0,2=21,4=0
P 1.351 4.126 11 P 0 8 0;2=7,4=1
L 1.385 4.126 1.351 4.126 8 P 0 
P 1.385 4.126 58 P 0 8 0;0,2=2,4=0
P 2.165 3.96 11 P 0 8 0;2=7,4=1
P 2.07813002 3.976 112 P 0 8 0;0,2=69,4=0
P 2.155 3.925 11 P 0 8 0;2=7,4=1
P 2.19 3.925 11 P 0 8 0;2=7,4=1
S P 0
OB 3.37716003937 4.032 I
OS 3.38 4.032
OS 3.384 4.028
OS 3.384 3.996
OS 3.38 3.992
OS 3.34716003937 3.992
OS 3.34715 3.992019980315
OS 3.24885 3.992019980315
OS 3.24883996063 3.992
OS 3.233 3.992
OS 3.223 3.982
OS 3.223 3.98193996063
OS 3.17571003937 3.93465
OS 2.978119980315 3.93465
OS 2.97783996063 3.934930019685
OS 2.97783996063 4.0307
OS 2.97913996063 4.032
OS 3.28883996063 4.032
OS 3.28885 4.031980019685
OS 3.34615 4.031980019685
OS 3.34616003937 4.032
OS 3.35283996063 4.032
OS 3.35285 4.031980019685
OS 3.37715 4.031980019685
OS 3.37716003937 4.032
OE
SE
P 3.23 4.015 11 P 0 8 0;2=1,4=1
P 3.2 3.985 11 P 0 8 0;2=7,4=1
P 3.32938002 4.0248 29 P 0 8 0;0,2=61,4=0
P 3.32938002 3.9992 29 P 0 8 0;0,2=61,4=0
P 3.05 3.98213002 44 P 0 8 0;0,2=69,4=0
L 3.41796004 4.02183996 3.47816004 4.02183996 6 P 0 
L 3.47816004 4.02183996 3.495 4.005 6 P 0 
L 3.495 4.005 3.504 4.005 6 P 0 
L 3.504 4.005 3.522 3.987 6 P 0 
P 3.41796004 4.02183996 55 P 0 8 0;0,2=62,4=0
P 3.522 3.987 63 P 0 8 0;0,2=2,4=0
L 3.443 3.858 3.443 3.93283002 6 P 0 
L 3.443 3.93283002 3.41796004 3.95786998 6 P 0 
P 3.443 3.858 58 P 0 8 0;0,2=2,4=0
P 3.41796004 3.95786998 57 P 0 8 0;0,2=63,4=0
P 5.9065 2.4568 11 P 0 8 0;2=7,4=1
P 3.745 4.185 11 P 0 8 0;2=8,4=0
L 3.41796004 3.98246998 3.44153002 3.98246998 6 P 0 
L 3.44153002 3.98246998 3.463 3.961 6 P 0 
L 3.463 3.961 3.463 3.919 6 P 0 
L 3.463 3.919 3.47 3.912 6 P 0 
L 3.47 3.912 3.50756998 3.912 6 P 0 
L 3.50756998 3.912 3.52756998 3.892 6 P 0 
P 3.47 3.912 11 P 0 8 0;2=1,4=1
L 3.522 3.833 3.522 3.807 8 P 0 
L 3.522 3.807 3.5255 3.8035 8 P 0 
L 3.5255 3.8035 3.5255 3.7905 8 P 0 
L 3.5255 3.7905 3.536 3.78 8 P 0 
L 3.52756998 3.892 3.52756998 3.86556998 6 P 0 
L 3.52756998 3.86556998 3.522 3.86 6 P 0 
L 3.522 3.86 3.522 3.833 6 P 0 
P 3.536 3.78 63 P 0 8 0;0,2=2,4=0
P 3.522 3.833 63 P 0 8 0;0,2=2,4=0
P 3.41796004 3.98246998 55 P 0 8 0;0,2=62,4=0
P 3.52756998 3.892 33 P 0 8 0;0,2=14,4=0
P 3.69 4.135 11 P 0 8 0;2=8,4=0
L 3.48278996 4.05678002 3.50756998 4.032 1 P 0 
L 3.50756998 4.032 3.522 4.032 1 P 0 
L 3.41796004 4.04153002 3.46753996 4.04153002 1 P 0 
L 3.46753996 4.04153002 3.48278996 4.05678002 1 P 0 
P 3.41796004 4.04153002 55 P 0 8 0;0,2=62,4=0
P 3.522 4.077 63 P 0 8 0;0,2=2,4=0
L 3.522 4.077 3.522 4.032 1 P 0 
P 3.522 4.032 63 P 0 8 0;0,2=2,4=0
P 3.48278996 4.05678002 11 P 0 8 0;2=7,4=1
L 3.41796004 4.00216004 3.46283996 4.00216004 6 P 0 
L 3.46283996 4.00216004 3.476 3.989 6 P 0 
L 3.476 3.989 3.476 3.988 6 P 0 
L 3.476 3.988 3.476 3.983 6 P 0 
L 3.476 3.983 3.512 3.947 6 P 0 
L 3.512 3.947 3.52756998 3.947 6 P 0 
P 3.476 3.988 11 P 0 8 0;2=1,4=1
P 3.41796004 4.00216004 55 P 0 8 0;0,2=62,4=0
P 3.52756998 3.947 33 P 0 8 0;0,2=14,4=0
L 3.437 4.099 3.4024 4.099 7 P 0 
L 3.4024 4.099 3.3904 4.087 7 P 0 
L 3.3904 4.087 3.3904 4.07696004 7 P 0 
P 3.3904 4.07696004 34 P 0 8 0;0,2=64,4=0
P 3.437 4.099 11 P 0 8 0;2=1,4=1
L 3.477 3.816 3.48 3.813 8 P 0 
L 3.48 3.813 3.48 3.794 8 P 0 
L 3.48 3.794 3.494 3.78 8 P 0 
L 3.443 3.816 3.477 3.816 8 P 0 
L 3.3904 3.94703996 3.3904 3.9306 7 P 0 
L 3.3904 3.9306 3.405 3.916 7 P 0 
P 3.598 3.977 11 P 0 8 0;2=7,4=1
P 3.564 3.987 63 P 0 8 0;0,2=2,4=0
L 3.54843002 3.947 3.585 3.947 6 P 0 
L 3.585 3.947 3.598 3.96 6 P 0 
L 3.598 3.96 3.598 3.977 6 P 0 
P 3.54843002 3.947 33 P 0 8 0;0,2=14,4=0
L 3.598 3.977 3.588 3.987 6 P 0 
L 3.588 3.987 3.564 3.987 6 P 0 
P 3.477 3.816 11 P 0 8 0;2=1,4=1
P 3.443 3.816 58 P 0 8 0;0,2=2,4=0
P 3.494 3.78 63 P 0 8 0;0,2=2,4=0
P 3.405 3.916 11 P 0 8 0;2=7,4=1
P 3.3904 3.94703996 34 P 0 8 0;0,2=64,4=0
P 5.59271004 3.71731004 82 P 0 8 0;0,2=70,4=0
P 5.68326004 3.712 11 P 0 8 0;2=1,4=1
L 5.68326004 3.712 5.67031004 3.712 5 P 0 
L 5.67031004 3.712 5.665 3.71731004 5 P 0 
L 5.665 3.71731004 5.59271004 3.71731004 5 P 0 
L 5.71056998 3.712 5.68326004 3.712 5 P 0 
P 5.71056998 3.712 33 P 0 8 0;0,2=14,4=0
P 5.59271004 3.75668996 82 P 0 8 0;0,2=70,4=0
P 5.686 3.807 11 P 0 8 0;2=1,4=1
L 5.686 3.807 5.686 3.802 5 P 0 
L 5.686 3.802 5.64068996 3.75668996 5 P 0 
L 5.64068996 3.75668996 5.59271004 3.75668996 5 P 0 
L 5.72 3.807 5.686 3.807 5 P 0 
P 5.72 3.807 63 P 0 8 0;0,2=2,4=0
P 5.51631004 3.83456004 42 P 0 8 0;0,2=65,4=0
P 5.50643002 4.009 9 P 0 8 0;2=9,4=1
L 5.50643002 4.009 5.45398996 4.009 5 P 0 
L 5.45398996 4.009 5.44098996 3.996 5 P 0 
L 5.44098996 3.996 5.401 3.996 5 P 0 
L 5.401 3.996 5.362 3.957 5 P 0 
L 5.50643002 3.967 5.50643002 4.009 5 P 0 
L 5.50643002 3.912 5.50643002 3.967 5 P 0 
P 5.50643002 3.967 63 P 0 8 0;0,2=2,4=0
L 5.51631004 3.83456004 5.51631004 3.90211998 5 P 0 
L 5.51631004 3.90211998 5.50643002 3.912 5 P 0 
P 5.50643002 3.912 33 P 0 8 0;0,2=14,4=0
P 5.362 3.957 63 P 0 8 0;0,2=2,4=0
P 5.59271004 3.737 82 P 0 8 0;0,2=70,4=0
P 5.686 3.76 11 P 0 8 0;2=1,4=1
L 5.686 3.76 5.663 3.737 5 P 0 
L 5.663 3.737 5.59271004 3.737 5 P 0 
P 5.72 3.757 63 P 0 8 0;0,2=2,4=0
L 5.72 3.757 5.717 3.76 5 P 0 
L 5.717 3.76 5.686 3.76 5 P 0 
P 5.59271004 3.79606004 82 P 0 8 0;0,2=70,4=0
L 5.675 3.865 5.675 3.851 5 P 0 
L 5.675 3.851 5.62006004 3.79606004 5 P 0 
L 5.62006004 3.79606004 5.59271004 3.79606004 5 P 0 
P 5.72 3.857 63 P 0 8 0;0,2=2,4=0
L 5.72 3.857 5.712 3.865 5 P 0 
L 5.712 3.865 5.675 3.865 5 P 0 
P 5.675 3.865 11 P 0 8 0;2=1,4=1
P 5.59271004 3.81573996 82 P 0 8 0;0,2=70,4=0
L 5.72 3.907 5.72 3.963 1 P 0 
L 5.72 3.963 5.718 3.965 1 P 0 
P 5.718 3.965 11 P 0 8 0;2=8,4=0
L 5.72 3.907 5.677 3.907 1 P 0 
L 5.677 3.907 5.648 3.878 1 P 0 
L 5.648 3.878 5.648 3.853 1 P 0 
L 5.648 3.853 5.61073996 3.81573996 1 P 0 
L 5.61073996 3.81573996 5.59271004 3.81573996 1 P 0 
P 5.72 3.907 63 P 0 8 0;0,2=2,4=0
S P 0
OB 0.823 3.861 I
OS 0.955 3.861
OS 0.972 3.844
OS 0.972 3.71928996063
OC 0.972 3.68071003937 0.994993110236 3.7 N
OS 0.972 3.648
OS 0.955 3.631
OS 0.823 3.631
OS 0.818 3.636
OS 0.818 3.856
OS 0.823 3.861
OE
SE
P 6.05315 3.67518996 25 P 0 8 0;2=71,4=0
P 6.05315 3.50983996 18 P 0 8 0;2=72,4=0
P 6.05315 3.34448996 18 P 0 8 0;2=72,4=0
P 0.865 3.645 11 P 0 8 0;2=7,4=1
P 0.905 3.645 11 P 0 8 0;2=7,4=1
P 0.945 3.645 11 P 0 8 0;2=7,4=1
P 0.945 3.69 11 P 0 8 0;2=7,4=1
P 0.945 3.73 11 P 0 8 0;2=7,4=1
P 0.945 3.765 11 P 0 8 0;2=7,4=1
P 0.865 3.845 11 P 0 8 0;2=7,4=1
P 0.905 3.845 11 P 0 8 0;2=7,4=1
P 0.94 3.845 11 P 0 8 0;2=7,4=1
P 0.945 3.805 11 P 0 8 0;2=1,4=1
P 0.828 3.846 11 P 0 8 0;2=7,4=1
P 0.873 3.736 95 P 0 8 0;0,2=73,4=0
P 0.828 3.646 11 P 0 8 0;2=7,4=1
P 5.59271004 3.65826004 82 P 0 8 0;0,2=70,4=0
P 5.66 3.47 11 P 0 8 0;2=8,4=0
L 5.66 3.47 5.717 3.47 1 P 0 
L 5.717 3.47 5.72 3.467 1 P 0 
P 5.72 3.467 63 P 0 8 0;0,2=2,4=0
L 5.72 3.467 5.72 3.517 1 P 0 
L 5.72 3.567 5.72 3.517 1 P 0 
P 5.72 3.517 63 P 0 8 0;0,2=2,4=0
L 5.59271004 3.65826004 5.61173996 3.65826004 1 P 0 
L 5.61173996 3.65826004 5.645 3.625 1 P 0 
L 5.645 3.625 5.645 3.61 1 P 0 
L 5.645 3.61 5.68 3.575 1 P 0 
L 5.68 3.575 5.68 3.567 1 P 0 
L 5.68 3.567 5.72 3.567 1 P 0 
P 5.72 3.567 63 P 0 8 0;0,2=2,4=0
P 5.68 3.567 9 P 0 8 0;2=9,4=1
S P 0
OB 5.358 3.921 I
OS 5.415 3.921
OS 5.421 3.915
OS 5.421 3.867
OS 5.45 3.838
OS 5.501 3.838
OS 5.503 3.836
OS 5.503 3.812
OS 5.501 3.81
OS 5.423 3.81
OS 5.403 3.79
OS 5.351 3.79
OS 5.3461 3.7949
OS 5.34601003937 3.79501003937
OC 5.344 3.797430019685 5.321944192913 3.777065649606 N
OS 5.344 3.87175
OC 5.34675 3.87575 5.329003641732 3.885005314961 N
OS 5.353 3.882
OS 5.353 3.916
OS 5.358 3.921
OE
SE
P 5.47928996 3.81573996 82 P 0 8 0;0,2=70,4=0
P 5.364 3.827 71 P 0 8 0;0,2=21,4=0
P 5.368 3.902 64 P 0 8 0;0,2=19,4=0
P 5.406 3.863 11 P 0 8 0;2=1,4=1
S P 0
OB 3.461 4.251 I
OS 3.563 4.251
OS 3.568 4.246
OS 3.568 4.225019980315
OC 3.559980019685 4.209 3.579990059055 4.209 N
OS 3.559980019685 4.185
OC 3.568 4.168980019685 3.579990059055 4.185 N
OS 3.568 4.154
OS 3.561019980315 4.147019980315
OS 3.547430019685 4.147019980315
OC 3.532769980315 4.14248996063 3.547439468504 4.121002952756 N
OC 3.526569980315 4.14336003937 3.526592716535 4.120996751969 N
OS 3.504630019685 4.14336003937
OC 3.492830019685 4.14 3.504619488189 4.120996948819 N
OS 3.467 4.14
OS 3.453 4.154
OS 3.453 4.243
OS 3.461 4.251
OE
SE
P 3.46 4.16 11 P 0 8 0;2=7,4=1
P 3.495 4.15 11 P 0 8 0;2=7,4=1
P 3.5 4.195 11 P 0 8 0;2=7,4=1
P 3.53 4.165 11 P 0 8 0;2=7,4=1
P 3.552 4.197 63 P 0 8 0;0,2=2,4=0
P 3.465 4.202 64 P 0 8 0;0,2=19,4=0
P 5.769 4.031 11 P 0 8 0;2=7,4=1
P 5.644 3.967 11 P 0 8 0;2=1,4=1
P 5.601 3.96 63 P 0 8 0;0,2=2,4=0
L 5.601 3.96 5.608 3.967 8 P 0 
L 5.608 3.967 5.644 3.967 8 P 0 
P 5.803 3.907 11 P 0 8 0;2=7,4=1
L 5.762 3.907 5.803 3.907 8 P 0 
P 5.762 3.907 63 P 0 8 0;0,2=2,4=0
S P 0
OB 1.45 3.815 I
OS 1.54 3.815
OS 1.545 3.81
OS 1.546 3.81
OS 1.546 3.739
OS 1.54036003937 3.73336003937
OS 1.469830019685 3.73336003937
OC 1.457 3.738019980315 1.456991043307 3.718003248031 N
OS 1.436980019685 3.738019980315
OS 1.435 3.74
OS 1.435 3.778380019685
OC 1.440019980315 3.795 1.409997637795 3.795 N
OC 1.439030019685 3.802630019685 1.410002066929 3.794984547244 N
OS 1.43873996063 3.80373996063
OS 1.45 3.815
OE
SE
P 1.445 3.746 58 P 0 8 0;0,2=2,4=0
P 1.45 3.78 11 P 0 8 0;2=7,4=1
P 1.485 3.76 9 P 0 8 0;2=24,4=1
P 1.485 3.8 11 P 0 8 0;2=7,4=1
P 1.534 3.776 64 P 0 8 0;0,2=19,4=0
P 5.406 2.346 11 P 0 8 0;2=8,4=0
P 5.331 2.28 58 P 0 8 0;0,2=2,4=0
P 5.375 2.32 11 P 0 8 0;2=7,4=1
P 5.34 2.315 11 P 0 8 0;2=7,4=1
P 5.395 2.283 67 P 0 8 0;0,2=19,4=0
S P 0
OB 5.334 2.365 I
OS 5.42 2.365
OS 5.431 2.354
OS 5.431 2.279
OS 5.422 2.27
OS 5.366 2.27
OS 5.365 2.269
OS 5.35356003937 2.269
OC 5.343 2.272019980315 5.3429875 2.252003543307 N
OS 5.3211 2.272019980315
OC 5.31711003937 2.2759 5.321105216535 2.276016830709 Y
OC 5.304 2.29981003937 5.287102755906 2.274995964567 N
OS 5.304 2.335
OS 5.334 2.365
OE
SE
S P 0
OB 5.434980019685 3.799980019685 I
OS 5.504 3.799980019685
OS 5.504 3.6034
OS 5.494 3.5934
OS 5.494 3.551
OS 5.453 3.551
OS 5.419 3.585
OS 5.23 3.585
OS 5.225 3.59
OS 5.225 3.691
OS 5.362 3.691
OS 5.37225 3.70125
OC 5.38075 3.70975 5.363 3.719 N
OS 5.425 3.754
OS 5.425 3.79
OS 5.434980019685 3.799980019685
OE
SE
P 5.47928996 3.79606004 82 P 0 8 0;0,2=70,4=0
P 5.47928996 3.77636998 82 P 0 8 0;0,2=70,4=0
P 5.47928996 3.75668996 82 P 0 8 0;0,2=70,4=0
P 5.47928996 3.737 82 P 0 8 0;0,2=70,4=0
P 5.47928996 3.71731004 82 P 0 8 0;0,2=70,4=0
P 5.47928996 3.69763002 82 P 0 8 0;0,2=70,4=0
P 5.47928996 3.67793996 82 P 0 8 0;0,2=70,4=0
P 5.47928996 3.65826004 82 P 0 8 0;0,2=70,4=0
P 5.43 3.6 11 P 0 8 0;2=1,4=1
P 5.433 3.651 11 P 0 8 0;2=7,4=1
P 5.43 3.7 11 P 0 8 0;2=7,4=1
P 5.336 3.672 88 P 0 8 0;0,2=21,4=0
P 5.39 3.6 11 P 0 8 0;2=7,4=1
P 5.393 3.651 11 P 0 8 0;2=7,4=1
P 5.39 3.7 11 P 0 8 0;2=7,4=1
P 5.254 3.672 88 P 0 8 0;0,2=21,4=0
P 5.479 3.569 64 P 0 8 0;0,2=19,4=0
S P 0
OB 1.601 4.186 I
OS 1.656 4.186
OS 1.666 4.176
OS 1.666 4.076
OS 1.641 4.051
OS 1.641 4.001
OS 1.636019980315 3.996019980315
OS 1.625980019685 3.996019980315
OS 1.621 4.001
OS 1.621 4.048
OS 1.596 4.073
OS 1.596 4.181
OS 1.601 4.186
OE
SE
S P 0
OB 1.626 3.936 I
OS 1.636 3.936
OS 1.640980019685 3.93101003937
OS 1.640980019685 3.88185
OS 1.641 3.88183996063
OS 1.641 3.866
OS 1.646 3.861
OS 1.681 3.861
OS 1.686 3.856
OS 1.686 3.816
OS 1.701 3.801
OS 1.701 3.741
OS 1.692 3.732
OS 1.581 3.732
OS 1.576 3.737
OS 1.576 3.846
OS 1.581 3.851
OS 1.611 3.851
OS 1.621 3.861
OS 1.621 3.931
OS 1.626 3.936
OE
SE
P 1.588 3.776 64 P 0 8 0;0,2=19,4=0
P 1.65 4.091 63 P 0 8 0;0,2=2,4=0
P 1.648 4.151 71 P 0 8 0;0,2=21,4=0
P 1.63221998 4.02013002 48 P 0 8 0;0,2=66,4=0
P 1.63221998 3.91186998 48 P 0 8 0;0,2=66,4=0
P 1.67 3.841 63 P 0 8 0;0,2=2,4=0
P 1.678 3.776 71 P 0 8 0;0,2=21,4=0
P 1.6055 4.134 11 P 0 8 0;2=7,4=1
P 1.60581998 4.1 11 P 0 8 0;2=7,4=1
P 1.606 4.174 9 P 0 8 0;2=24,4=1
P 1.636 3.786 11 P 0 8 0;2=7,4=1
P 1.591 3.826 11 P 0 8 0;2=7,4=1
P 1.633 3.829 9 P 0 8 0;2=24,4=1
S P 0
OB 3.303 4.252 I
OS 3.418 4.252
OS 3.423 4.247
OS 3.423 4.132
OS 3.418 4.127
OS 3.388 4.127
OS 3.378 4.117
OS 3.378 4.047
OS 3.373 4.042
OS 3.357 4.042
OS 3.356019980315 4.042980019685
OS 3.356019980315 4.09515
OS 3.354 4.09716003937
OS 3.354 4.113
OS 3.35 4.117
OS 3.318 4.117
OS 3.313 4.122
OS 3.313 4.162
OS 3.298 4.177
OS 3.298 4.247
OS 3.303 4.252
OE
SE
S P 0
OB 3.361 3.98 I
OS 3.374 3.98
OS 3.374 3.91
OS 3.403 3.881
OS 3.403 3.797
OS 3.398 3.792
OS 3.343 3.792
OS 3.333 3.802
OS 3.333 3.86783996063
OS 3.333019980315 3.86785
OS 3.333019980315 3.897019980315
OS 3.359 3.923
OS 3.359 3.978
OS 3.361 3.98
OE
SE
P 3.411 4.202 64 P 0 8 0;0,2=19,4=0
P 3.329 4.137 63 P 0 8 0;0,2=2,4=0
P 3.321 4.202 71 P 0 8 0;0,2=21,4=0
P 3.408 4.152 11 P 0 8 0;2=7,4=1
P 3.363 4.192 11 P 0 8 0;2=7,4=1
P 3.363 4.152 11 P 0 8 0;2=7,4=1
P 3.363 4.232 11 P 0 8 0;2=1,4=1
P 3.36678002 4.06613002 48 P 0 8 0;0,2=66,4=0
P 3.36678002 3.95786998 48 P 0 8 0;0,2=66,4=0
P 3.349 3.887 63 P 0 8 0;0,2=2,4=0
P 3.351 3.827 71 P 0 8 0;0,2=21,4=0
P 3.393 3.877 11 P 0 8 0;2=7,4=1
P 3.393 3.84 11 P 0 8 0;2=7,4=1
P 3.392 3.803 11 P 0 8 0;2=7,4=1
P 3.607 4.062 11 P 0 8 0;2=7,4=1
L 3.54843002 3.892 3.54843002 3.87056004 6 P 0 
L 3.54843002 3.87056004 3.564 3.85498996 6 P 0 
L 3.564 3.85498996 3.564 3.833 6 P 0 
P 3.564 3.833 63 P 0 8 0;0,2=2,4=0
P 3.54843002 3.892 33 P 0 8 0;0,2=14,4=0
L 3.54843002 3.892 3.607 3.892 7 P 0 
L 3.607 3.892 3.609 3.892 6 P 0 
L 3.609 3.892 3.623 3.878 6 P 0 
P 3.623 3.878 58 P 0 8 0;0,2=2,4=0
P 1.435 4.142 63 P 0 8 0;0,2=2,4=0
L 1.385 4.084 1.352 4.084 8 P 0 
P 1.352 4.084 11 P 0 8 0;2=1,4=1
L 1.44556998 4.086 1.44356998 4.084 7 P 0 
L 1.44356998 4.084 1.385 4.084 7 P 0 
P 1.385 4.084 58 P 0 8 0;0,2=2,4=0
L 1.435 4.142 1.435 4.12101004 6 P 0 
L 1.435 4.12101004 1.44556998 4.11043996 6 P 0 
L 1.44556998 4.11043996 1.44556998 4.086 6 P 0 
P 1.44556998 4.086 33 P 0 8 0;0,2=14,4=0
P 1.95 0.5455 9 P 0 8 0;2=24,4=1
L 1.95 0.5455 1.97466998 0.5455 1 P 0 
L 1.97466998 0.5455 1.9977 0.56853002 1 P 0 
L 1.9977 0.56853002 1.9977 0.59 1 P 0 
P 1.8832 0.59 97 P 0 8 0;0,2=59,4=0
L 1.8832 0.59 1.9289 0.59 1 P 0 
L 1.9289 0.59 1.95 0.5689 1 P 0 
L 1.95 0.5689 1.95 0.5455 1 P 0 
L 1.9977 0.59 2.0477 0.59 1 P 0 
P 2.0477 0.59 58 P 0 8 0;0,2=2,4=0
P 1.9977 0.59 58 P 0 8 0;0,2=2,4=0
P 5.59271004 3.67793996 82 P 0 8 0;0,2=70,4=0
P 5.681 3.617 11 P 0 8 0;2=1,4=1
L 5.681 3.617 5.62006004 3.67793996 5 P 0 
L 5.62006004 3.67793996 5.59271004 3.67793996 5 P 0 
P 5.72 3.617 63 P 0 8 0;0,2=2,4=0
L 5.72 3.617 5.681 3.617 5 P 0 
P 5.59271004 3.69763002 82 P 0 8 0;0,2=70,4=0
P 5.681 3.664 11 P 0 8 0;2=1,4=1
L 5.681 3.664 5.666 3.664 5 P 0 
L 5.666 3.664 5.63236998 3.69763002 5 P 0 
L 5.63236998 3.69763002 5.59271004 3.69763002 5 P 0 
L 5.72 3.667 5.684 3.667 5 P 0 
L 5.684 3.667 5.681 3.664 5 P 0 
P 5.72 3.667 63 P 0 8 0;0,2=2,4=0
L 5.50543996 2.721 5.41981998 2.721 1 P 0 
L 5.41981998 2.721 5.40318002 2.70436004 1 P 0 
P 5.40318002 2.70436004 9 P 0 8 0;2=24,4=1
P 5.50543996 2.721 43 P 0 8 0;0,2=37,4=0
L 0.53 1.444 0.55921998 1.41478002 1 P 0 
L 0.55921998 1.41478002 0.55921998 1.40543002 1 P 0 
L 0.55921998 1.40543002 0.55921998 1.40421998 1 P 0 
L 0.55921998 1.40421998 0.55708002 1.40208002 1 P 0 
L 0.55708002 1.40208002 0.55708002 1.35 1 P 0 
P 0.53 1.444 58 P 0 8 0;0,2=2,4=0
P 0.55921998 1.40543002 11 P 0 8 0;2=1,4=1
P 0.55708002 1.35 35 P 0 8 0;0,2=43,4=0
L 0.57 0.835 0.535 0.87 1 P 0 
L 0.535 0.87 0.535 0.884 1 P 0 
L 0.55708002 0.77913996 0.55708002 0.82208002 1 P 0 
L 0.55708002 0.82208002 0.57 0.835 1 P 0 
P 0.535 0.884 58 P 0 8 0;0,2=2,4=0
P 0.55708002 0.77913996 35 P 0 8 0;0,2=43,4=0
P 0.57 0.835 11 P 0 8 0;2=1,4=1
P 3.584 1.827 9 P 0 8 0;2=24,4=1
L 3.584 1.827 3.604 1.807 1 P 0 
L 3.604 1.807 3.604 1.78748996 1 P 0 
L 3.55188996 1.88543002 3.55188996 1.85711004 1 P 0 
L 3.55188996 1.85711004 3.582 1.827 1 P 0 
L 3.582 1.827 3.584 1.827 1 P 0 
P 3.55188996 1.88543002 109 P 0 8 0;0,2=68,4=0
P 3.604 1.78748996 58 P 0 8 0;0,2=2,4=0
L 1.535 3.905 1.518 3.905 1 P 0 
L 1.518 3.905 1.477 3.946 1 P 0 
L 1.58103996 3.93646998 1.56646998 3.93646998 1 P 0 
L 1.56646998 3.93646998 1.535 3.905 1 P 0 
P 1.58103996 3.93646998 55 P 0 8 0;0,2=62,4=0
P 1.477 3.946 63 P 0 8 0;0,2=2,4=0
P 1.535 3.905 9 P 0 8 0;2=26,4=1
P 1.98135 0.365 9 P 0 8 0;2=26,4=1
P 1.7317 0.7084 11 P 0 8 0;2=1,4=1
L 1.7317 0.7084 1.7133 0.69 1 P 0 
L 1.7133 0.69 1.6622 0.69 1 P 0 
P 1.6622 0.69 97 P 0 8 0;0,2=59,4=0
L 1.99408996 0.13781004 1.99408996 0.35226004 1 P 0 
L 1.99408996 0.35226004 1.98135 0.365 1 P 0 
P 1.99408996 0.13781004 62 P 0 8 0;0,2=74,4=0
P 1.91535 0.412 9 P 0 8 0;2=26,4=1
L 1.91535 0.412 1.91535 0.41063996 1 P 0 
L 1.91535 0.41063996 1.95471998 0.37126998 1 P 0 
L 1.95471998 0.37126998 1.95471998 0.13781004 1 P 0 
P 1.95471998 0.13781004 62 P 0 8 0;0,2=74,4=0
P 1.8039 0.7072 9 P 0 8 0;2=24,4=1
L 1.8039 0.7072 1.8211 0.69 1 P 0 
L 1.8211 0.69 1.8832 0.69 1 P 0 
P 1.8832 0.69 97 P 0 8 0;0,2=59,4=0
L 3.45301004 1.89898996 3.45638002 1.90235 3 P 0 
A 3.45638002 1.90235 3.46443002 1.90761998 3.47300797 1.88573366 3 P 0 Y
L 3.46443002 1.90761998 3.46616004 1.9083 3 P 0 
L 3.46616004 1.9083 3.50595 1.9083 3 P 0 
L 3.50595 1.9083 3.50595 1.90761998 3 P 0 
P 3.161 1.895 63 P 0 8 0;0,2=2,4=0
L 3.161 1.895 3.16951998 1.88648002 3 P 0 
A 3.16951998 1.88648002 3.17848996 1.8806 3.18816722 1.90514469 3 P 0 N
L 3.17848996 1.8806 3.2298 1.8806 3 P 0 
A 3.2298 1.8806 3.23518002 1.88443996 3.2298 1.88628878 3 P 0 N
L 3.23518002 1.88443996 3.2353 1.88511004 3 P 0 
L 3.2353 1.88511004 3.2353 1.89116998 3 P 0 
A 3.2353 1.89116998 3.23273996 1.89735 3.22656053 1.89116988 3 P 0 N
L 3.23273996 1.89735 3.2271 1.90298996 3 P 0 
P 3.2271 1.90298996 9 P 0 8 0;2=38,4=1
P 3.45301004 1.89898996 9 P 0 8 0;2=38,4=1
P 3.50595 1.90761998 69 P 0 8 0;0,2=55,4=0
L 3.45301004 1.93098996 3.45466004 1.92933002 3 P 0 
A 3.45466004 1.92933002 3.46413002 1.9233 3.472994 1.94767185 3 P 0 N
L 3.46413002 1.9233 3.50595 1.9233 3 P 0 
L 3.50595 1.9233 3.50595 1.92336004 3 P 0 
L 3.2591 1.90298996 3.25496004 1.89885 3 P 0 
A 3.25496004 1.89885 3.2503 1.8876 3.26620965 1.8875999 3 P 0 N
L 3.2503 1.8876 3.2503 1.88511998 3 P 0 
A 3.2503 1.88511998 3.24935 1.87948996 3.23321782 1.88510719 3 P 0 Y
A 3.24935 1.87948996 3.2298 1.8656 3.2298 1.88630315 3 P 0 Y
L 3.2298 1.8656 3.18185 1.8656 3 P 0 
L 3.18185 1.8656 3.1795 1.86478002 3 P 0 
A 3.1795 1.86478002 3.16951998 1.85851998 3.18817746 1.83986073 3 P 0 N
L 3.16951998 1.85851998 3.161 1.85 3 P 0 
P 3.161 1.85 63 P 0 8 0;0,2=2,4=0
P 3.2591 1.90298996 9 P 0 8 0;2=38,4=1
P 3.45301004 1.93098996 9 P 0 8 0;2=38,4=1
P 3.50595 1.92336004 69 P 0 8 0;0,2=55,4=0
P 1.26066998 2.64043002 17 P 0 8 0;2=75,4=0
P 5.50543996 2.821 43 P 0 8 0;0,2=37,4=0
P 5.71056004 2.921 43 P 0 8 0;0,2=37,4=0
P 5.50543996 2.921 43 P 0 8 0;0,2=37,4=0
P 1.6622 0.74 97 P 0 8 0;0,2=59,4=0
S P 0
OB 4.875 3.945 I
OS 4.885 3.955
OS 5.125 3.955
OS 5.135 3.945
OS 5.135 3.895
OS 5.13 3.89
OS 4.875 3.89
OS 4.875 3.945
OE
SE
P 5.12 3.907 67 P 0 8 0;0,2=19,4=0
P 5.035 3.945 11 P 0 8 0;2=1,4=1
P 5.075 3.945 11 P 0 8 0;2=7,4=1
P 4.91548996 3.90826998 106 P 0 8 0;0,2=20,4=0
P 5.05 3.903 88 P 0 8 0;0,2=21,4=0
P 2.97771998 1.88693996 11 P 0 8 0;2=7,4=1
L 2.97771998 1.88693996 2.97503002 1.88963002 6 P 0 
L 2.97503002 1.88963002 2.92733996 1.88963002 6 P 0 
P 3.00995 1.87611004 11 P 0 8 0;2=7,4=1
L 3.00995 1.87611004 2.99911998 1.88693996 8 P 0 
L 2.99911998 1.88693996 2.97771998 1.88693996 8 P 0 
P 2.92733996 1.88963002 98 P 0 8 0;0,2=76,4=0
P 2.86066998 2.64043002 17 P 0 8 0;2=75,4=0
P 2.105 0.305 9 P 0 8 0;2=26,4=1
L 2.07283002 0.13781004 2.07283002 0.27283002 8 P 0 
L 2.07283002 0.27283002 2.105 0.305 8 P 0 
P 2.07283002 0.13781004 62 P 0 8 0;0,2=74,4=0
P 2.235 0.5825 11 P 0 8 0;2=7,4=1
P 3.405 0.635 11 P 0 8 0;2=7,4=1
L 5.295 0.605 5.255 0.645 8 P 0 
L 5.255 0.645 5.19 0.645 8 P 0 
L 5.19 0.645 5.16 0.615 8 P 0 
L 5.16 0.615 3.63 0.615 8 P 0 
L 3.63 0.615 3.565 0.68 8 P 0 
L 3.565 0.68 3.45 0.68 8 P 0 
L 3.45 0.68 3.405 0.635 8 P 0 
P 5.295 0.605 11 P 0 8 0;2=1,4=1
P 5.91 4.04 11 P 0 8 0;2=1,4=1
P 2.135 0.54 11 P 0 8 0;2=7,4=1
L 2.135 0.54 2.135 0.52 8 P 0 
L 2.135 0.52 2.15 0.505 8 P 0 
L 2.15 0.505 2.15 0.3581 8 P 0 
L 2.15 0.3581 2.168 0.3401 8 P 0 
L 2.168 0.3401 2.168 0.29 8 P 0 
L 2.168 0.29 2.15156998 0.27356998 8 P 0 
L 2.15156998 0.27356998 2.15156998 0.13781004 8 P 0 
L 2.15 0.594 2.105 0.594 8 P 0 
P 2.105 0.594 58 P 0 8 0;0,2=2,4=0
L 2.15 0.594 2.15 0.565 8 P 0 
L 2.15 0.565 2.135 0.55 8 P 0 
L 2.135 0.55 2.135 0.54 8 P 0 
P 2.15 0.594 58 P 0 8 0;0,2=2,4=0
P 2.15156998 0.13781004 62 P 0 8 0;0,2=74,4=0
L 5.215 0.6 5.195 0.58 8 P 0 
L 5.195 0.58 3.62 0.58 8 P 0 
L 3.62 0.58 3.555 0.645 8 P 0 
L 3.555 0.645 3.465 0.645 8 P 0 
L 3.465 0.645 3.4175 0.5975 8 P 0 
L 3.4175 0.5975 3.3731 0.5975 8 P 0 
L 3.3731 0.5975 3.36 0.6106 8 P 0 
P 5.215 0.6 11 P 0 8 0;2=1,4=1
P 6.025 4.04 11 P 0 8 0;2=1,4=1
P 3.36 0.6106 11 P 0 8 0;2=7,4=1
L 3.075 3.685 3.042 3.652 8 P 0 
L 3.042 3.652 2.5495 3.652 8 P 0 
L 2.5495 3.652 2.38 3.4825 8 P 0 
L 2.38 3.4825 2.38 3.45 8 P 0 
S P 0
OB 3.50575 3.583919980315 I
OS 3.481319980315 3.55948996063
OS 2.99671003937 3.55948996063
OS 2.978719980315 3.577480019685
OS 2.978719980315 3.793130019685
OS 3.105980019685 3.793130019685
OS 3.234119980315 3.665
OS 3.28 3.665
OS 3.28331003937 3.66168996063
OS 3.5035 3.66168996063
OS 3.50575 3.65943996063
OS 3.50575 3.583919980315
OE
SE
P 0.96 2.41 11 P 0 8 0;2=7,4=1
L 0.715 2.402 0.736 2.381 8 P 0 
L 0.736 2.381 0.76 2.381 8 P 0 
L 0.76 2.381 0.7826 2.4036 8 P 0 
L 0.7826 2.4036 0.7826 2.4275 8 P 0 
L 0.715 2.402 0.715 2.399 8 P 0 
L 0.715 2.399 0.68 2.364 8 P 0 
L 0.68 2.364 0.68 2.355 8 P 0 
P 0.68 2.355 11 P 0 8 0;2=7,4=1
P 0.715 2.402 58 P 0 8 0;0,2=2,4=0
P 0.7826 2.4275 50 P 0 8 0;0,2=42,4=0
P 2.38 3.45 11 P 0 8 0;2=7,4=1
L 3.15 3.685 3.075 3.685 8 P 0 
P 1.41 3.795 11 P 0 8 0;2=7,4=1
L 3.623 3.836 3.623 3.7505 8 P 0 
L 3.623 3.7505 3.5245 3.652 8 P 0 
L 3.5245 3.652 3.48 3.652 8 P 0 
P 3.255 3.664 58 P 0 8 0;0,2=2,4=0
P 3.623 3.836 58 P 0 8 0;0,2=2,4=0
P 3.445 3.613 11 P 0 8 0;2=7,4=1
P 3.365 3.613 11 P 0 8 0;2=1,4=1
P 3.48 3.652 88 P 0 8 0;0,2=21,4=0
P 3.4 3.652 88 P 0 8 0;0,2=21,4=0
P 3.25 3.63 11 P 0 8 0;2=7,4=1
P 3.325 3.613 11 P 0 8 0;2=7,4=1
P 3.405 3.613 11 P 0 8 0;2=7,4=1
P 3.48418002 3.613 11 P 0 8 0;2=7,4=1
P 3.05 3.74786998 44 P 0 8 0;0,2=69,4=0
P 3.32 3.652 88 P 0 8 0;0,2=21,4=0
P 3.645 4.135 11 P 0 8 0;2=7,4=1
S P 0
OB 3.607 3.121 I
OS 3.667 3.121
OS 3.672980019685 3.115019980315
OS 3.672980019685 3.04071003937
OS 3.674 3.03968996063
OS 3.674 3.010019980315
OS 3.65 3.010019980315
OC 3.6357 3.004 3.650009251969 2.990003838583 N
OS 3.61 3.004
OS 3.603 3.011
OS 3.603 3.117
OS 3.607 3.121
OE
SE
P 3.655 3.059 11 P 0 8 0;2=7,4=1
P 3.614 3.099 11 P 0 8 0;2=7,4=1
P 3.614 3.058 11 P 0 8 0;2=7,4=1
P 3.614 3.015 11 P 0 8 0;2=7,4=1
P 3.654 3.099 64 P 0 8 0;0,2=19,4=0
P 3.662 3.018 58 P 0 8 0;0,2=2,4=0
P 5.236 2.811 11 P 0 8 0;2=7,4=1
L 5.27 2.811 5.236 2.811 8 P 0 
P 5.27 2.811 58 P 0 8 0;0,2=2,4=0
L 4.36583996 2.86616004 4.41975 2.86616004 6 P 0 
S P 0
OB 4.33 2.939 I
OS 4.388 2.939
OS 4.392 2.935
OS 4.392 2.857
OS 4.39 2.855
OS 4.39 2.815
OS 4.405 2.8
OS 4.46893996063 2.8
OC 4.47 2.799980019685 4.470035629921 2.829999311024 N
OC 4.47106003937 2.8 4.469964370079 2.829999311024 N
OS 4.475 2.8
OS 4.485 2.79
OS 4.485 2.725
OS 4.425 2.725
OS 4.415 2.735
OS 4.326 2.735
OS 4.321 2.74
OS 4.321 2.93
OS 4.33 2.939
OE
SE
L 4.356 2.876 4.36583996 2.86616004 6 P 0 
P 4.41975 2.82428996 66 P 0 8 0;0,2=77,4=0
P 4.41975 2.86616004 65 P 0 8 0;0,2=53,4=0
L 4.41975 2.86616004 4.49516004 2.86616004 6 P 0 
L 4.49516004 2.86616004 4.524 2.895 6 P 0 
P 4.356 2.876 101 P 0 8 0;0,2=78,4=0
L 4.3815 2.838 4.39521004 2.82428996 8 P 0 
L 4.39521004 2.82428996 4.41975 2.82428996 8 P 0 
P 4.3305 2.914 11 P 0 8 0;2=79,4=1
P 4.3815 2.838 11 P 0 8 0;2=79,4=1
L 4.33 2.765 4.315 2.765 8 P 0 
L 4.315 2.765 4.29 2.74 8 P 0 
P 4.29 2.74 11 P 0 8 0;2=8,4=0
P 4.455 2.738 88 P 0 8 0;0,2=21,4=0
P 4.39 2.741 58 P 0 8 0;0,2=2,4=0
P 4.456 2.783 11 P 0 8 0;2=7,4=1
P 4.355 2.745 11 P 0 8 0;2=7,4=1
P 4.346 2.783 11 P 0 8 0;2=7,4=1
P 4.4 2.785 11 P 0 8 0;2=7,4=1
P 4 2.655 11 P 0 8 0;2=7,4=1
L 3.968 2.68 3.975 2.68 8 P 0 
L 3.975 2.68 4 2.655 8 P 0 
P 3.968 2.68 63 P 0 8 0;0,2=2,4=0
P 4.524 2.895 63 P 0 8 0;0,2=2,4=0
S P 0
OB 4.917 2.481 I
OS 5.021980019685 2.481
OS 5.021980019685 2.462
OC 5.028 2.4477 5.041996161417 2.462009251969 N
OS 5.028 2.402
OS 5.022 2.396
OS 4.92 2.396
OS 4.914 2.402
OS 4.914 2.478
OS 4.917 2.481
OE
SE
P 5.022 2.407 11 P 0 8 0;2=7,4=1
P 4.923 2.408 11 P 0 8 0;2=7,4=1
P 4.972 2.406 11 P 0 8 0;2=7,4=1
P 4.971 2.447 11 P 0 8 0;2=7,4=1
P 4.933 2.466 67 P 0 8 0;0,2=19,4=0
P 5.014 2.474 63 P 0 8 0;0,2=2,4=0
P 5.2871 2.275 11 P 0 8 0;2=7,4=1
S P 0
OB 5.565 1.04 I
OS 5.705 1.04
OS 5.715 1.03
OS 5.715 0.975
OS 5.66256003937 0.975
OC 5.652 0.978019980315 5.6519875 0.958003543307 N
OS 5.628 0.978019980315
OC 5.61743996063 0.975 5.6280125 0.958003543307 N
OS 5.555 0.975
OS 5.555 1.03
OS 5.565 1.04
OE
SE
P 5.64 0.986 58 P 0 8 0;0,2=2,4=0
P 5.7 0.987 67 P 0 8 0;0,2=19,4=0
P 5.62533002 1.02001004 11 P 0 8 0;2=7,4=1
P 5.65933002 1.02 11 P 0 8 0;2=7,4=1
P 5.575 0.998 88 P 0 8 0;0,2=21,4=0
P 3.804 0.816 9 P 0 8 0;2=26,4=1
P 4.23 0.7295 11 P 0 8 0;2=7,4=1
P 2.31 0.715 11 P 0 8 0;2=7,4=1
P 2.31 0.68 11 P 0 8 0;2=7,4=1
P 2.595 0.547 11 P 0 8 0;2=7,4=1
L 2.595 0.605 2.595 0.547 8 P 0 
P 2.595 0.605 63 P 0 8 0;0,2=2,4=0
S P 0
OB 1.833 0.391 I
OS 1.874 0.391
OS 1.885 0.38
OS 1.905 0.36
OS 1.905 0.325
OS 1.885 0.305
OS 1.885 0.285
OS 1.88 0.28
OS 1.83 0.28
OS 1.824 0.286
OS 1.824 0.382
OS 1.833 0.391
OE
SE
P 1.87598002 0.289 9 P 0 8 0;2=26,4=1
L 1.87598002 0.289 1.87598002 0.13781004 8 P 0 
P 1.86 0.33 9 P 0 8 0;2=26,4=1
L 1.83661004 0.289 1.87598002 0.289 8 P 0 
P 1.87598002 0.13781004 62 P 0 8 0;0,2=74,4=0
L 1.83661004 0.289 1.809 0.289 8 P 0 
L 1.809 0.289 1.79723996 0.27723996 8 P 0 
L 1.79723996 0.27723996 1.79723996 0.13781004 8 P 0 
L 1.83661004 0.13781004 1.83661004 0.289 8 P 0 
P 1.83661004 0.13781004 62 P 0 8 0;0,2=74,4=0
P 1.79723996 0.13781004 62 P 0 8 0;0,2=74,4=0
P 1.895 0.33 9 P 0 8 0;2=26,4=1
P 1.87598002 0.369 9 P 0 8 0;2=26,4=1
S P 0
OB 0.756 3.854 I
OS 0.756 3.638
OS 0.749 3.631
OS 0.564 3.631
OS 0.545 3.65
OS 0.545 3.861
OS 0.749 3.861
OS 0.756 3.854
OE
SE
P 0.571 3.845 67 P 0 8 0;0,2=19,4=0
P 0.693 3.736 95 P 0 8 0;0,2=73,4=0
P 0.705 3.82 11 P 0 8 0;2=7,4=1
P 0.665 3.82 11 P 0 8 0;2=7,4=1
P 0.625 3.82 11 P 0 8 0;2=7,4=1
P 0.625 3.78 11 P 0 8 0;2=1,4=1
P 0.625 3.73 11 P 0 8 0;2=1,4=1
P 0.66 3.65 11 P 0 8 0;2=7,4=1
P 0.695 3.65 11 P 0 8 0;2=7,4=1
P 0.73 3.65 11 P 0 8 0;2=7,4=1
P 0.625 3.69 11 P 0 8 0;2=7,4=1
P 0.625 3.65 11 P 0 8 0;2=7,4=1
L 3.63673002 2.39156998 3.63073002 2.38556998 1 P 0 
L 3.63073002 2.38556998 3.57 2.38556998 1 P 0 
P 3.63673002 2.39156998 47 P 0 8 0;0,2=14,4=0
L 3.51 2.37 3.514 2.37 1 P 0 
L 3.514 2.37 3.52956998 2.38556998 1 P 0 
L 3.52956998 2.38556998 3.57 2.38556998 1 P 0 
L 3.45151998 2.36321004 3.50321004 2.36321004 1 P 0 
L 3.50321004 2.36321004 3.51 2.37 1 P 0 
P 3.51 2.37 11 P 0 8 0;2=7,4=1
P 3.45151998 2.36321004 60 P 0 8 0;0,2=49,4=0
P 3.57 2.38556998 89 P 0 8 0;0,2=51,4=0
P 0.29 2.915 11 P 0 8 0;2=1,4=1
P 0.28 2.965 11 P 0 8 0;2=1,4=1
P 0.285 3.02 11 P 0 8 0;2=1,4=1
L 2.977 3.351 2.977 3.319 1 P 0 
L 2.977 3.319 2.9938 3.3022 1 P 0 
L 2.9938 3.3022 3.0425 3.3022 1 P 0 
P 2.977 3.351 9 P 0 8 0;2=9,4=1
P 3.0425 3.3022 94 P 0 8 0;0,2=10,4=0
P 3.36525 3.255 9 P 0 8 0;2=9,4=1
L 3.36525 3.255 3.36126998 3.25101998 1 P 0 
L 3.36126998 3.25101998 3.2815 3.25101998 1 P 0 
P 3.2815 3.25101998 94 P 0 8 0;0,2=10,4=0
P 3.36525 3.205 9 P 0 8 0;2=9,4=1
L 3.36525 3.205 3.34481998 3.22543002 1 P 0 
L 3.34481998 3.22543002 3.2815 3.22543002 1 P 0 
P 3.2815 3.22543002 94 P 0 8 0;0,2=10,4=0
P 1.8062 0.7789 9 P 0 8 0;2=24,4=1
L 3.073 0.613 3.073 0.558 1 P 0 
L 3.073 0.558 3.05 0.535 1 P 0 
L 3.05 0.535 3.05 0.275 1 P 0 
L 3.05 0.275 3.05708002 0.26791998 1 P 0 
L 3.05708002 0.26791998 3.05708002 0.15731004 1 P 0 
P 3.05708002 0.15731004 61 P 0 8 0;0,2=80,4=0
P 3.073 0.613 9 P 0 8 0;2=24,4=1
P 2.54526998 0.339 9 P 0 8 0;2=26,4=1
L 2.5059 0.13781004 2.5059 0.29963002 1 P 0 
L 2.5059 0.29963002 2.54526998 0.339 1 P 0 
P 2.5059 0.13781004 62 P 0 8 0;0,2=74,4=0
P 2.527 0.44 9 P 0 8 0;2=9,4=1
L 2.527 0.44 2.527 0.56821998 1 P 0 
L 2.527 0.56821998 2.51121998 0.584 1 P 0 
P 2.51121998 0.584 58 P 0 8 0;0,2=2,4=0
L 5.78936998 4.27558002 5.73991004 4.27558002 1 P 0 
P 5.73991004 4.27558002 11 P 0 8 0;2=1,4=1
P 5.78936998 4.27558002 24 P 0 8 0;0,2=36,4=0
P 5.38558002 4.27558002 11 P 0 8 0;2=1,4=1
L 5.43503996 4.27558002 5.38558002 4.27558002 1 P 0 
P 5.43503996 4.27558002 24 P 0 8 0;0,2=36,4=0
L 5.55315 4.27558002 5.50368996 4.27558002 1 P 0 
P 5.50368996 4.27558002 11 P 0 8 0;2=1,4=1
P 5.55315 4.27558002 24 P 0 8 0;0,2=36,4=0
L 5.67126004 4.27558002 5.6218 4.27558002 1 P 0 
P 5.6218 4.27558002 11 P 0 8 0;2=1,4=1
P 5.67126004 4.27558002 24 P 0 8 0;0,2=36,4=0
L 3.865 3.65 3.8225 3.6075 1 P 0 
L 3.8225 3.6075 3.7925 3.6075 1 P 0 
L 3.7925 3.6075 3.715 3.53 1 P 0 
L 3.715 3.53 3.715 3.5 1 P 0 
L 3.715 3.5 3.665 3.45 1 P 0 
L 3.665 3.45 3.445 3.45 1 P 0 
L 3.445 3.45 3.34838996 3.35338996 1 P 0 
L 3.34838996 3.35338996 3.2815 3.35338996 1 P 0 
P 3.2815 3.35338996 94 P 0 8 0;0,2=10,4=0
L 5.875 1.9 5.91036998 1.9 1 P 0 
L 5.91036998 1.9 5.91901998 1.90865 1 P 0 
P 5.91901998 1.90865 58 P 0 8 0;0,2=2,4=0
P 5.875 1.9 11 P 0 8 0;2=1,4=1
P 3.865 3.65 11 P 0 8 0;2=7,4=1
L 6.06901998 1.90865 6.06901998 1.86 1 P 0 
L 3.81 3.65 3.81 3.64998996 1 P 0 
L 3.81 3.64998996 3.695 3.53498996 1 P 0 
L 3.695 3.53498996 3.695 3.51001004 1 P 0 
L 3.695 3.51001004 3.65266004 3.46766998 1 P 0 
L 3.65266004 3.46766998 3.43768002 3.46766998 1 P 0 
L 3.43768002 3.46766998 3.34898996 3.37898002 1 P 0 
L 3.34898996 3.37898002 3.2815 3.37898002 1 P 0 
P 3.2815 3.37898002 94 P 0 8 0;0,2=10,4=0
P 6.06901998 1.86 11 P 0 8 0;2=1,4=1
P 6.06901998 1.90865 58 P 0 8 0;0,2=2,4=0
P 3.81 3.65 11 P 0 8 0;2=7,4=1
P 5.98016004 2.04418002 36 P 0 8 0;0,2=22,4=0
L 5.98016004 2.04418002 5.98016004 2.00916004 1 P 0 
L 5.98016004 2.00916004 5.97 1.999 1 P 0 
L 5.96901998 1.95065 5.96901998 1.99801998 1 P 0 
L 5.96901998 1.99801998 5.97 1.999 1 P 0 
P 5.97 1.999 9 P 0 8 0;2=24,4=1
P 5.96901998 1.95065 58 P 0 8 0;0,2=2,4=0
S P 0
OB 2.195069980315 3.22 I
OS 2.205 3.22
OS 2.21 3.215
OS 2.21 3.135
OS 2.2 3.125
OS 2.14825 3.125
OC 2.1312 3.134519980315 2.1312 3.114492027559 N
OS 2.0876 3.134519980315
OC 2.07055 3.125 2.0876 3.114492027559 N
OS 2.055 3.125
OS 2.04 3.11
OS 2.04 2.9
OS 2.07 2.87
OS 2.11326003937 2.87
OC 2.14273996063 2.87 2.128 2.895013287402 N
OS 3.045 2.87
OS 3.09 2.825
OS 3.09 2.69106003937
OC 3.089980019685 2.69 3.119999311024 2.689964370079 N
OC 3.09 2.68893996063 3.119999311024 2.690035629921 N
OS 3.09 2.64606003937
OC 3.089980019685 2.645 3.119999311024 2.644964370079 N
OC 3.09 2.64393996063 3.119999311024 2.645035629921 N
OS 3.09 2.56606003937
OC 3.089980019685 2.565 3.119999311024 2.564964370079 N
OC 3.09 2.56393996063 3.119999311024 2.565035629921 N
OS 3.09 2.44176003937
OS 3.08993996063 2.441519980315
OC 3.088980019685 2.434 3.118998622047 2.433989370079 N
OC 3.08993996063 2.426480019685 3.118998622047 2.434010629921 N
OS 3.09 2.42623996063
OS 3.09 2.30676003937
OS 3.08993996063 2.306519980315
OC 3.088980019685 2.299 3.118998622047 2.298989370079 N
OC 3.08993996063 2.291480019685 3.118998622047 2.299010629921 N
OS 3.09 2.29123996063
OS 3.09 2.175
OS 3.07 2.155
OS 2.765 2.155
OS 2.68 2.07
OS 2.68 1.61
OS 2.705 1.585
OS 3.05 1.585
OS 3.085 1.55
OS 3.085 0.835
OS 3.05 0.8
OS 2.32 0.8
OS 2.25 0.87
OS 1.81 0.87
OS 1.74 0.8
OS 1.706430019685 0.8
OS 1.70626003937 0.800030019685
OC 1.7024 0.80036003937 1.702432185039 0.777997244094 N
OS 1.54246003937 0.80036003937
OS 1.54226003937 0.802130019685
OC 1.49453996063 0.802130019685 1.5184 0.799348425197 N
OS 1.49433996063 0.80036003937
OS 1.485 0.80036003937
OC 1.48113996063 0.800030019685 1.484967814961 0.777997244094 N
OS 1.480969980315 0.8
OS 1.440730019685 0.8
OC 1.4207 0.808019980315 1.4207 0.778997440945 N
OC 1.40221003937 0.80136003937 1.42070738189 0.77900265748 N
OS 1.3767 0.80136003937
OC 1.369319980315 0.80011003937 1.376691633858 0.778998622047 N
OS 1.369 0.8
OS 1.06 0.8
OS 1.02 0.84
OS 1.02 1.75393996063
OC 1.020019980315 1.755 0.990000688976 1.755035629921 N
OC 1.02 1.75606003937 0.990000688976 1.754964370079 N
OS 1.02 1.88393996063
OC 1.020019980315 1.885 0.990000688976 1.885035629921 N
OC 1.02 1.88606003937 0.990000688976 1.884964370079 N
OS 1.02 1.97393996063
OC 1.020019980315 1.975 0.990000688976 1.975035629921 N
OC 1.02 1.97606003937 0.990000688976 1.974964370079 N
OS 1.02 2.01393996063
OC 1.020019980315 2.015 0.990000688976 2.015035629921 N
OC 1.02 2.01606003937 0.990000688976 2.014964370079 N
OS 1.02 2.06393996063
OC 1.020019980315 2.065 0.990000688976 2.065035629921 N
OC 1.02 2.06606003937 0.990000688976 2.064964370079 N
OS 1.02 2.55668996063
OS 1.021019980315 2.55771003937
OS 1.021019980315 2.65028996063
OS 1.02 2.65131003937
OS 1.02 2.835
OS 1.06 2.875
OS 1.108380019685 2.875
OC 1.141619980315 2.875 1.125 2.900002362205 N
OS 1.158380019685 2.875
OC 1.191619980315 2.875 1.175 2.900002362205 N
OS 1.7346 2.875
OC 1.735430019685 2.874980019685 1.735616929134 2.899995472441 N
OS 1.74838996063 2.874980019685
OS 1.748880019685 2.874669980315
OC 1.765 2.869980019685 1.76499242126 2.900002165354 N
OC 1.781619980315 2.875 1.765 2.900002362205 N
OS 1.80361003937 2.875
OC 1.84838996063 2.875 1.826 2.895005610236 N
OS 1.89 2.875
OS 1.945 2.93
OS 1.945 3.16
OS 2.005 3.22
OS 2.126130019685 3.22
OC 2.1388 3.215480019685 2.1388 3.235497637795 N
OS 2.1824 3.215480019685
OC 2.195069980315 3.22 2.1824 3.235497637795 N
OE
OB 1.31526003937 0.988969980315 H
OC 1.435669980315 0.920419980315 1.435662893701 1.060434153543 N
OC 1.435669980315 1.20043996063 1.435669980315 1.060430019685 N
OC 1.30223996063 1.102880019685 1.435663090551 1.060425098425 N
OC 1.29638996063 1.10065 1.298428444882 1.104090551181 Y
OC 1.260669980315 1.11045 1.260664370079 1.040431594488 N
OC 1.260669980315 0.97041003937 1.260669980315 1.040430019685 N
OC 1.30906003937 0.989819980315 1.26067007874 1.040434251969 N
OC 1.31526003937 0.988969980315 1.311821948819 0.986929035433 Y
OE
OB 2.61925 0.99161003937 H
OC 2.60291003937 0.975430019685 2.659679625984 0.934440059055 N
OC 2.596430019685 0.975430019685 2.59967007874 0.977776476378 Y
OC 2.539669980315 1.00445 2.53967007874 0.934431791339 N
OC 2.539669980315 0.86441003937 2.539669980315 0.934430019685 N
OC 2.596430019685 0.893430019685 2.53967007874 0.934428248031 N
OC 2.60291003937 0.893430019685 2.59967007874 0.891083562992 Y
OC 2.659669980315 0.86441003937 2.659669980315 0.934428248031 N
OC 2.71595 0.892780019685 2.65967007874 0.934418700787 N
OC 2.72238996063 0.892780019685 2.719169980315 0.890399704724 Y
OC 2.778669980315 0.86441003937 2.77866988189 0.934418700787 N
OC 2.778669980315 1.00445 2.778669980315 0.934430019685 N
OC 2.77506003937 1.00436003937 2.778608858268 0.934428444882 N
OC 2.772380019685 1.01148996063 2.774855905512 1.008351968504 Y
OC 2.825680019685 1.121430019685 2.685665354331 1.121420275591 N
OC 2.54566003937 1.121430019685 2.68567007874 1.121430019685 N
OC 2.61885 0.99838996063 2.685676476378 1.12142992126 N
OC 2.61925 0.99161003937 2.616941929134 0.994875590551 Y
OE
OB 2.8307 2.57715 H
OC 2.860669980315 2.57041003937 2.860673720472 2.640429133858 N
OC 2.860669980315 2.71045 2.860669980315 2.640430019685 N
OC 2.793030019685 2.65853996063 2.86067007874 2.640426673228 N
OC 2.78628996063 2.65678996063 2.78916515748 2.659570669291 Y
OC 2.685669980315 2.69943996063 2.685669980315 2.559423523622 N
OC 2.825680019685 2.559430019685 2.68567007874 2.559430019685 N
OC 2.82501003937 2.57313996063 2.685668602362 2.559459251969 N
OC 2.8307 2.57715 2.828991732283 2.573532086614 Y
OE
OB 1.31385 2.685980019685 H
OC 1.260669980315 2.71045 1.260669980315 2.64042765748 N
OC 1.260669980315 2.57041003937 1.260669980315 2.640430019685 N
OC 1.327280019685 2.61883996063 1.26067007874 2.640432283465 N
OC 1.334680019685 2.61935 1.331082874016 2.617602559055 Y
OC 1.460669980315 2.540419980315 1.46067007874 2.680439173228 N
OC 1.460669980315 2.82043996063 1.460669980315 2.680430019685 N
OC 1.320880019685 2.68836003937 1.460669980315 2.680425 N
OC 1.31385 2.685980019685 1.316886712598 2.688582775591 Y
OE
SE
P 5.762 3.667 63 P 0 8 0;0,2=2,4=0
L 5.762 3.667 5.801 3.667 8 P 0 
P 4.62 2.245 11 P 0 8 0;2=7,4=1
P 5.801 3.667 11 P 0 8 0;2=7,4=1
P 3.8 2.045 11 P 0 8 0;2=7,4=1
P 1.275 2.905 11 P 0 8 0;2=7,4=1
S P 0
OB 5.08288996063 2.774269980315 I
OS 5.18101003937 2.774269980315
OS 5.187830019685 2.76745
OS 5.187830019685 2.74
OS 5.141 2.74
OS 5.136 2.735
OS 5.136 2.69716003937
OS 5.135980019685 2.69715
OS 5.135980019685 2.64185
OS 5.136 2.64183996063
OS 5.136 2.636
OS 5.1365 2.6355
OS 5.1365 2.6195
OS 5.143 2.613
OS 5.166 2.613
OS 5.170480019685 2.608519980315
OS 5.17028996063 2.6075
OC 5.169980019685 2.604 5.189999212598 2.603990944882 N
OS 5.169980019685 2.58
OC 5.175 2.56675 5.189997047244 2.580007874016 N
OS 5.175 2.5517
OS 5.181 2.5457
OS 5.181 2.401
OS 5.174 2.394
OS 5.052 2.394
OS 5.049969980315 2.396030019685
OS 5.050380019685 2.39721003937
OC 5.052019980315 2.407 5.021999409449 2.406996555118 N
OC 5.048019980315 2.421980019685 5.021998031496 2.407007480315 N
OS 5.048019980315 2.478019980315
OS 5.06 2.49
OS 5.06 2.56
OS 5.0755 2.5755
OS 5.0755 2.580480019685
OS 5.07555 2.5807
OC 5.076019980315 2.585 5.056001377953 2.58501230315 N
OS 5.076019980315 2.609
OC 5.075919980315 2.6109 5.056005314961 2.608899212598 N
OS 5.07583996063 2.61183996063
OS 5.079 2.615
OS 5.079 2.758
OS 5.07943996063 2.75843996063
OS 5.07943996063 2.770819980315
OS 5.08288996063 2.774269980315
OE
SE
P 5.061 2.806 11 P 0 8 0;2=7,4=1
L 5.99 0.925 5.99 0.94 8 P 0 
L 5.99 0.94 6.0566 1.0066 8 P 0 
L 6.0566 1.0066 6.0845 1.0066 8 P 0 
S P 0
OB 3.593 4.242 I
OS 3.638 4.242
OS 3.642 4.238
OS 3.642 4.176
OS 3.638 4.172
OS 3.593 4.172
OS 3.588019980315 4.176980019685
OS 3.588019980315 4.237019980315
OS 3.593 4.242
OE
SE
S P 0
OB 5.233 3.855 I
OS 5.309 3.855
OS 5.317 3.847
OS 5.317 3.796
OS 5.323980019685 3.789019980315
OS 5.323980019685 3.78871003937
OS 5.34271003937 3.769980019685
OS 5.361019980315 3.769980019685
OS 5.365 3.766
OS 5.365 3.723
OS 5.36 3.718
OS 5.232 3.718
OS 5.222 3.728
OS 5.222 3.844
OS 5.233 3.855
OE
SE
S P 0
OB 5.272980019685 3.564980019685 I
OS 5.385019980315 3.564980019685
OS 5.405 3.545
OS 5.405 3.18
OS 5.399 3.174
OS 5.263 3.174
OS 5.257 3.18
OS 5.257 3.549
OS 5.272980019685 3.564980019685
OE
SE
S P 0
OB 5.29486003937 2.246 I
OS 5.31826003937 2.246
OC 5.319 2.245980019685 5.319170177165 2.265995374016 N
OS 5.343019980315 2.245980019685
OS 5.346 2.243
OS 5.346 2.19
OS 5.343 2.187
OS 5.29 2.187
OS 5.286 2.191
OS 5.286 2.243
OS 5.287980019685 2.244980019685
OS 5.28875 2.245030019685
OC 5.294619980315 2.24593996063 5.287109251969 2.27500265748 N
OS 5.29486003937 2.246
OE
SE
S P 0
OB 3.495 1.705 I
OS 3.707 1.705
OS 3.7295 1.6825
OS 3.7295 1.6755
OS 3.73 1.675
OS 3.73 1.621019980315
OS 3.678 1.621019980315
OC 3.67198996063 1.62008996063 3.678020472441 1.601003149606 N
OS 3.6717 1.62
OS 3.56 1.62
OS 3.55 1.63
OS 3.485 1.63
OS 3.485 1.695
OS 3.495 1.705
OE
SE
P 3.705 1.648 88 P 0 8 0;0,2=21,4=0
P 3.515 1.648 88 P 0 8 0;0,2=21,4=0
P 3.575 1.621 58 P 0 8 0;0,2=2,4=0
P 3.995 1.2 11 P 0 8 0;2=7,4=1
P 4.07 1.2 11 P 0 8 0;2=7,4=1
P 4.0805 1.16098996 9 P 0 8 0;2=26,4=1
L 4.092 1.005 4.101 1.014 8 P 0 
L 4.101 1.014 4.101 1.146 8 P 0 
L 4.101 1.146 4.10625 1.15125 8 P 0 
L 4.10625 1.15125 4.10625 1.17786998 8 P 0 
L 4.10625 1.17786998 4.08501004 1.19911004 8 P 0 
L 4.08501004 1.19911004 4.07088996 1.19911004 8 P 0 
L 4.07088996 1.19911004 4.07 1.2 8 P 0 
P 4.092 1.005 9 P 0 8 0;2=26,4=1
P 4.135 0.885 11 P 0 8 0;2=7,4=1
L 4.135 0.885 4.13621998 0.88378002 8 P 0 
L 4.13621998 0.88378002 4.13621998 0.75 8 P 0 
P 4.13621998 0.75 9 P 0 8 0;2=26,4=1
P 4.13401998 0.54196998 9 P 0 8 0;2=26,4=1
P 4.09401998 0.54196998 9 P 0 8 0;2=26,4=1
P 4.05401998 0.54196998 9 P 0 8 0;2=26,4=1
P 4.01401998 0.54196998 9 P 0 8 0;2=26,4=1
P 2.985 1.845 11 P 0 8 0;2=7,4=1
P 2.845 1.907 9 P 0 8 0;2=26,4=1
P 2.845 1.811 9 P 0 8 0;2=26,4=1
P 2.822 1.79121004 11 P 0 8 0;2=7,4=1
P 2.71 1.845 11 P 0 8 0;2=7,4=1
P 2.2 0.69 11 P 0 8 0;2=7,4=1
P 2.15 0.69 11 P 0 8 0;2=7,4=1
P 2.105 0.636 58 P 0 8 0;0,2=2,4=0
L 2.105 0.636 2.15 0.636 8 P 0 
L 2.15 0.636 2.15 0.69 8 P 0 
P 2.15 0.636 58 P 0 8 0;0,2=2,4=0
P 1.9216 0.7784 11 P 0 8 0;2=7,4=1
P 2.0195 0.2905 9 P 0 8 0;2=26,4=1
L 2.03346004 0.13781004 2.03346004 0.27653996 8 P 0 
L 2.03346004 0.27653996 2.0195 0.2905 8 P 0 
P 2.03346004 0.13781004 62 P 0 8 0;0,2=74,4=0
P 1.91535 0.289 9 P 0 8 0;2=26,4=1
L 1.91535 0.13781004 1.91535 0.289 8 P 0 
P 1.91535 0.13781004 62 P 0 8 0;0,2=74,4=0
P 1.78196004 0.50601004 9 P 0 8 0;2=26,4=1
P 1.80341004 0.47225 9 P 0 8 0;2=26,4=1
P 1.63543002 0.52158996 9 P 0 8 0;2=26,4=1
P 3.65101004 1.85158996 9 P 0 8 0;2=26,4=1
P 3.45301004 1.86698996 9 P 0 8 0;2=26,4=1
P 3.473 1.79 11 P 0 8 0;2=7,4=1
P 3.1951 1.90298996 9 P 0 8 0;2=26,4=1
P 3.2911 1.90298996 9 P 0 8 0;2=26,4=1
P 2.958 0.289 9 P 0 8 0;2=26,4=1
L 2.958 0.289 2.97833996 0.26866004 8 P 0 
L 2.97833996 0.26866004 2.97833996 0.13781004 8 P 0 
P 2.97833996 0.13781004 62 P 0 8 0;0,2=74,4=0
P 2.88056998 0.289 9 P 0 8 0;2=26,4=1
L 2.88056998 0.289 2.86023002 0.26866004 8 P 0 
L 2.86023002 0.26866004 2.86023002 0.13781004 8 P 0 
P 2.86023002 0.13781004 62 P 0 8 0;0,2=74,4=0
P 2.95835 0.321 9 P 0 8 0;2=26,4=1
L 2.80051998 0.289 2.82086004 0.26866004 8 P 0 
L 2.82086004 0.26866004 2.82086004 0.13781004 8 P 0 
P 2.82086004 0.13781004 62 P 0 8 0;0,2=74,4=0
P 2.80051998 0.289 9 P 0 8 0;2=26,4=1
P 2.80086998 0.321 9 P 0 8 0;2=26,4=1
P 2.63506998 0.763 9 P 0 8 0;2=26,4=1
P 2.78655 0.763 9 P 0 8 0;2=26,4=1
P 2.73106998 0.763 9 P 0 8 0;2=26,4=1
P 2.7233 0.54871004 11 P 0 8 0;2=7,4=1
L 2.7233 0.54871004 2.7233 0.56331004 7 P 0 
L 2.7233 0.56331004 2.7394 0.57941004 7 P 0 
L 2.7394 0.57941004 2.754 0.57941004 7 P 0 
P 2.754 0.57941004 70 P 0 8 0;0,2=58,4=0
P 2.64338996 0.417 9 P 0 8 0;2=26,4=1
L 2.72308996 0.289 2.70275 0.26866004 8 P 0 
L 2.70275 0.26866004 2.70275 0.13781004 8 P 0 
P 2.70275 0.13781004 62 P 0 8 0;0,2=74,4=0
P 2.72308996 0.289 9 P 0 8 0;2=26,4=1
L 2.64303996 0.289 2.66338002 0.26866004 8 P 0 
L 2.66338002 0.26866004 2.66338002 0.13781004 8 P 0 
P 2.66338002 0.13781004 62 P 0 8 0;0,2=74,4=0
P 2.64303996 0.289 9 P 0 8 0;2=26,4=1
P 2.64338996 0.321 9 P 0 8 0;2=26,4=1
P 2.53421998 0.763 9 P 0 8 0;2=26,4=1
P 2.595 0.701 11 P 0 8 0;2=7,4=1
L 2.595 0.701 2.595 0.655 8 P 0 
P 2.595 0.655 63 P 0 8 0;0,2=2,4=0
P 2.44618996 0.289 9 P 0 8 0;2=26,4=1
L 2.44618996 0.289 2.46653002 0.26866004 8 P 0 
L 2.46653002 0.26866004 2.46653002 0.13781004 8 P 0 
P 2.46653002 0.13781004 62 P 0 8 0;0,2=74,4=0
P 2.54526998 0.289 9 P 0 8 0;2=26,4=1
L 2.54526998 0.13781004 2.54526998 0.289 8 P 0 
P 2.54526998 0.13781004 62 P 0 8 0;0,2=74,4=0
P 2.43821998 0.763 9 P 0 8 0;2=26,4=1
P 2.40508002 0.667 9 P 0 8 0;2=26,4=1
P 2.40508002 0.763 9 P 0 8 0;2=26,4=1
P 2.327 0.291 9 P 0 8 0;2=26,4=1
L 2.327 0.291 2.34841998 0.26958002 8 P 0 
L 2.34841998 0.26958002 2.34841998 0.13781004 8 P 0 
P 2.34841998 0.13781004 62 P 0 8 0;0,2=74,4=0
P 3.56 1.305 11 P 0 8 0;2=7,4=1
P 3.535 1.305 11 P 0 8 0;2=7,4=1
P 3.51 1.305 11 P 0 8 0;2=7,4=1
P 3.54 1.28 11 P 0 8 0;2=7,4=1
P 3.57863996 1.04706998 9 P 0 8 0;2=26,4=1
P 3.593 0.92 9 P 0 8 0;2=26,4=1
P 3.65401998 0.54196998 9 P 0 8 0;2=26,4=1
P 3.61401998 0.54196998 9 P 0 8 0;2=26,4=1
P 3.57401998 0.54196998 9 P 0 8 0;2=26,4=1
P 3.53401998 0.54196998 9 P 0 8 0;2=26,4=1
P 3.49401998 0.54196998 9 P 0 8 0;2=26,4=1
P 3.375 1.226 9 P 0 8 0;2=26,4=1
P 3.375 1.13 9 P 0 8 0;2=26,4=1
P 3.48263996 1.04706998 9 P 0 8 0;2=26,4=1
P 3.48198996 1.085 9 P 0 8 0;2=26,4=1
P 3.38598996 1.085 9 P 0 8 0;2=26,4=1
P 3.33401998 0.54196998 9 P 0 8 0;2=26,4=1
P 3.45401998 0.54196998 9 P 0 8 0;2=26,4=1
P 3.41401998 0.54196998 9 P 0 8 0;2=26,4=1
P 3.37401998 0.54196998 9 P 0 8 0;2=26,4=1
P 3.17025 0.82975 9 P 0 8 0;2=26,4=1
P 3.17401998 0.54196998 9 P 0 8 0;2=26,4=1
P 3.21401998 0.54196998 9 P 0 8 0;2=26,4=1
P 3.25401998 0.54196998 9 P 0 8 0;2=26,4=1
P 3.29401998 0.54196998 9 P 0 8 0;2=26,4=1
P 3.10236998 0.89763002 9 P 0 8 0;2=26,4=1
P 3.035 0.694 11 P 0 8 0;2=7,4=1
L 3.035 0.694 3.019 0.694 8 P 0 
L 3.019 0.694 2.9972 0.6722 8 P 0 
L 2.9972 0.6722 2.9972 0.6678 8 P 0 
P 2.9972 0.6678 63 P 0 8 0;0,2=2,4=0
P 2.98726004 0.49471004 9 P 0 8 0;2=26,4=1
P 2.98726004 0.43528996 9 P 0 8 0;2=26,4=1
P 3.07708002 0.289 9 P 0 8 0;2=26,4=1
P 2.88255 0.763 9 P 0 8 0;2=26,4=1
P 2.95835 0.417 9 P 0 8 0;2=26,4=1
P 2.80086998 0.417 9 P 0 8 0;2=26,4=1
P 3.9845 1.16098996 9 P 0 8 0;2=26,4=1
P 3.9 1.005 9 P 0 8 0;2=26,4=1
L 3.9 1.005 3.8973 1.0023 8 P 0 
L 3.8973 1.0023 3.76838002 1.0023 8 P 0 
L 3.995 1.2 3.99 1.2 8 P 0 
L 3.99 1.2 3.964 1.174 8 P 0 
L 3.964 1.174 3.964 1.005 8 P 0 
P 3.964 1.005 9 P 0 8 0;2=24,4=1
P 3.97401998 0.54196998 9 P 0 8 0;2=26,4=1
P 3.93401998 0.54196998 9 P 0 8 0;2=26,4=1
P 3.89401998 0.54196998 9 P 0 8 0;2=26,4=1
P 3.85401998 0.54196998 9 P 0 8 0;2=26,4=1
P 3.798 1.771 11 P 0 8 0;2=7,4=1
P 3.647 1.694 11 P 0 8 0;2=7,4=1
P 3.676 1.693 11 P 0 8 0;2=7,4=1
P 3.718 1.32 11 P 0 8 0;2=7,4=1
P 3.743 1.32 11 P 0 8 0;2=7,4=1
P 3.718 1.29 11 P 0 8 0;2=7,4=1
P 3.743 1.29 11 P 0 8 0;2=7,4=1
P 3.67 1.26 11 P 0 8 0;2=7,4=1
P 3.84 1.095 11 P 0 8 0;2=7,4=1
L 3.798 1.06 3.803 1.065 8 P 0 
L 3.803 1.065 3.803 1.066 8 P 0 
L 3.803 1.066 3.821 1.084 8 P 0 
L 3.821 1.084 3.829 1.084 8 P 0 
L 3.829 1.084 3.84 1.095 8 P 0 
L 3.84 1.0298 3.8358 1.034 8 P 0 
L 3.8358 1.034 3.825 1.034 8 P 0 
L 3.825 1.034 3.799 1.06 8 P 0 
L 3.799 1.06 3.798 1.06 8 P 0 
P 3.798 1.06 71 P 0 8 0;0,2=21,4=0
P 3.84 1.0298 11 P 0 8 0;2=7,4=1
P 3.76838002 1.0023 11 P 0 8 0;2=7,4=1
P 3.735 0.94 9 P 0 8 0;2=26,4=1
L 3.735 0.94 3.735 0.98675 8 P 0 
L 3.735 0.98675 3.75055 1.0023 8 P 0 
L 3.75055 1.0023 3.76838002 1.0023 8 P 0 
P 3.689 0.92 9 P 0 8 0;2=26,4=1
P 3.805 0.774 9 P 0 8 0;2=26,4=1
P 3.735 0.78 9 P 0 8 0;2=26,4=1
L 3.735 0.78 3.70061004 0.78 8 P 0 
L 3.70061004 0.78 3.665 0.81561004 8 P 0 
L 3.665 0.81561004 3.665 0.855 8 P 0 
L 3.665 0.855 3.735 0.925 8 P 0 
L 3.735 0.925 3.735 0.94 8 P 0 
P 3.795 0.725 9 P 0 8 0;2=24,4=1
L 3.795 0.725 3.765 0.725 8 P 0 
L 3.765 0.725 3.735 0.755 8 P 0 
L 3.735 0.755 3.735 0.78 8 P 0 
L 3.964 1.005 3.9 1.005 8 P 0 
L 4.092 1.005 4.12 1.005 8 P 0 
L 4.12 1.005 4.135 0.99 8 P 0 
L 4.135 0.99 4.135 0.885 8 P 0 
P 4.101 0.97 63 P 0 8 0;0,2=2,4=0
L 4.101 0.97 4.092 0.979 7 P 0 
L 4.092 0.979 4.092 1.005 7 P 0 
L 4.13621998 0.75 4.135 0.74878002 8 P 0 
L 4.135 0.74878002 4.135 0.726 8 P 0 
L 4.135 0.726 4.12 0.711 8 P 0 
L 4.12 0.711 3.809 0.711 8 P 0 
L 3.809 0.711 3.795 0.725 8 P 0 
L 4.13621998 0.75 4.13405 0.75216998 8 P 0 
L 4.13405 0.75216998 4.08 0.75216998 8 P 0 
P 4.08 0.75216998 90 P 0 8 0;0,2=13,4=0
P 3.769 0.97 63 P 0 8 0;0,2=2,4=0
L 3.769 0.97 3.769 1.00168002 8 P 0 
L 3.769 1.00168002 3.76838002 1.0023 8 P 0 
L 3.964 0.97 3.964 1.005 7 P 0 
P 3.964 0.97 63 P 0 8 0;0,2=2,4=0
L 3.964 0.97 3.911 0.97 7 P 0 
P 3.911 0.97 63 P 0 8 0;0,2=2,4=0
P 3.81401998 0.54196998 9 P 0 8 0;2=26,4=1
P 3.77401998 0.54196998 9 P 0 8 0;2=26,4=1
P 3.73401998 0.54196998 9 P 0 8 0;2=26,4=1
P 3.69401998 0.54196998 9 P 0 8 0;2=26,4=1
P 3.551 1.694 11 P 0 8 0;2=7,4=1
P 3.576 1.694 11 P 0 8 0;2=7,4=1
P 3.526 1.694 11 P 0 8 0;2=7,4=1
P 3.501 1.694 11 P 0 8 0;2=7,4=1
P 3.636 1.766 11 P 0 8 0;2=7,4=1
L 3.636 1.766 3.63326998 1.766 8 P 0 
L 3.63326998 1.766 3.61276004 1.74548996 8 P 0 
L 3.61276004 1.74548996 3.604 1.74548996 8 P 0 
P 3.604 1.74548996 58 P 0 8 0;0,2=2,4=0
L 2.76986004 1.85026004 2.71526004 1.85026004 6 P 0 
L 2.71526004 1.85026004 2.71 1.845 6 P 0 
L 2.985 1.845 2.985 1.85 6 P 0 
L 2.985 1.85 2.96505 1.86995 6 P 0 
L 2.96505 1.86995 2.92733996 1.86995 6 P 0 
L 1.8832 0.74 1.9216 0.7784 8 P 0 
L 2.76986004 1.79121004 2.822 1.79121004 6 P 0 
P 3.09645 0.13781004 62 P 0 8 0;0,2=74,4=0
L 3.09645 0.13781004 3.09645 0.26963002 8 P 0 
L 3.09645 0.26963002 3.07708002 0.289 8 P 0 
P 2.86066998 1.04043002 17 P 0 8 0;2=75,4=0
L 4.56091004 1.33161004 4.57843996 1.31408002 8 P 0 
P 4.6053 1.22166998 9 P 0 8 0;2=26,4=1
P 1.041 3.825 9 P 0 8 0;2=26,4=1
P 1.137 3.825 9 P 0 8 0;2=26,4=1
L 1.5086 0.674 1.5194 0.6632 8 P 0 
L 1.5194 0.6632 1.548 0.6632 8 P 0 
S P 0
OB 2.308 4.07 I
OS 2.297 4.081
OS 2.136 4.081
OS 2.132 4.085
OS 1.77 4.085
OS 1.756 4.071
OS 1.756 4.006
OS 1.746019980315 3.996019980315
OS 1.655980019685 3.996019980315
OS 1.65166003937 4.00033996063
OS 1.65166003937 4.04658996063
OS 1.67666003937 4.07158996063
OS 1.67666003937 4.10646003937
OC 1.68461003937 4.1145 1.666981496063 4.123980807087 N
OS 1.68475 4.11475
OS 1.691 4.121
OS 1.691 4.181
OS 1.696 4.186
OS 2.319 4.186
OS 2.34 4.165
OS 2.34 3.841
OS 2.234 3.735
OS 1.731 3.735
OS 1.726 3.74
OS 1.726 3.806
OS 1.706 3.826
OS 1.706 3.871
OS 1.696 3.881
OS 1.656 3.881
OS 1.651 3.886
OS 1.651 3.931
OS 1.656 3.936
OS 1.706 3.936
OS 1.792 3.85
OS 2.207 3.85
OS 2.211 3.846
OS 2.275 3.846
OS 2.308 3.879
OS 2.308 3.88168996063
OS 2.308019980315 3.88171003937
OS 2.308019980315 4.057
OC 2.308 4.05773996063 2.288004625984 4.056829822835 N
OS 2.308 4.07
OE
SE
S P 0
OB 6.386 2.27873996063 I
OS 6.547 2.27873996063
OS 6.57 2.25573996063
OS 6.57 1.95473996063
OS 6.554 1.93873996063
OS 6.198 1.93873996063
OS 6.192 1.94473996063
OS 6.192 1.97973996063
OS 6.199 1.98673996063
OS 6.260980019685 1.98673996063
OC 6.277 1.978719980315 6.277 1.998730019685 N
OS 6.301 1.978719980315
OC 6.317019980315 1.98673996063 6.301 1.998730019685 N
OS 6.342 1.98673996063
OS 6.351 1.99573996063
OS 6.351 1.99673996063
OS 6.382980019685 2.028719980315
OS 6.43928996063 2.028719980315
OS 6.43931003937 2.02873996063
OS 6.464 2.02873996063
OS 6.476 2.04073996063
OS 6.476 2.17873996063
OS 6.467 2.18773996063
OS 6.388 2.18773996063
OS 6.374 2.20173996063
OS 6.374 2.26673996063
OS 6.386 2.27873996063
OE
SE
S P 0
OB 1.652 2.981 I
OS 1.652 3.05
OS 1.71 3.05
OS 1.71 2.928
OS 1.701 2.919
OS 1.701 2.895
OS 1.43 2.895
OS 1.405 2.92
OS 1.405 3.006
OS 1.426 3.027
OS 1.485 3.027
OS 1.499 3.013
OS 1.499 2.93
OS 1.504 2.925
OS 1.59 2.925
OS 1.6 2.935
OS 1.6 2.98
OS 1.651 2.98
OS 1.652 2.981
OE
SE
L 1.155 3.89 1.165 3.88 8 P 0 
L 1.165 3.88 1.165 3.82 8 P 0 
L 1.165 3.82 1.185 3.8 8 P 0 
L 1.185 3.8 1.185 3.79 8 P 0 
S P 0
OB 0.946019980315 2.749 I
OS 0.993 2.749
OS 0.998 2.744
OS 0.998 2.674
OS 0.993 2.669
OS 0.968219980315 2.669
OC 0.967480019685 2.669019980315 0.96730984252 2.649004625984 N
OS 0.94898996063 2.669019980315
OS 0.946019980315 2.67198996063
OS 0.946019980315 2.749
OE
SE
S P 0
OB 1.46426003937 3.71333996063 I
OS 1.5355 3.71333996063
OS 1.5355 3.7
OS 1.5155 3.68
OS 1.4505 3.68
OS 1.4345 3.696
OS 1.4345 3.711980019685
OS 1.457 3.711980019685
OC 1.463930019685 3.713219980315 1.456993996063 3.731998917323 N
OS 1.46426003937 3.71333996063
OE
SE
S P 0
OB 3.56 2.52 I
OS 3.565 2.515
OS 3.565 2.47
OS 3.56 2.465
OS 3.54 2.465
OS 3.535 2.47
OS 3.535 2.52
OS 3.56 2.52
OE
SE
S P 0
OB 5.538 0.947 I
OS 5.653 0.947
OS 5.653 0.827
OS 5.663 0.817
OS 5.663 0.77
OS 5.653 0.76
OS 5.653 0.75616003937
OS 5.651980019685 0.75515
OS 5.651980019685 0.68885
OS 5.653 0.68783996063
OS 5.653 0.61468996063
OS 5.647069980315 0.60876003937
OS 5.565419980315 0.60876003937
OS 5.544869980315 0.62931003937
OS 5.544869980315 0.64553996063
OS 5.5875 0.64553996063
OS 5.58796003937 0.646
OS 5.588 0.646
OS 5.596 0.654
OS 5.596 0.68783996063
OS 5.597019980315 0.68885
OS 5.597019980315 0.74415
OS 5.58715 0.754019980315
OS 5.585980019685 0.754019980315
OS 5.582 0.758
OS 5.561 0.758
OS 5.555 0.764
OS 5.555 0.814
OS 5.547 0.822
OS 5.532 0.822
OS 5.527 0.827
OS 5.527 0.93661003937
OS 5.538 0.947
OE
SE
S P 0
OB 3.612 2.982 I
OS 3.691 2.982
OS 3.702 2.971
OS 3.772 2.971
OS 3.775 2.974
OS 3.83383996063 2.974
OS 3.83385 2.973980019685
OS 3.90115 2.973980019685
OS 3.90116003937 2.974
OS 3.981 2.974
OS 3.985 2.97
OS 3.985 2.862
OS 3.982 2.859
OS 3.949 2.859
OS 3.945 2.863
OS 3.945 2.912
OS 3.94 2.917
OS 3.832 2.917
OS 3.825 2.91
OS 3.825 2.885
OS 3.819830019685 2.879830019685
OC 3.809 2.883019980315 3.808988877953 2.863003248031 N
OS 3.785 2.883019980315
OC 3.77175 2.878 3.785007874016 2.863002952756 N
OS 3.764 2.878
OS 3.76 2.874
OS 3.76 2.853
OS 3.757 2.85
OS 3.614019980315 2.85
OS 3.614019980315 2.87
OC 3.609 2.88326003937 3.593997244094 2.870000098425 N
OC 3.609019980315 2.884 3.594000984252 2.884035334646 N
OS 3.609019980315 2.912
OC 3.605 2.922219980315 3.594002559055 2.911993602362 N
OS 3.605 2.975
OS 3.612 2.982
OE
SE
S P 0
OB 3.253 3.982 I
OS 3.343 3.982
OS 3.348 3.977
OS 3.348 3.932
OS 3.343 3.927
OS 3.333 3.927
OS 3.323 3.917
OS 3.323 3.872
OS 3.32275 3.87175
OC 3.31425 3.86325 3.332 3.854 N
OS 3.308 3.857
OS 3.308 3.797
OS 3.31425 3.79075
OC 3.32275 3.78225 3.332 3.8 N
OS 3.344619980315 3.760380019685
OS 3.433580019685 3.760380019685
OS 3.466869980315 3.72708996063
OS 3.504619980315 3.72708996063
OS 3.505430019685 3.726280019685
OS 3.505430019685 3.69206003937
OS 3.29268996063 3.69206003937
OS 3.29161003937 3.690980019685
OS 3.29091003937 3.69091003937
OC 3.28385 3.6888 3.293013976378 3.671004133858 N
OC 3.267 3.698019980315 3.267 3.678012893701 N
OS 3.243 3.698019980315
OS 3.243 3.972
OS 3.253 3.982
OE
SE
S P 0
OB 3.342 4.042 I
OS 3.293 4.042
OS 3.203 4.132
OS 3.203 4.242
OS 3.208 4.247
OS 3.268 4.247
OS 3.273 4.242
OS 3.273 4.172
OS 3.293 4.152
OS 3.293 4.107
OS 3.303 4.097
OS 3.34 4.097
OS 3.346 4.091
OS 3.346 4.046
OS 3.342 4.042
OE
SE
S P 0
OB 4.147 2.769 I
OS 4.095 2.769
OS 4.079 2.785
OS 4.079 2.955
OS 4.093 2.969
OS 4.146 2.969
OS 4.152 2.963
OS 4.152 2.774
OS 4.147 2.769
OE
SE
S P 0
OB 4.683 2.601 I
OS 4.69 2.608
OS 4.788 2.608
OS 4.795 2.601
OS 4.795 2.519
OS 4.789 2.513
OS 4.687 2.513
OS 4.683 2.517
OS 4.683 2.601
OE
SE
S P 0
OB 5.49 2.139719980315 I
OS 5.497280019685 2.147
OS 5.538 2.147
OS 5.545 2.14
OS 5.545 2.095
OS 5.505 2.055
OS 5.47 2.055
OS 5.44 2.025
OS 5.44 1.835
OS 5.435 1.83
OS 5.4 1.83
OS 5.39 1.84
OS 5.325 1.84
OS 5.325 2.07
OS 5.33 2.075
OS 5.415 2.075
OS 5.435 2.095
OS 5.48 2.095
OS 5.49 2.105
OS 5.49 2.139719980315
OE
SE
S P 0
OB 5.684 2.122 I
OS 5.711969980315 2.122
OS 5.72785 2.106119980315
OS 5.786480019685 2.106119980315
OS 5.786480019685 2.040569980315
OS 5.77591003937 2.03
OS 5.645 2.03
OS 5.615 2.06
OS 5.615 2.15
OS 5.656 2.15
OS 5.684 2.122
OE
SE
S P 0
OB 5.675 2.055 I
OS 5.72548996063 2.055
OC 5.733 2.052980019685 5.733012401575 2.067996653543 N
OS 5.785 2.052980019685
OS 5.785 1.98
OS 5.775 1.97
OS 5.775 1.575
OS 5.72 1.52
OS 5.42 1.52
OS 5.38 1.48
OS 5.38 1.25
OS 5.345 1.215
OS 5.255 1.215
OS 5.255 1.26
OS 5.275 1.28
OS 5.275 1.645
OS 5.335 1.645
OS 5.34525 1.63475
OS 5.34538996063 1.6345
OC 5.3535 1.62638996063 5.363 1.644 N
OS 5.35375 1.62625
OS 5.355 1.625
OS 5.35668996063 1.625
OS 5.35671003937 1.624980019685
OS 5.35675 1.624980019685
OS 5.35703996063 1.62488996063
OC 5.363 1.623980019685 5.363006889764 1.643998917323 N
OS 5.417 1.623980019685
OC 5.42296003937 1.62488996063 5.416993110236 1.643998917323 N
OS 5.42325 1.624980019685
OS 5.465019980315 1.624980019685
OS 5.53 1.56
OS 5.53668996063 1.56
OS 5.53671003937 1.559980019685
OS 5.66828996063 1.559980019685
OS 5.66831003937 1.56
OS 5.69 1.56
OS 5.705 1.575
OS 5.705 2
OS 5.690019980315 2.014980019685
OS 5.690019980315 2.028019980315
OS 5.676980019685 2.028019980315
OS 5.675 2.03
OS 5.675 2.055
OE
SE
S P 0
OB 4.525 3.98 I
OS 4.595 3.98
OS 4.6 3.975
OS 4.6 3.9
OS 4.57 3.9
OS 4.55095 3.88095
OS 4.54971003937 3.881469980315
OC 4.542 3.883019980315 4.541986614173 3.86300265748 N
OS 4.52 3.883019980315
OS 4.52 3.975
OS 4.525 3.98
OE
SE
S P 0
OB 5.075 3.81 I
OS 5.095 3.79
OS 5.095 3.755
OS 5.085 3.745
OS 5.035 3.745
OS 5.025 3.755
OS 5.025 3.855
OS 5.075 3.855
OS 5.075 3.81
OE
SE
S P 0
OB 4.38 2.706980019685 I
OS 4.398019980315 2.706980019685
OS 4.415 2.69
OS 4.48 2.69
OS 4.48 2.63
OS 4.47406003937 2.62406003937
OS 4.392919980315 2.62406003937
OS 4.38 2.63698996063
OS 4.38 2.706980019685
OE
SE
S P 0
OB 1.835 3.315 I
OS 1.905 3.315
OS 1.92 3.3
OS 1.92 2.98
OS 1.90906003937 2.96906003937
OS 1.9077 2.96991003937
OC 1.897 2.973019980315 1.896984448819 2.953004527559 N
OS 1.875019980315 2.973019980315
OS 1.875019980315 3.00328996063
OS 1.875 3.00331003937
OS 1.875 3.005
OS 1.86 3.02
OS 1.86 3.06
OS 1.865 3.065
OS 1.865 3.07168996063
OS 1.865019980315 3.07171003937
OS 1.865019980315 3.14328996063
OS 1.865 3.14331003937
OS 1.865 3.145
OS 1.85 3.16
OS 1.85 3.16668996063
OS 1.850019980315 3.16671003937
OS 1.850019980315 3.16745
OS 1.85028996063 3.16791003937
OC 1.853019980315 3.178 1.833008858268 3.178000098425 N
OS 1.853019980315 3.202
OC 1.85028996063 3.21208996063 1.833008858268 3.201999901575 N
OS 1.850019980315 3.21255
OS 1.850019980315 3.21828996063
OS 1.825019980315 3.24328996063
OS 1.825019980315 3.30328996063
OS 1.825 3.30331003937
OS 1.825 3.305
OS 1.835 3.315
OE
SE
P 6.56038996 1.41205 9 P 0 8 0;2=26,4=1
P 6.56038996 1.37205 9 P 0 8 0;2=26,4=1
P 6.56038996 1.33205 9 P 0 8 0;2=26,4=1
P 6.56038996 1.29205 9 P 0 8 0;2=26,4=1
P 6.56038996 1.25205 9 P 0 8 0;2=26,4=1
P 6.56038996 1.21205 9 P 0 8 0;2=26,4=1
P 6.56038996 1.17205 9 P 0 8 0;2=26,4=1
P 6.56038996 1.13205 9 P 0 8 0;2=26,4=1
P 6.56038996 1.09205 9 P 0 8 0;2=26,4=1
P 5.99 2.094 99 P 0 8 0;0,2=81,4=0
P 5.9645 2.1035 11 P 0 8 0;2=79,4=1
P 6.0155 2.0845 11 P 0 8 0;2=79,4=1
P 0.22703996 0.43635 12 P 0 8 0;2=82,4=0
P 0.19878002 0.36811004 12 P 0 8 0;2=82,4=0
P 0.22703996 0.29986998 12 P 0 8 0;2=82,4=0
P 0.29528002 0.27161004 12 P 0 8 0;2=82,4=0
P 0.36351998 0.29986998 12 P 0 8 0;2=82,4=0
P 0.39178002 0.36811004 12 P 0 8 0;2=82,4=0
P 0.36351998 0.43635 12 P 0 8 0;2=82,4=0
P 0.29528002 0.46461004 12 P 0 8 0;2=82,4=0
P 6.33215 0.72178002 12 P 0 8 0;2=82,4=0
P 6.30388996 0.65353996 12 P 0 8 0;2=82,4=0
P 6.33215 0.5853 12 P 0 8 0;2=82,4=0
P 6.40038996 0.55703996 12 P 0 8 0;2=82,4=0
P 6.46863002 0.5853 12 P 0 8 0;2=82,4=0
P 6.49688996 0.65353996 12 P 0 8 0;2=82,4=0
P 6.46863002 0.72178002 12 P 0 8 0;2=82,4=0
P 6.40038996 0.75003996 12 P 0 8 0;2=82,4=0
P 6.33215 4.24658996 12 P 0 8 0;2=82,4=0
P 6.30388996 4.17835 12 P 0 8 0;2=82,4=0
P 6.33215 4.11011004 12 P 0 8 0;2=82,4=0
P 6.40038996 4.08185 12 P 0 8 0;2=82,4=0
P 6.46863002 4.11011004 12 P 0 8 0;2=82,4=0
P 6.49688996 4.17835 12 P 0 8 0;2=82,4=0
P 6.46863002 4.24658996 12 P 0 8 0;2=82,4=0
P 6.40038996 4.27485 12 P 0 8 0;2=82,4=0
P 5.9945 1.37063002 107 P 0 8 0;0,2=34,4=0
L 5.9945 1.37063002 5.93063002 1.37063002 8 P 0 
L 5.93063002 1.37063002 5.92 1.36 8 P 0 
P 5.92 1.36 11 P 0 8 0;2=1,4=1
L 6.14648002 1.37063002 6.20936998 1.37063002 8 P 0 
L 6.20936998 1.37063002 6.22 1.36 8 P 0 
P 6.22 1.36 11 P 0 8 0;2=7,4=1
P 6.14648002 1.37063002 110 P 0 8 0;0,2=35,4=0
L 1.4213 3.2563 1.40573002 3.24073002 6 P 0 
L 1.40573002 3.24073002 1.352 3.24073002 6 P 0 
L 0.61488996 3.32328996 0.62755 3.31063002 8 P 0 
L 0.62755 3.31063002 0.62755 3.30993996 8 P 0 
L 0.62755 3.30993996 0.631 3.30648996 8 P 0 
L 0.631 3.30648996 0.631 3.29 8 P 0 
L 0.99 3.5 0.995 3.505 6 P 0 
L 0.995 3.505 0.995 3.57795 6 P 0 
L 0.995 3.57795 0.99505 3.578 6 P 0 
L 0.95593002 3.33346998 0.95023996 3.33916004 6 P 0 
L 0.95023996 3.33916004 0.894 3.33916004 6 P 0 
P 5.99 0.925 11 P 0 8 0;2=7,4=1
P 6.0845 1.0066 93 P 0 8 0;0,2=42,4=0
P 5.803 3.857 11 P 0 8 0;2=7,4=1
L 5.803 3.857 5.762 3.857 8 P 0 
L 1.355 3.905 1.355 3.83 8 P 0 
L 1.355 3.96 1.355 3.905 8 P 0 
P 1.355 3.905 11 P 0 8 0;2=7,4=1
P 1.29831004 3.85153996 91 P 0 8 0;0,2=33,4=0
L 1.29831004 3.85153996 1.33346004 3.85153996 8 P 0 
L 1.33346004 3.85153996 1.355 3.83 8 P 0 
L 1.21168996 3.96891998 1.17108002 3.96891998 8 P 0 
L 1.17108002 3.96891998 1.17 3.97 8 P 0 
L 1.21168996 3.96891998 1.26831004 3.96891998 8 P 0 
L 1.26831004 3.96891998 1.27 3.97061004 8 P 0 
L 1.21168996 3.91846004 1.21168996 3.96891998 8 P 0 
P 1.21168996 3.96891998 11 P 0 8 0;2=7,4=1
P 1.21168996 3.91846004 91 P 0 8 0;0,2=33,4=0
L 0.452 2.368 0.42 2.368 8 P 0 
P 0.42 2.368 11 P 0 8 0;2=7,4=1
P 0.452 2.368 58 P 0 8 0;0,2=2,4=0
L 2.0966 3.2655 2.0966 3.315 8 P 0 
L 5.29043002 2.725 5.325 2.725 6 P 0 
P 5.325 2.725 11 P 0 8 0;2=7,4=1
P 5.29043002 2.725 33 P 0 8 0;0,2=14,4=0
L 5.328 2.611 5.3075 2.5905 8 P 0 
L 5.3075 2.5905 5.3075 2.58975 8 P 0 
L 5.3075 2.58975 5.3035 2.58575 8 P 0 
L 5.3035 2.58575 5.3035 2.5748 8 P 0 
P 5.96046998 2.14381998 36 P 0 8 0;0,2=22,4=0
P 5.98016004 2.14381998 36 P 0 8 0;0,2=22,4=0
P 1.6985 2.9895 11 P 0 8 0;2=79,4=1
P 1.6615 3.0405 11 P 0 8 0;2=79,4=1
P 1.62033002 2.97111998 114 P 0 8 0;0,2=32,4=0
P 1.68 3.015 92 P 0 8 0;0,2=83,4=0
P 5.6435 0.6535 11 P 0 8 0;2=79,4=1
P 5.1265 2.6815 11 P 0 8 0;2=79,4=1
P 5.0895 2.7325 11 P 0 8 0;2=79,4=1
P 5.16766998 2.75088002 113 P 0 8 0;0,2=32,4=0
P 5.108 2.707 92 P 0 8 0;0,2=83,4=0
P 5.59271004 3.77636998 82 P 0 8 0;0,2=70,4=0
L 4.1235 3.9715 4.103 3.992 7 P 0 
L 4.103 3.992 4.0489 3.992 7 P 0 
P 4.0489 3.992 85 P 0 8 0;0,2=0,4=0
L 4.1645 3.9715 4.144 3.951 7 P 0 
L 4.144 3.951 4.144 3.8969 7 P 0 
P 4.144 3.8969 39 P 0 8 0;0,2=46,4=0
L 4.1645 4.0125 4.185 3.992 7 P 0 
L 4.185 3.992 4.2391 3.992 7 P 0 
L 4.1235 4.0125 4.144 4.033 7 P 0 
L 4.144 4.033 4.144 4.0871 7 P 0 
P 4.144 4.0871 39 P 0 8 0;0,2=46,4=0
P 4.1915 4.0395 11 P 0 8 0;2=79,4=1
P 4.0965 3.9445 11 P 0 8 0;2=79,4=1
P 4.1235 3.9715 11 P 0 8 0;2=79,4=1
P 4.1645 3.9715 11 P 0 8 0;2=79,4=1
P 4.1645 4.0125 11 P 0 8 0;2=79,4=1
P 4.1235 4.0125 11 P 0 8 0;2=79,4=1
P 4.0965 4.0395 11 P 0 8 0;2=79,4=1
P 4.1915 3.9445 11 P 0 8 0;2=79,4=1
P 4.144 3.992 26 P 0 8 0;0,2=84,4=0
P 4.41975 2.88583996 65 P 0 8 0;0,2=53,4=0
P 4.5 4.07 11 P 0 8 0;2=7,4=1
P 4.31 4.16 11 P 0 8 0;2=7,4=1
P 1.41 2.985 11 P 0 8 0;2=7,4=1
P 1.484 2.95 63 P 0 8 0;0,2=2,4=0
P 1.46 3.007 88 P 0 8 0;0,2=21,4=0
P 1.45 2.965 11 P 0 8 0;2=7,4=1
P 2.0966 3.2655 50 P 0 8 0;0,2=42,4=0
L 2.218 2.895 2.218 2.931 8 P 0 
P 1.51 3.206 58 P 0 8 0;0,2=2,4=0
L 1.51 3.206 1.51 3.242 8 P 0 
P 1.51 3.242 11 P 0 8 0;2=7,4=1
P 1.848 3.26 71 P 0 8 0;0,2=21,4=0
P 1.888 3.105 71 P 0 8 0;0,2=21,4=0
P 1.861 3.19 63 P 0 8 0;0,2=2,4=0
P 1.885 2.981 58 P 0 8 0;0,2=2,4=0
P 1.866 3.04 63 P 0 8 0;0,2=2,4=0
P 1.89 3.26 11 P 0 8 0;2=7,4=1
P 1.895 3.19 11 P 0 8 0;2=7,4=1
P 1.9 3.055 11 P 0 8 0;2=7,4=1
P 1.9 3.015 11 P 0 8 0;2=7,4=1
P 1.65 2.94 11 P 0 8 0;2=7,4=1
P 1.685 2.94 11 P 0 8 0;2=7,4=1
L 1.71456998 2.9 1.69 2.9 6 P 0 
P 1.71456998 2.9 33 P 0 8 0;0,2=14,4=0
P 5.17 2.125 11 P 0 8 0;2=7,4=1
P 4.96 1.79258002 11 P 0 8 0;2=7,4=1
L 4.551 3.27 4.58 3.27 8 P 0 
L 4.58 3.27 4.59 3.26 8 P 0 
P 4.59 3.26 11 P 0 8 0;2=7,4=1
L 4.551 3.27 4.554 3.267 8 P 0 
L 4.554 3.267 4.554 3.22 8 P 0 
P 4.551 3.27 63 P 0 8 0;0,2=2,4=0
P 2.866 1.987 9 P 0 8 0;2=26,4=1
P 2.77 1.987 9 P 0 8 0;2=26,4=1
L 4.44 2.461 4.44 2.5 8 P 0 
L 0.695 1 0.715 0.98 7 P 0 
L 0.715 0.98 0.72461998 0.98 7 P 0 
L 0.72461998 0.98 0.73661998 0.968 7 P 0 
L 0.73661998 0.968 0.73661998 0.9475 7 P 0 
L 0.51771998 1.35 0.51771998 1.305 6 P 0 
L 0.47 1 0.50356998 1 6 P 0 
L 4.294 1.075 4.3245 1.1055 8 P 0 
L 4.3245 1.1055 4.3245 1.123 8 P 0 
L 4.5 1.082 4.4735 1.082 8 P 0 
L 4.4735 1.082 4.4585 1.097 8 P 0 
L 4.4585 1.097 4.4585 1.123 8 P 0 
L 4.5 1.082 4.5 1.14 8 P 0 
L 4.5 1.14 4.48 1.16 8 P 0 
L 4.48 1.16 4.44648996 1.16 8 P 0 
L 4.44648996 1.16 4.4405 1.16598996 8 P 0 
L 4.4843 0.8954 4.5 0.9111 8 P 0 
L 4.5 0.9111 4.5 0.975 8 P 0 
L 4.5 0.975 4.515 0.99 8 P 0 
L 4.515 0.99 4.515 1.067 8 P 0 
L 4.515 1.067 4.5 1.082 8 P 0 
P 4.4585 1.123 63 P 0 8 0;0,2=2,4=0
P 4.3245 1.123 63 P 0 8 0;0,2=2,4=0
P 4.5093 1.22166998 9 P 0 8 0;2=26,4=1
P 0.04 2.85618996 9 P 0 8 0;2=26,4=1
P 0.04 2.81618996 9 P 0 8 0;2=26,4=1
P 0.04 3.13618996 9 P 0 8 0;2=26,4=1
P 0.04 3.09618996 9 P 0 8 0;2=26,4=1
P 0.04 3.05618996 9 P 0 8 0;2=26,4=1
P 0.04 3.01618996 9 P 0 8 0;2=26,4=1
L 4.426 3.745 4.46 3.745 8 P 0 
L 1.045 3.055 1.035 3.055 6 P 0 
L 1.035 3.055 1.01473002 3.07526998 6 P 0 
L 1.01473002 3.07526998 1.01473002 3.12 6 P 0 
L 1.2157 0.6136 1.2157 0.59763996 8 P 0 
L 1.2157 0.59763996 1.195 0.57693996 8 P 0 
L 4.075 3.05 4.105 3.05 8 P 0 
L 4.105 3.05 4.12143002 3.06643002 8 P 0 
L 4.12143002 3.06643002 4.1695 3.06643002 8 P 0 
L 0.606 1.64745 0.606 1.612 8 P 0 
L 0.619 2.79 0.619 2.799 8 P 0 
L 0.619 2.799 0.651 2.831 8 P 0 
L 0.651 2.831 0.67 2.831 8 P 0 
P 3.49 3.03 11 P 0 8 0;2=7,4=1
P 3.555 3.065 11 P 0 8 0;2=7,4=1
L 3.695 2.6265 3.695 2.675 8 P 0 
P 3.695 2.675 11 P 0 8 0;2=7,4=1
P 3.695 2.6265 53 P 0 8 0;0,2=6,4=0
L 3.725 2.32 3.705 2.34 8 P 0 
L 3.705 2.34 3.705 2.384 8 P 0 
P 3.725 2.32 11 P 0 8 0;2=7,4=1
P 3.705 2.384 58 P 0 8 0;0,2=2,4=0
L 4.0355 3.58543002 4.1 3.58543002 8 P 0 
L 3.98 3.4804 3.98 3.52 8 P 0 
L 0.49656998 2.68 0.49656998 2.705 6 P 0 
L 0.49656998 2.705 0.48656998 2.715 6 P 0 
L 0.48656998 2.715 0.485 2.715 6 P 0 
P 0.945 1.05 11 P 0 8 0;2=7,4=1
P 4.635 0.865 11 P 0 8 0;2=7,4=1
L 1.1919 3.578 1.1919 3.6369 6 P 0 
L 1.1919 3.6369 1.2 3.645 6 P 0 
P 0.866 1.413 11 P 0 8 0;2=7,4=1
L 0.595 3.596 0.635 3.596 8 P 0 
L 2.895 3.206 2.895 3.18 8 P 0 
L 2.895 3.18 2.885 3.17 8 P 0 
P 2.885 3.17 11 P 0 8 0;2=7,4=1
P 2.895 3.206 63 P 0 8 0;0,2=2,4=0
L 0.575 2.185 0.54 2.185 7 P 0 
L 0.54 2.185 0.521 2.166 7 P 0 
L 0.521 2.166 0.51643002 2.166 7 P 0 
P 0.83 4.17 11 P 0 8 0;2=7,4=1
P 0.455 1.26 11 P 0 8 0;2=7,4=1
L 0.455 1.22 0.455 1.26 8 P 0 
P 0.455 1.22 58 P 0 8 0;0,2=2,4=0
L 0.175 0.91 0.2055 0.9405 8 P 0 
L 0.2055 0.9405 0.2055 0.9565 8 P 0 
P 0.175 0.91 11 P 0 8 0;2=7,4=1
P 0.2055 0.9565 77 P 0 8 0;0,2=85,4=0
L 0.17 2.045 0.2055 2.0805 8 P 0 
L 0.2055 2.0805 0.2055 2.0965 8 P 0 
P 0.17 2.045 11 P 0 8 0;2=7,4=1
P 0.2055 2.0965 77 P 0 8 0;0,2=85,4=0
P 0.455 1.61 11 P 0 8 0;2=7,4=1
L 0.455 1.644 0.455 1.61 8 P 0 
P 0.455 1.644 58 P 0 8 0;0,2=2,4=0
L 1.2 3.715 1.2 3.72 8 P 0 
L 1.2 3.72 1.195 3.725 8 P 0 
L 1.195 3.725 1.195 3.76 8 P 0 
L 1.195 3.76 1.185 3.77 8 P 0 
L 1.185 3.77 1.185 3.79 8 P 0 
L 1.355 3.83 1.355 3.775 8 P 0 
L 1.355 3.775 1.335 3.755 8 P 0 
L 1.335 3.755 1.32 3.755 8 P 0 
L 1.32 3.755 1.32 3.735 8 P 0 
L 1.32 3.735 1.29 3.705 8 P 0 
P 1.32 3.755 11 P 0 8 0;2=7,4=1
L 1.29 3.65 1.29 3.705 8 P 0 
L 1.29 3.65 1.29 3.63 6 P 0 
L 1.29 3.63 1.27063996 3.61063996 6 P 0 
L 1.27063996 3.61063996 1.27063996 3.578 6 P 0 
P 1.25095 3.06095 11 P 0 8 0;2=7,4=1
L 1.25095 3.12 1.25095 3.06095 6 P 0 
P 1.25095 3.12 40 P 0 8 0;0,2=18,4=0
P 0.95593002 3.33346998 11 P 0 8 0;2=7,4=1
P 0.894 3.33916004 96 P 0 8 0;0,2=18,4=0
P 0.575 2.89 11 P 0 8 0;2=1,4=1
P 0.16 3.025 11 P 0 8 0;2=7,4=1
P 0.16 3.075 11 P 0 8 0;2=7,4=1
P 1.445 3.704 58 P 0 8 0;0,2=2,4=0
P 0.631 3.29 63 P 0 8 0;0,2=2,4=0
P 0.72 3.35 11 P 0 8 0;2=7,4=1
L 0.72 3.3935 0.72 3.35 8 P 0 
P 0.72 3.3935 53 P 0 8 0;0,2=6,4=0
P 0.635 3.596 11 P 0 8 0;2=7,4=1
P 0.595 3.596 58 P 0 8 0;0,2=2,4=0
P 0.671 3.575 9 P 0 8 0;2=26,4=1
P 0.767 3.575 9 P 0 8 0;2=26,4=1
P 1.4213 3.2563 11 P 0 8 0;2=7,4=1
P 1.352 3.24073002 96 P 0 8 0;0,2=18,4=0
P 4.426 3.745 63 P 0 8 0;0,2=2,4=0
L 4.426 3.745 4.426 3.79 8 P 0 
L 4.472 3.5315 4.472 3.475 8 P 0 
P 4.472 3.475 11 P 0 8 0;2=7,4=1
P 4.472 3.5315 73 P 0 8 0;0,2=13,4=0
L 6.4105 2.16141998 6.36 2.16141998 8 P 0 
S P 0
OB 6.025 2.1125 I
OS 6.025 2.0775
OS 5.945 2.0775
OS 5.88 2.0125
OS 5.88 1.9825
OS 5.845 1.9475
OS 5.84 1.9425
OS 5.84 1.9175
OS 5.835 1.9125
OS 5.825 1.9125
OS 5.795 1.9425
OS 5.795 1.9575
OS 5.8 1.9625
OS 5.805 1.9675
OS 5.805 2.0075
OS 5.91 2.1125
OS 5.955 2.1575
OS 5.955 2.1675
OS 5.985 2.1675
OS 5.985 2.1175
OS 5.99 2.1125
OS 6.025 2.1125
OE
SE
L 4.735 3.504 4.71 3.479 8 P 0 
L 4.71 3.479 4.71 3.47 8 P 0 
P 4.735 3.504 58 P 0 8 0;0,2=2,4=0
L 5.601 3.915 5.601 3.8915 8 P 0 
L 5.601 3.8915 5.602 3.8905 8 P 0 
L 5.602 3.8905 5.602 3.865 8 P 0 
P 5.97703002 1.87 11 P 0 8 0;2=7,4=1
L 0.64 2.229 0.675 2.229 8 P 0 
P 0.606 1.612 11 P 0 8 0;2=7,4=1
P 0.606 1.64745 58 P 0 8 0;0,2=2,4=0
L 0.625 1.084 0.625 1.06 8 P 0 
L 0.625 1.06 0.614 1.049 8 P 0 
L 5.291 0.87 5.291 0.92 8 P 0 
L 5.33 0.87 5.291 0.87 8 P 0 
P 5.33 0.87 11 P 0 8 0;2=7,4=1
P 5.291 0.87 63 P 0 8 0;0,2=2,4=0
P 5.291 0.92 63 P 0 8 0;0,2=2,4=0
L 4.81 0.707 4.81 0.7201 8 P 0 
L 4.81 0.7201 4.83033002 0.74043002 8 P 0 
L 4.83033002 0.74043002 4.8855 0.74043002 8 P 0 
L 1.21456998 3.79 1.185 3.79 6 P 0 
P 6.26988996 2.37988996 11 P 0 8 0;2=7,4=1
L 6.26988996 2.31483996 6.26988996 2.37988996 8 P 0 
P 6.26988996 2.31483996 53 P 0 8 0;0,2=6,4=0
P 4.46 3.745 11 P 0 8 0;2=7,4=1
P 4.426 3.79 63 P 0 8 0;0,2=2,4=0
P 3.769 3.385 102 P 0 8 0;0,2=39,4=0
L 3.83 3.415 3.8 3.385 7 P 0 
L 3.8 3.385 3.769 3.385 7 P 0 
P 3.83 3.415 11 P 0 8 0;2=7,4=1
P 3.55 3.325 9 P 0 8 0;2=26,4=1
P 6.335 3.015 11 P 0 8 0;2=7,4=1
L 6.22356004 3.015 6.335 3.015 8 P 0 
P 6.22356004 3.015 43 P 0 8 0;0,2=37,4=0
P 1.667 3.388 11 P 0 8 0;2=7,4=1
P 0.51043002 1.57 33 P 0 8 0;0,2=14,4=0
L 0.51043002 1.57 0.539 1.57 6 P 0 
L 4.22 0.775 4.19 0.775 8 P 0 
L 4.19 0.775 4.165 0.8 8 P 0 
L 4.165 0.8 4.165 0.94 8 P 0 
L 4.165 0.94 4.23 1.005 8 P 0 
L 4.345 0.77 4.34 0.775 8 P 0 
L 4.34 0.775 4.22 0.775 8 P 0 
L 4.345 0.77 4.403 0.77 8 P 0 
L 4.403 0.77 4.414 0.781 8 P 0 
P 1.591 3.504 11 P 0 8 0;2=7,4=1
P 1.045 3.055 11 P 0 8 0;2=7,4=1
P 1.01473002 3.12 40 P 0 8 0;0,2=18,4=0
P 1.42 3.5 11 P 0 8 0;2=7,4=1
P 1.235 3.475 11 P 0 8 0;2=7,4=1
L 1.1 3.64 1.09346998 3.63346998 6 P 0 
L 1.09346998 3.63346998 1.09346998 3.578 6 P 0 
L 1.03441998 3.578 1.03441998 3.63558002 6 P 0 
L 1.03441998 3.63558002 1.03 3.64 6 P 0 
L 1.07378996 3.578 1.07378996 3.63121004 6 P 0 
L 1.07378996 3.63121004 1.065 3.64 6 P 0 
P 1.2 3.715 11 P 0 8 0;2=7,4=1
P 1.409 3.554 11 P 0 8 0;2=7,4=1
P 1.2 3.68 11 P 0 8 0;2=7,4=1
P 1.155 3.89 11 P 0 8 0;2=7,4=1
L 1.17 3.97 1.155 3.955 8 P 0 
L 1.155 3.955 1.155 3.89 8 P 0 
P 1.17 3.97 11 P 0 8 0;2=7,4=1
P 1.27 3.97061004 11 P 0 8 0;2=7,4=1
P 1.29 3.705 11 P 0 8 0;2=7,4=1
P 1.355 3.83 11 P 0 8 0;2=7,4=1
P 1.355 3.96 11 P 0 8 0;2=7,4=1
L 1.355 3.96 1.34438996 3.97061004 8 P 0 
L 1.34438996 3.97061004 1.27 3.97061004 8 P 0 
P 1.185 3.79 11 P 0 8 0;2=7,4=1
P 1.21456998 3.79 33 P 0 8 0;0,2=14,4=0
P 1.32 3.79 11 P 0 8 0;2=7,4=1
L 1.29043002 3.79 1.32 3.79 6 P 0 
P 1.29043002 3.79 33 P 0 8 0;0,2=14,4=0
P 1.29 3.65 11 P 0 8 0;2=7,4=1
P 1.27063996 3.578 40 P 0 8 0;0,2=18,4=0
L 5.762 3.567 5.803 3.567 8 P 0 
P 5.803 3.567 11 P 0 8 0;2=7,4=1
P 5.43 3.967 11 P 0 8 0;2=7,4=1
P 6.165 1.94873996 11 P 0 8 0;2=7,4=1
P 6.4105 2.16141998 87 P 0 8 0;0,2=56,4=0
L 5.001 1.43 5.0395 1.43 8 P 0 
P 1.038 0.7624 11 P 0 8 0;2=7,4=1
L 4.894 1.263 4.9058 1.263 8 P 0 
L 4.9058 1.263 4.9068 1.264 8 P 0 
L 4.9068 1.264 4.933 1.264 8 P 0 
P 4.037 2.593 11 P 0 8 0;2=7,4=1
P 3.978 2.593 11 P 0 8 0;2=7,4=1
L 0.889 0.67 0.89 0.67 8 P 0 
L 0.89 0.67 0.911 0.691 8 P 0 
L 0.911 0.691 0.9575 0.691 8 P 0 
P 4.81 0.707 11 P 0 8 0;2=7,4=1
P 4.8855 0.74043002 94 P 0 8 0;0,2=10,4=0
P 5.2975 1.345 78 P 0 8 0;0,2=57,4=0
P 5.273 1.24 71 P 0 8 0;0,2=21,4=0
P 6.47 1.135 11 P 0 8 0;2=7,4=1
L 6.421 1.135 6.47 1.135 8 P 0 
P 6.421 1.135 63 P 0 8 0;0,2=2,4=0
P 4.595 3.22 11 P 0 8 0;2=7,4=1
L 4.554 3.22 4.595 3.22 8 P 0 
P 4.554 3.22 63 P 0 8 0;0,2=2,4=0
P 4.175 3.52 11 P 0 8 0;2=7,4=1
L 4.175 3.4824 4.175 3.52 8 P 0 
P 4.175 3.4824 49 P 0 8 0;0,2=11,4=0
P 3.98 3.52 11 P 0 8 0;2=7,4=1
P 3.98 3.4804 49 P 0 8 0;0,2=11,4=0
P 3.973 3.207 11 P 0 8 0;2=7,4=1
P 4.075 3.05 11 P 0 8 0;2=7,4=1
P 4.1695 3.06643002 94 P 0 8 0;0,2=10,4=0
P 3.839 3.726 11 P 0 8 0;2=7,4=1
P 4.0355 3.58543002 94 P 0 8 0;0,2=10,4=0
P 4.1 3.58543002 11 P 0 8 0;2=7,4=1
P 5.637 3.569 63 P 0 8 0;0,2=2,4=0
L 5.637 3.524 5.637 3.569 8 P 0 
P 5.637 3.524 11 P 0 8 0;2=1,4=1
P 5.276 3.189 11 P 0 8 0;2=7,4=1
P 5.329 3.189 11 P 0 8 0;2=7,4=1
P 5.386 3.189 11 P 0 8 0;2=7,4=1
P 5.271 3.456 11 P 0 8 0;2=7,4=1
P 5.271 3.406 11 P 0 8 0;2=7,4=1
P 5.324 3.456 11 P 0 8 0;2=7,4=1
P 5.381 3.456 11 P 0 8 0;2=7,4=1
P 5.324 3.406 11 P 0 8 0;2=7,4=1
P 5.381 3.406 11 P 0 8 0;2=7,4=1
P 5.29108002 3.306 111 P 0 8 0;0,2=25,4=0
P 5.762 3.617 63 P 0 8 0;0,2=2,4=0
L 5.762 3.617 5.802 3.617 8 P 0 
P 5.802 3.617 11 P 0 8 0;2=7,4=1
P 5.73143002 3.712 33 P 0 8 0;0,2=14,4=0
L 5.73143002 3.712 5.763 3.712 5 P 0 
P 5.763 3.712 11 P 0 8 0;2=7,4=1
P 5.762 3.807 63 P 0 8 0;0,2=2,4=0
L 5.762 3.757 5.762 3.807 8 P 0 
P 5.762 3.757 63 P 0 8 0;0,2=2,4=0
L 5.762 3.807 5.803 3.807 8 P 0 
L 5.762 3.857 5.762 3.807 8 P 0 
P 5.762 3.857 63 P 0 8 0;0,2=2,4=0
L 5.762 3.757 5.803 3.757 8 P 0 
P 5.803 3.757 11 P 0 8 0;2=7,4=1
P 5.803 3.807 11 P 0 8 0;2=7,4=1
P 5.601 3.915 63 P 0 8 0;0,2=2,4=0
P 5.602 3.865 11 P 0 8 0;2=7,4=1
L 5.645 3.79 5.63136998 3.77636998 5 P 0 
L 5.63136998 3.77636998 5.59271004 3.77636998 5 P 0 
P 5.645 3.79 11 P 0 8 0;2=7,4=1
P 5.48556998 3.912 33 P 0 8 0;0,2=14,4=0
L 5.48556998 3.912 5.48556998 3.877 5 P 0 
P 5.48556998 3.877 11 P 0 8 0;2=1,4=1
P 5.237 3.777 11 P 0 8 0;2=7,4=1
P 5.282 3.777 11 P 0 8 0;2=7,4=1
P 5.237 3.841 11 P 0 8 0;2=7,4=1
P 5.322 3.777 11 P 0 8 0;2=7,4=1
P 5.298 3.827 71 P 0 8 0;0,2=21,4=0
P 5.254 3.738 88 P 0 8 0;0,2=21,4=0
P 5.336 3.738 88 P 0 8 0;0,2=21,4=0
L 5.43503996 4.07875 5.385 4.07875 8 P 0 
P 5.385 4.07875 11 P 0 8 0;2=7,4=1
L 5.55315 4.07875 5.43503996 4.07875 8 P 0 
P 5.43503996 4.07875 24 P 0 8 0;0,2=36,4=0
P 5.55315 4.07875 24 P 0 8 0;0,2=36,4=0
L 5.55315 4.07875 5.67126004 4.07875 8 P 0 
L 5.78936998 4.07875 5.67126004 4.07875 8 P 0 
P 5.67126004 4.07875 24 P 0 8 0;0,2=36,4=0
L 5.90748002 4.07875 5.78936998 4.07875 8 P 0 
P 5.78936998 4.07875 24 P 0 8 0;0,2=36,4=0
L 6.02558996 4.07875 5.90748002 4.07875 8 P 0 
P 5.90748002 4.07875 24 P 0 8 0;0,2=36,4=0
P 6.1437 4.07875 24 P 0 8 0;0,2=36,4=0
L 6.1437 4.07875 6.02558996 4.07875 8 P 0 
P 6.02558996 4.07875 24 P 0 8 0;0,2=36,4=0
L 3.505 2.295 3.64998996 2.295 8 P 0 
L 3.64998996 2.295 3.67 2.31501004 8 P 0 
L 3.67 2.31501004 3.67 2.32 8 P 0 
L 3.67 2.41243002 3.67 2.32 8 P 0 
L 3.67 2.41243002 3.67 2.42243002 8 P 0 
L 3.67 2.42243002 3.65743002 2.435 8 P 0 
L 3.65743002 2.435 3.61 2.435 8 P 0 
L 3.61 2.435 3.605 2.43 8 P 0 
L 3.63673002 2.41243002 3.67 2.41243002 7 P 0 
L 3.67 2.32 3.6423 2.32 7 P 0 
L 3.6423 2.32 3.63673002 2.32556998 7 P 0 
P 0.199 2.83 11 P 0 8 0;2=7,4=1
P 1.2 3.645 11 P 0 8 0;2=7,4=1
P 1.1919 3.578 40 P 0 8 0;0,2=18,4=0
P 1.1 3.64 11 P 0 8 0;2=7,4=1
P 1.09346998 3.578 40 P 0 8 0;0,2=18,4=0
P 1.065 3.64 11 P 0 8 0;2=7,4=1
P 1.07378996 3.578 40 P 0 8 0;0,2=18,4=0
P 1.03 3.64 11 P 0 8 0;2=7,4=1
P 0.99 3.5 11 P 0 8 0;2=7,4=1
P 0.99505 3.578 40 P 0 8 0;0,2=18,4=0
P 0.664 0.774 11 P 0 8 0;2=7,4=1
P 0.833 0.871 11 P 0 8 0;2=7,4=1
P 0.66 0.911 11 P 0 8 0;2=7,4=1
P 0.73661998 0.9475 46 P 0 8 0;0,2=31,4=0
P 0.695 1 11 P 0 8 0;2=7,4=1
P 0.485 2.715 11 P 0 8 0;2=7,4=1
P 0.49656998 2.68 33 P 0 8 0;0,2=14,4=0
L 0.51771998 2.49173996 0.51771998 2.45073996 6 P 0 
P 0.51771998 2.45073996 11 P 0 8 0;2=7,4=1
P 0.51771998 2.49173996 35 P 0 8 0;0,2=43,4=0
P 0.675 2.229 11 P 0 8 0;2=7,4=1
P 0.64 2.229 58 P 0 8 0;0,2=2,4=0
P 0.575 2.185 11 P 0 8 0;2=7,4=1
P 0.51643002 2.166 33 P 0 8 0;0,2=14,4=0
L 0.51771998 1.92086998 0.51771998 1.87986998 6 P 0 
P 0.51771998 1.87986998 11 P 0 8 0;2=7,4=1
P 0.51771998 1.92086998 35 P 0 8 0;0,2=43,4=0
P 0.539 1.57 11 P 0 8 0;2=7,4=1
P 0.51771998 1.305 11 P 0 8 0;2=7,4=1
P 0.51771998 1.35 35 P 0 8 0;0,2=43,4=0
P 0.476 0.689 11 P 0 8 0;2=7,4=1
L 0.443 0.689 0.476 0.689 8 P 0 
P 0.443 0.689 58 P 0 8 0;0,2=2,4=0
L 0.51771998 0.77913996 0.51771998 0.736 6 P 0 
P 0.614 1.049 11 P 0 8 0;2=7,4=1
P 0.625 1.084 58 P 0 8 0;0,2=2,4=0
P 0.51771998 0.736 11 P 0 8 0;2=7,4=1
P 0.51771998 0.77913996 35 P 0 8 0;0,2=43,4=0
P 0.47 1 11 P 0 8 0;2=7,4=1
P 0.677 0.65 11 P 0 8 0;2=7,4=1
P 4.546 1.085 11 P 0 8 0;2=7,4=1
P 0.43705 3.51576004 27 P 0 8 0;2=86,4=0
P 0.43705 3.31655 27 P 0 8 0;2=86,4=0
P 0.24806998 3.47245 27 P 0 8 0;2=86,4=0
P 0.24806998 3.35985 27 P 0 8 0;2=86,4=0
P 0.24606004 3.4315 12 P 0 8 0;2=17,4=0
P 0.4587 3.4315 12 P 0 8 0;2=17,4=0
P 0.44098002 3.4008 12 P 0 8 0;2=17,4=0
P 0.22833996 3.4008 12 P 0 8 0;2=17,4=0
P 3.816 2.68 63 P 0 8 0;0,2=2,4=0
P 4.566 2.845 63 P 0 8 0;0,2=2,4=0
P 0.835 2.524 58 P 0 8 0;0,2=2,4=0
P 0.619 2.79 63 P 0 8 0;0,2=2,4=0
L 3.12 2.17 3.126 2.164 8 P 0 
L 3.126 2.164 3.159 2.164 8 P 0 
P 5.75071998 1.655 11 P 0 8 0;2=7,4=1
P 1.76 4.16 11 P 0 8 0;2=7,4=1
P 2.26 3.785 11 P 0 8 0;2=7,4=1
P 2.215 3.785 11 P 0 8 0;2=7,4=1
P 3.843 3.687 11 P 0 8 0;2=7,4=1
P 0.61488996 3.32328996 11 P 0 8 0;2=7,4=1
P 5.335 1.245 11 P 0 8 0;2=7,4=1
P 5.345 1.3 11 P 0 8 0;2=7,4=1
P 5.345 1.365 11 P 0 8 0;2=7,4=1
P 3.645 2.13 11 P 0 8 0;2=7,4=1
P 3.67 2.13 11 P 0 8 0;2=7,4=1
L 3.55 2.425 3.6 2.425 8 P 0 
L 3.6 2.425 3.605 2.43 8 P 0 
P 3.11 1.935 11 P 0 8 0;2=7,4=1
L 4.31 1.165 4.26063002 1.11563002 8 P 0 
L 4.26063002 1.11563002 4.26063002 1.03563002 8 P 0 
L 4.26063002 1.03563002 4.23 1.005 8 P 0 
P 4.294 1.075 11 P 0 8 0;2=7,4=1
P 4.5 1.082 11 P 0 8 0;2=7,4=1
P 5.41 1.836 58 P 0 8 0;0,2=2,4=0
P 5.35 1.853 88 P 0 8 0;0,2=21,4=0
P 5.385 1.895 11 P 0 8 0;2=7,4=1
P 5.425 1.895 11 P 0 8 0;2=7,4=1
P 5.76458996 1.61971004 11 P 0 8 0;2=7,4=1
P 5.34 1.605 11 P 0 8 0;2=7,4=1
P 5.44 1.59 11 P 0 8 0;2=7,4=1
P 5.723 1.61 71 P 0 8 0;0,2=21,4=0
P 5.39 1.597 88 P 0 8 0;0,2=21,4=0
P 4.54123002 1.70563996 9 P 0 8 0;2=4,4=1
P 4.73806998 1.66626998 9 P 0 8 0;2=4,4=1
P 4.26563996 2.17806998 9 P 0 8 0;2=4,4=1
P 4.6987 1.3513 9 P 0 8 0;2=4,4=1
P 4.57843996 1.31408002 9 P 0 8 0;2=4,4=1
P 4.54121998 1.43005 9 P 0 8 0;2=4,4=1
P 4.42311004 1.54816004 9 P 0 8 0;2=4,4=1
P 4.42311004 1.39066998 9 P 0 8 0;2=4,4=1
P 4.38373996 1.58753002 9 P 0 8 0;2=4,4=1
P 4.38373996 1.50878996 9 P 0 8 0;2=4,4=1
P 4.38373996 1.6269 9 P 0 8 0;2=4,4=1
P 4.34436998 1.54816004 9 P 0 8 0;2=4,4=1
P 4.34436998 1.66626998 9 P 0 8 0;2=4,4=1
P 4.34436998 1.6269 9 P 0 8 0;2=4,4=1
P 4.26563996 1.58753002 9 P 0 8 0;2=4,4=1
P 4.26563996 1.3513 9 P 0 8 0;2=4,4=1
P 4.26563996 1.6269 9 P 0 8 0;2=4,4=1
P 4.26563996 1.66626998 9 P 0 8 0;2=4,4=1
P 4.22626998 1.54816004 9 P 0 8 0;2=4,4=1
P 4.22626998 1.46941998 9 P 0 8 0;2=4,4=1
P 4.22626998 1.6269 9 P 0 8 0;2=4,4=1
P 4.1869 1.58753002 9 P 0 8 0;2=4,4=1
P 4.14753002 1.54816004 9 P 0 8 0;2=4,4=1
P 4.14753002 1.31193002 9 P 0 8 0;2=4,4=1
P 4.10816004 1.54816004 9 P 0 8 0;2=4,4=1
P 4.10816004 1.50878996 9 P 0 8 0;2=4,4=1
P 4.10816004 1.46941998 9 P 0 8 0;2=4,4=1
P 4.06878996 1.46941998 9 P 0 8 0;2=4,4=1
P 4.02941998 1.46941998 9 P 0 8 0;2=4,4=1
P 4.02941998 1.43005 9 P 0 8 0;2=4,4=1
P 3.99005 1.43005 9 P 0 8 0;2=4,4=1
P 3.99005 1.39066998 9 P 0 8 0;2=4,4=1
P 3.95066998 1.39066998 9 P 0 8 0;2=4,4=1
P 3.87193002 2.17806998 9 P 0 8 0;2=4,4=1
P 3.9113 2.05996004 9 P 0 8 0;2=4,4=1
P 3.95066998 1.94185 9 P 0 8 0;2=4,4=1
P 4.10816004 1.86311004 9 P 0 8 0;2=4,4=1
P 3.99005 1.82373996 9 P 0 8 0;2=4,4=1
P 4.1869 1.78436998 9 P 0 8 0;2=4,4=1
P 4.10816004 1.78436998 9 P 0 8 0;2=4,4=1
P 3.99005 1.78436998 9 P 0 8 0;2=4,4=1
P 3.87193002 1.78436998 9 P 0 8 0;2=4,4=1
P 3.95066998 1.78436998 9 P 0 8 0;2=4,4=1
P 3.9113 1.78436998 9 P 0 8 0;2=4,4=1
P 4.22626998 1.70563996 9 P 0 8 0;2=4,4=1
P 4.14753002 1.70563996 9 P 0 8 0;2=4,4=1
P 4.06878996 1.70563996 9 P 0 8 0;2=4,4=1
P 4.02941998 1.70563996 9 P 0 8 0;2=4,4=1
P 3.87193002 1.70563996 9 P 0 8 0;2=4,4=1
P 4.1869 1.66626998 9 P 0 8 0;2=4,4=1
P 4.10816004 1.66626998 9 P 0 8 0;2=4,4=1
P 3.95066998 1.66626998 9 P 0 8 0;2=4,4=1
P 3.87193002 1.6269 9 P 0 8 0;2=4,4=1
P 4.14753002 1.6269 9 P 0 8 0;2=4,4=1
P 4.10816004 1.6269 9 P 0 8 0;2=4,4=1
P 4.02941998 1.6269 9 P 0 8 0;2=4,4=1
P 4.10816004 1.58753002 9 P 0 8 0;2=4,4=1
P 3.99005 1.58753002 9 P 0 8 0;2=4,4=1
P 3.87193002 1.54816004 9 P 0 8 0;2=4,4=1
P 4.02941998 1.54816004 9 P 0 8 0;2=4,4=1
P 3.95066998 1.50878996 9 P 0 8 0;2=4,4=1
P 3.87193002 1.46941998 9 P 0 8 0;2=4,4=1
P 3.87193002 1.39066998 9 P 0 8 0;2=4,4=1
P 3.9113 1.39066998 9 P 0 8 0;2=4,4=1
P 3.87193002 1.3513 9 P 0 8 0;2=4,4=1
P 4.6987 2.17806998 9 P 0 8 0;2=4,4=1
P 4.58058996 2.1387 9 P 0 8 0;2=4,4=1
P 4.50185 1.98121998 9 P 0 8 0;2=4,4=1
P 4.46248002 2.09933002 9 P 0 8 0;2=4,4=1
P 4.38373996 1.94185 9 P 0 8 0;2=4,4=1
P 4.34436998 2.05996004 9 P 0 8 0;2=4,4=1
P 4.22626998 1.90248002 9 P 0 8 0;2=4,4=1
P 4.1869 2.02058996 9 P 0 8 0;2=4,4=1
P 4.14753002 2.1387 9 P 0 8 0;2=4,4=1
P 4.06878996 1.98121998 9 P 0 8 0;2=4,4=1
P 4.02941998 2.09933002 9 P 0 8 0;2=4,4=1
P 4.73806998 2.05996004 9 P 0 8 0;2=4,4=1
P 4.61996004 2.02058996 9 P 0 8 0;2=4,4=1
P 4.65933002 1.90248002 9 P 0 8 0;2=4,4=1
P 4.54121998 1.86311004 9 P 0 8 0;2=4,4=1
P 4.42311004 1.82373996 9 P 0 8 0;2=4,4=1
P 4.6987 1.78436998 9 P 0 8 0;2=4,4=1
P 4.46248002 1.78436998 9 P 0 8 0;2=4,4=1
P 4.50185 1.70563996 9 P 0 8 0;2=4,4=1
P 4.42311004 1.70563996 9 P 0 8 0;2=4,4=1
P 4.34436998 1.70563996 9 P 0 8 0;2=4,4=1
P 4.46248002 1.66626998 9 P 0 8 0;2=4,4=1
P 4.58058996 1.66626998 9 P 0 8 0;2=4,4=1
P 4.38373996 1.66626998 9 P 0 8 0;2=4,4=1
P 4.50185 1.6269 9 P 0 8 0;2=4,4=1
P 4.42311004 1.6269 9 P 0 8 0;2=4,4=1
P 4.61996004 1.58753002 9 P 0 8 0;2=4,4=1
P 4.46248002 1.58753002 9 P 0 8 0;2=4,4=1
P 4.50185 1.54816004 9 P 0 8 0;2=4,4=1
P 4.65933002 1.46941998 9 P 0 8 0;2=4,4=1
L 4.73806998 1.66626998 4.71838996 1.64658996 8 P 0 
L 4.71838996 1.64658996 4.71838996 1.64658002 8 P 0 
L 3.60311004 4.0988 3.60311004 4.09701004 8 P 0 
L 3.60311004 4.09701004 3.5831 4.077 8 P 0 
L 3.5831 4.077 3.564 4.077 8 P 0 
L 0.856 2.637 0.85168996 2.64131004 6 P 0 
L 0.85168996 2.64131004 0.81998996 2.64131004 6 P 0 
L 3.96243002 2.774 3.988 2.774 7 P 0 
L 3.988 2.774 3.998 2.784 7 P 0 
S P 0
OB 0.5 4.33661003937 I
OS 0.5 3.5315
OS 0.039369980315 3.5315
OS 0.030130019685 3.5315
OS 0.030130019685 4.336569980315
OS 0.039469980315 4.34591003937
OS 0.5 4.34591003937
OS 0.5 4.33661003937
OE
SE
S P 0
OB 0.047369980315 3.513330019685 I
OC 0.049980019685 3.511419980315 0.047979232283 3.511424212598 Y
OS 0.049980019685 3.36
OS 0.03003996063 3.36
OS 0.03003996063 3.511419980315
OC 0.03265 3.513319980315 0.03203976378 3.511415551181 Y
OC 0.03998996063 3.512169980315 0.039993503937 3.536191240157 N
OS 0.04 3.512169980315
OC 0.047369980315 3.513330019685 0.039995570866 3.536189862205 N
OE
SE
S P 0
OB 0.049980019685 3.155 I
OS 0.049980019685 2.775
OS 0.03003996063 2.775
OS 0.03003996063 3.155
OS 0.049980019685 3.155
OE
SE
S P 0
OB 0.560430019685 0.528069980315 I
OS 0.560430019685 0.2166
OS 0.55126003937 0.207430019685
OS 0.071380019685 0.207430019685
OS 0.038269980315 0.207430019685
OS 0.030330019685 0.215369980315
OS 0.030330019685 0.528069980315
OS 0.030330019685 0.5353
OS 0.34908996063 0.5353
OS 0.560430019685 0.5353
OS 0.560430019685 0.528069980315
OE
SE
S P 0
OB 1.27081003937 0.55193996063 I
OC 1.2728 0.54973996063 1.27080984252 0.54993976378 Y
OS 1.2728 0.53495
OS 1.26985 0.532
OS 0.63893996063 0.532
OS 0.638630019685 0.53231003937
OS 0.638630019685 0.54136003937
OC 0.637 0.54921003937 0.614630708661 0.540470964567 N
OC 0.638869980315 0.55193996063 0.638864862205 0.549938090551 Y
OS 1.27081003937 0.55193996063
OE
SE
P 0.951 2.728 63 P 0 8 0;0,2=2,4=0
P 0.95048002 2.683 63 P 0 8 0;0,2=2,4=0
P 2.261 4.104 88 P 0 8 0;0,2=21,4=0
P 2.186 4.104 88 P 0 8 0;0,2=21,4=0
P 1.692 4.091 63 P 0 8 0;0,2=2,4=0
P 1.714 4.151 71 P 0 8 0;0,2=21,4=0
P 1.70111998 4.02013002 37 P 0 8 0;0,2=87,4=0
P 1.67946004 4.02013002 37 P 0 8 0;0,2=87,4=0
P 1.65781004 4.02013002 37 P 0 8 0;0,2=87,4=0
P 2.176 3.845 58 P 0 8 0;0,2=2,4=0
P 2.236 3.828 88 P 0 8 0;0,2=21,4=0
P 1.65781004 3.91186998 37 P 0 8 0;0,2=87,4=0
P 1.67946004 3.91186998 37 P 0 8 0;0,2=87,4=0
P 1.70111998 3.91186998 37 P 0 8 0;0,2=87,4=0
P 1.744 3.776 71 P 0 8 0;0,2=21,4=0
P 1.712 3.841 63 P 0 8 0;0,2=2,4=0
P 0.12878002 0.21716998 9 P 0 8 0;2=26,4=1
P 0.16878002 0.21716998 9 P 0 8 0;2=26,4=1
P 0.20878002 0.21716998 9 P 0 8 0;2=26,4=1
P 0.24878002 0.21716998 9 P 0 8 0;2=26,4=1
P 0.08413002 4.33598002 9 P 0 8 0;2=26,4=1
P 0.04413002 4.33598002 9 P 0 8 0;2=26,4=1
P 0.04 4.29618996 9 P 0 8 0;2=26,4=1
P 0.04 4.25618996 9 P 0 8 0;2=26,4=1
P 0.04 4.21618996 9 P 0 8 0;2=26,4=1
P 0.04 4.17618996 9 P 0 8 0;2=26,4=1
P 0.04 4.13618996 9 P 0 8 0;2=26,4=1
P 0.04 4.09618996 9 P 0 8 0;2=26,4=1
P 0.04 4.05618996 9 P 0 8 0;2=26,4=1
P 0.04 4.01618996 9 P 0 8 0;2=26,4=1
P 0.04 3.97618996 9 P 0 8 0;2=26,4=1
P 0.04 3.93618996 9 P 0 8 0;2=26,4=1
P 0.04 3.89618996 9 P 0 8 0;2=26,4=1
P 0.04 3.85618996 9 P 0 8 0;2=26,4=1
P 0.04 3.81618996 9 P 0 8 0;2=26,4=1
P 0.04 3.77618996 9 P 0 8 0;2=26,4=1
P 0.04 3.73618996 9 P 0 8 0;2=26,4=1
P 0.04 3.69618996 9 P 0 8 0;2=26,4=1
P 0.04 3.65618996 9 P 0 8 0;2=26,4=1
P 0.04 3.61618996 9 P 0 8 0;2=26,4=1
P 0.04 3.57618996 9 P 0 8 0;2=26,4=1
P 0.04 3.53618996 9 P 0 8 0;2=26,4=1
P 0.04 3.49618996 9 P 0 8 0;2=26,4=1
P 0.04 3.45618996 9 P 0 8 0;2=26,4=1
P 0.04 3.41618996 9 P 0 8 0;2=26,4=1
P 0.04 3.37618996 9 P 0 8 0;2=26,4=1
P 0.04 2.97618996 9 P 0 8 0;2=26,4=1
P 0.04 2.93618996 9 P 0 8 0;2=26,4=1
P 0.04 2.89618996 9 P 0 8 0;2=26,4=1
P 0.04 0.49618996 9 P 0 8 0;2=26,4=1
P 0.04 0.45618996 9 P 0 8 0;2=26,4=1
P 0.04 0.41618996 9 P 0 8 0;2=26,4=1
P 0.04 0.37618996 9 P 0 8 0;2=26,4=1
P 0.04 0.33618996 9 P 0 8 0;2=26,4=1
P 0.04 0.29618996 9 P 0 8 0;2=26,4=1
P 0.04 0.25618996 9 P 0 8 0;2=26,4=1
P 0.04878002 0.21716998 9 P 0 8 0;2=26,4=1
P 0.08878002 0.21716998 9 P 0 8 0;2=26,4=1
P 2.76413002 4.33598002 9 P 0 8 0;2=26,4=1
P 2.72413002 4.33598002 9 P 0 8 0;2=26,4=1
P 2.68413002 4.33598002 9 P 0 8 0;2=26,4=1
P 2.64413002 4.33598002 9 P 0 8 0;2=26,4=1
P 2.60413002 4.33598002 9 P 0 8 0;2=26,4=1
P 0.55055 0.45073002 9 P 0 8 0;2=26,4=1
P 0.55558002 0.49041004 9 P 0 8 0;2=26,4=1
P 0.57858996 0.52313002 9 P 0 8 0;2=26,4=1
P 0.61463002 0.54048002 9 P 0 8 0;2=26,4=1
P 0.55055 0.29073002 9 P 0 8 0;2=26,4=1
P 0.55055 0.33073002 9 P 0 8 0;2=26,4=1
P 0.55055 0.37073002 9 P 0 8 0;2=26,4=1
P 0.55055 0.41073002 9 P 0 8 0;2=26,4=1
P 0.48878002 0.21716998 9 P 0 8 0;2=26,4=1
P 0.52878002 0.21716998 9 P 0 8 0;2=26,4=1
P 0.55055 0.25073002 9 P 0 8 0;2=26,4=1
P 0.44413002 4.33598002 9 P 0 8 0;2=26,4=1
P 0.40413002 4.33598002 9 P 0 8 0;2=26,4=1
P 0.36413002 4.33598002 9 P 0 8 0;2=26,4=1
P 0.32413002 4.33598002 9 P 0 8 0;2=26,4=1
P 0.28878002 0.21716998 9 P 0 8 0;2=26,4=1
P 0.32878002 0.21716998 9 P 0 8 0;2=26,4=1
P 0.36878002 0.21716998 9 P 0 8 0;2=26,4=1
P 0.40878002 0.21716998 9 P 0 8 0;2=26,4=1
P 0.44878002 0.21716998 9 P 0 8 0;2=26,4=1
P 0.28413002 4.33598002 9 P 0 8 0;2=26,4=1
P 0.24413002 4.33598002 9 P 0 8 0;2=26,4=1
P 0.20413002 4.33598002 9 P 0 8 0;2=26,4=1
P 0.16413002 4.33598002 9 P 0 8 0;2=26,4=1
P 0.12413002 4.33598002 9 P 0 8 0;2=26,4=1
P 0.889 0.67 11 P 0 8 0;2=7,4=1
P 0.9575 0.691 83 P 0 8 0;0,2=6,4=0
P 0.6546 0.54196998 9 P 0 8 0;2=26,4=1
P 0.6946 0.54196998 9 P 0 8 0;2=26,4=1
P 0.7346 0.54196998 9 P 0 8 0;2=26,4=1
P 0.7746 0.54196998 9 P 0 8 0;2=26,4=1
P 0.8146 0.54196998 9 P 0 8 0;2=26,4=1
P 0.64413002 4.33598002 9 P 0 8 0;2=26,4=1
P 0.60413002 4.33598002 9 P 0 8 0;2=26,4=1
P 0.56413002 4.33598002 9 P 0 8 0;2=26,4=1
P 0.52413002 4.33598002 9 P 0 8 0;2=26,4=1
P 0.48413002 4.33598002 9 P 0 8 0;2=26,4=1
P 0.8575 2.0275 11 P 0 8 0;2=7,4=1
L 0.8575 2.0275 0.86206998 2.03206998 8 P 0 
L 0.86206998 2.03206998 0.86206998 2.091 8 P 0 
P 0.86206998 2.091 76 P 0 8 0;0,2=88,4=0
P 1.195 0.57693996 11 P 0 8 0;2=7,4=1
P 1.2157 0.6136 63 P 0 8 0;0,2=2,4=0
P 0.8546 0.54196998 9 P 0 8 0;2=26,4=1
P 0.8946 0.54196998 9 P 0 8 0;2=26,4=1
P 0.9346 0.54196998 9 P 0 8 0;2=26,4=1
P 0.9746 0.54196998 9 P 0 8 0;2=26,4=1
P 0.80413002 4.33598002 9 P 0 8 0;2=26,4=1
P 0.76413002 4.33598002 9 P 0 8 0;2=26,4=1
P 0.72413002 4.33598002 9 P 0 8 0;2=26,4=1
P 0.68413002 4.33598002 9 P 0 8 0;2=26,4=1
P 0.66 4.19 11 P 0 8 0;2=7,4=1
P 0.67 2.831 9 P 0 8 0;2=26,4=1
P 0.79248002 2.661 9 P 0 8 0;2=26,4=1
L 0.81998996 2.661 0.79248002 2.661 6 P 0 
P 0.81998996 2.661 45 P 0 8 0;0,2=48,4=0
P 0.80148002 2.53648002 11 P 0 8 0;2=7,4=1
L 0.835 2.524 0.83 2.524 8 P 0 
L 0.83 2.524 0.829 2.525 8 P 0 
L 0.829 2.525 0.81296004 2.525 8 P 0 
L 0.81296004 2.525 0.80148002 2.53648002 8 P 0 
P 0.715 2.478 11 P 0 8 0;2=7,4=1
L 0.715 2.444 0.715 2.478 8 P 0 
P 0.715 2.444 58 P 0 8 0;0,2=2,4=0
P 0.714 2.217 11 P 0 8 0;2=7,4=1
L 0.714 2.252 0.714 2.217 8 P 0 
P 0.714 2.252 58 P 0 8 0;0,2=2,4=0
P 0.74593002 2.02206998 11 P 0 8 0;2=7,4=1
L 0.74593002 2.091 0.74593002 2.02206998 8 P 0 
P 0.74593002 2.091 76 P 0 8 0;0,2=88,4=0
P 1.0146 0.54196998 9 P 0 8 0;2=26,4=1
P 1.0546 0.54196998 9 P 0 8 0;2=26,4=1
P 1.0946 0.54196998 9 P 0 8 0;2=26,4=1
P 1.1346 0.54196998 9 P 0 8 0;2=26,4=1
P 1.1746 0.54196998 9 P 0 8 0;2=26,4=1
P 1.00413002 4.33598002 9 P 0 8 0;2=26,4=1
P 0.96413002 4.33598002 9 P 0 8 0;2=26,4=1
P 0.92413002 4.33598002 9 P 0 8 0;2=26,4=1
P 0.88413002 4.33598002 9 P 0 8 0;2=26,4=1
P 0.84413002 4.33598002 9 P 0 8 0;2=26,4=1
P 1.025 4.2 11 P 0 8 0;2=7,4=1
P 0.94 4.2 11 P 0 8 0;2=7,4=1
P 0.858 2.87451998 9 P 0 8 0;2=9,4=1
P 0.988 2.724 11 P 0 8 0;2=7,4=1
P 0.987 2.683 11 P 0 8 0;2=1,4=1
P 0.856 2.637 9 P 0 8 0;2=26,4=1
P 0.81998996 2.64131004 45 P 0 8 0;0,2=48,4=0
P 0.93031998 2.46476998 11 P 0 8 0;2=7,4=1
P 0.872 2.583 11 P 0 8 0;2=7,4=1
L 0.907 2.58048002 0.87723002 2.58048002 8 P 0 
L 0.87723002 2.58048002 0.87671004 2.581 8 P 0 
L 0.87671004 2.581 0.874 2.581 8 P 0 
L 0.874 2.581 0.872 2.583 8 P 0 
P 0.907 2.58048002 63 P 0 8 0;0,2=2,4=0
P 0.868 2.3 9 P 0 8 0;2=26,4=1
L 0.868 2.3 0.868 2.278 8 P 0 
L 0.868 2.278 0.8594 2.2694 8 P 0 
L 0.8594 2.2694 0.8594 2.2465 8 P 0 
P 0.8594 2.2465 50 P 0 8 0;0,2=42,4=0
P 1.401 3.956 11 P 0 8 0;2=7,4=1
L 1.435 3.946 1.411 3.946 7 P 0 
L 1.411 3.946 1.401 3.956 7 P 0 
P 1.435 3.946 63 P 0 8 0;0,2=2,4=0
P 1.40123002 3.91603996 11 P 0 8 0;2=7,4=1
L 1.40123002 3.91603996 1.40123002 3.91376998 7 P 0 
L 1.40123002 3.91376998 1.414 3.901 7 P 0 
L 1.414 3.901 1.45056998 3.901 7 P 0 
P 1.45056998 3.901 33 P 0 8 0;0,2=14,4=0
P 1.48 3.7 11 P 0 8 0;2=7,4=1
P 1.38163002 0.21716998 9 P 0 8 0;2=26,4=1
P 1.42163002 0.21716998 9 P 0 8 0;2=26,4=1
P 1.46163002 0.21716998 9 P 0 8 0;2=26,4=1
P 1.50163002 0.21716998 9 P 0 8 0;2=26,4=1
P 1.54163002 0.21716998 9 P 0 8 0;2=26,4=1
P 1.36413002 4.33598002 9 P 0 8 0;2=26,4=1
P 1.32413002 4.33598002 9 P 0 8 0;2=26,4=1
P 1.28413002 4.33598002 9 P 0 8 0;2=26,4=1
P 1.24413002 4.33598002 9 P 0 8 0;2=26,4=1
P 1.20413002 4.33598002 9 P 0 8 0;2=26,4=1
P 1.515 3.7 11 P 0 8 0;2=7,4=1
P 1.385 0.75 9 P 0 8 0;2=26,4=1
P 1.44 0.625 9 P 0 8 0;2=26,4=1
P 1.5184 0.79935 9 P 0 8 0;2=26,4=1
P 1.2146 0.54196998 9 P 0 8 0;2=26,4=1
P 1.2546 0.54196998 9 P 0 8 0;2=26,4=1
P 1.2945 0.53916998 9 P 0 8 0;2=26,4=1
P 1.3292 0.51926004 9 P 0 8 0;2=26,4=1
P 1.34976998 0.48496004 9 P 0 8 0;2=26,4=1
P 1.35298996 0.44508996 9 P 0 8 0;2=26,4=1
P 1.35298996 0.40508996 9 P 0 8 0;2=26,4=1
P 1.35298996 0.36508996 9 P 0 8 0;2=26,4=1
P 1.35298996 0.32508996 9 P 0 8 0;2=26,4=1
P 1.35298996 0.28508996 9 P 0 8 0;2=26,4=1
P 1.35298996 0.24508996 9 P 0 8 0;2=26,4=1
P 1.16413002 4.33598002 9 P 0 8 0;2=26,4=1
P 1.12413002 4.33598002 9 P 0 8 0;2=26,4=1
P 1.08413002 4.33598002 9 P 0 8 0;2=26,4=1
P 1.04413002 4.33598002 9 P 0 8 0;2=26,4=1
P 1.96413002 4.33598002 9 P 0 8 0;2=26,4=1
P 1.92413002 4.33598002 9 P 0 8 0;2=26,4=1
P 1.915 4.13 11 P 0 8 0;2=7,4=1
P 1.8832 0.74 97 P 0 8 0;0,2=59,4=0
P 1.88413002 4.33598002 9 P 0 8 0;2=26,4=1
P 1.84413002 4.33598002 9 P 0 8 0;2=26,4=1
P 1.80413002 4.33598002 9 P 0 8 0;2=26,4=1
P 1.76413002 4.33598002 9 P 0 8 0;2=26,4=1
P 1.746 4.061 11 P 0 8 0;2=7,4=1
P 1.746 4.106 11 P 0 8 0;2=1,4=1
P 1.751 3.871 11 P 0 8 0;2=7,4=1
P 1.746 4.016 11 P 0 8 0;2=7,4=1
P 1.751 3.826 11 P 0 8 0;2=1,4=1
P 1.786 3.746 11 P 0 8 0;2=7,4=1
P 1.786 3.786 11 P 0 8 0;2=7,4=1
P 2.0966 3.315 9 P 0 8 0;2=26,4=1
P 1.72413002 4.33598002 9 P 0 8 0;2=26,4=1
P 1.68413002 4.33598002 9 P 0 8 0;2=26,4=1
P 1.64413002 4.33598002 9 P 0 8 0;2=26,4=1
P 1.60413002 4.33598002 9 P 0 8 0;2=26,4=1
P 1.56413002 4.33598002 9 P 0 8 0;2=26,4=1
P 1.671 4.056 9 P 0 8 0;2=26,4=1
P 1.5086 0.674 11 P 0 8 0;2=1,4=1
P 1.548 0.6632 58 P 0 8 0;0,2=2,4=0
P 1.59111998 0.45653996 9 P 0 8 0;2=26,4=1
P 1.60736004 0.49308996 9 P 0 8 0;2=26,4=1
P 1.58795 0.29666998 9 P 0 8 0;2=26,4=1
P 1.58795 0.33666998 9 P 0 8 0;2=26,4=1
P 1.58795 0.37666998 9 P 0 8 0;2=26,4=1
P 1.58795 0.41666998 9 P 0 8 0;2=26,4=1
P 1.58163002 0.21716998 9 P 0 8 0;2=26,4=1
P 1.58795 0.25666998 9 P 0 8 0;2=26,4=1
P 1.52413002 4.33598002 9 P 0 8 0;2=26,4=1
P 1.48413002 4.33598002 9 P 0 8 0;2=26,4=1
P 1.44413002 4.33598002 9 P 0 8 0;2=26,4=1
P 1.40413002 4.33598002 9 P 0 8 0;2=26,4=1
P 2.56413002 4.33598002 9 P 0 8 0;2=26,4=1
P 2.52413002 4.33598002 9 P 0 8 0;2=26,4=1
P 2.48413002 4.33598002 9 P 0 8 0;2=26,4=1
P 2.44413002 4.33598002 9 P 0 8 0;2=26,4=1
P 2.40413002 4.33598002 9 P 0 8 0;2=26,4=1
P 2.36413002 4.33598002 9 P 0 8 0;2=26,4=1
P 2.32413002 4.33598002 9 P 0 8 0;2=26,4=1
P 2.28413002 4.33598002 9 P 0 8 0;2=26,4=1
P 2.295 4.15 11 P 0 8 0;2=7,4=1
P 2.285 3.825 11 P 0 8 0;2=1,4=1
P 2.24413002 4.33598002 9 P 0 8 0;2=26,4=1
P 2.20413002 4.33598002 9 P 0 8 0;2=26,4=1
P 2.16413002 4.33598002 9 P 0 8 0;2=26,4=1
P 2.12413002 4.33598002 9 P 0 8 0;2=26,4=1
P 2.176 4.151 11 P 0 8 0;2=7,4=1
P 2.256 4.151 11 P 0 8 0;2=7,4=1
P 2.215 4.15 11 P 0 8 0;2=7,4=1
P 2.18 3.811 11 P 0 8 0;2=7,4=1
P 2.218 2.895 9 P 0 8 0;2=26,4=1
P 2.218 2.931 58 P 0 8 0;0,2=2,4=0
P 2.173 2.895 9 P 0 8 0;2=26,4=1
P 2.083 2.895 9 P 0 8 0;2=26,4=1
P 2.08413002 4.33598002 9 P 0 8 0;2=26,4=1
P 2.04413002 4.33598002 9 P 0 8 0;2=26,4=1
P 2.00413002 4.33598002 9 P 0 8 0;2=26,4=1
S P 0
OB 6.51838996063 0.65353996063 I
OC 6.51838996063 0.65353996063 6.40038996063 0.65353996063 Y
OE
OB 6.47538996063 0.65353996063 H
OC 6.47538996063 0.65353996063 6.40038996063 0.65353996063 N
OE
SE
S P 0
OB 0.413280019685 3.73031003937 I
OC 0.413280019685 3.73031003937 0.295280019685 3.73031003937 Y
OE
OB 0.370280019685 3.73031003937 H
OC 0.370280019685 3.73031003937 0.295280019685 3.73031003937 N
OE
SE
P 0.22703996 3.79855 12 P 0 8 0;2=82,4=0
P 0.19878002 3.73031004 12 P 0 8 0;2=82,4=0
P 0.22703996 3.66206998 12 P 0 8 0;2=82,4=0
P 0.29528002 3.63381004 12 P 0 8 0;2=82,4=0
P 0.36351998 3.66206998 12 P 0 8 0;2=82,4=0
P 0.39178002 3.73031004 12 P 0 8 0;2=82,4=0
P 0.36351998 3.79855 12 P 0 8 0;2=82,4=0
P 0.29528002 3.82681004 12 P 0 8 0;2=82,4=0
P 6.19961004 2.21273996 9 P 0 8 0;2=26,4=1
P 6.19961004 2.30873996 9 P 0 8 0;2=26,4=1
P 4.3445 1.16598996 9 P 0 8 0;2=26,4=1
P 4.4405 1.16598996 9 P 0 8 0;2=26,4=1
P 3.45301004 1.96298996 9 P 0 8 0;2=26,4=1
P 3.65101004 1.94758996 9 P 0 8 0;2=26,4=1
P 4.44 2.63 11 P 0 8 0;2=7,4=1
P 4.395 2.665 11 P 0 8 0;2=7,4=1
P 4.455 2.672 88 P 0 8 0;0,2=21,4=0
P 4.39 2.699 58 P 0 8 0;0,2=2,4=0
L 4.566 2.845 4.6 2.845 8 P 0 
L 4.566 2.895 4.6 2.895 8 P 0 
P 4.6 2.895 11 P 0 8 0;2=7,4=1
P 4.6 2.845 11 P 0 8 0;2=7,4=1
L 6.141 2.278 6.141 2.241 9 P 0 
L 6.071 2.225 6.125 2.225 9 P 0 
L 6.125 2.225 6.141 2.241 9 P 0 
L 6.071 2.27 6.105 2.27 9 P 0 
L 5.51 2.35043002 5.51 2.36498996 7 P 0 
L 5.51 2.36498996 5.523 2.37798996 7 P 0 
L 5.523 2.37798996 5.523 2.387 7 P 0 
L 5.523 2.387 5.538 2.402 7 P 0 
L 4.465 2.895 4.45498996 2.895 7 P 0 
L 4.45498996 2.895 4.44583002 2.88583996 7 P 0 
L 4.44583002 2.88583996 4.41975 2.88583996 7 P 0 
P 5.76 2.087 88 P 0 8 0;0,2=21,4=0
P 3.42 3.76 11 P 0 8 0;2=7,4=1
P 3.385 3.76 11 P 0 8 0;2=7,4=1
P 3.315 3.76 11 P 0 8 0;2=7,4=1
P 3.26 3.74 11 P 0 8 0;2=7,4=1
P 3.48 3.718 88 P 0 8 0;0,2=21,4=0
P 3.4 3.718 88 P 0 8 0;0,2=21,4=0
P 3.255 3.706 58 P 0 8 0;0,2=2,4=0
P 3.32 3.718 88 P 0 8 0;0,2=21,4=0
S P 0
OB 0.50888996063 4.326 I
OC 0.50698996063 4.32861003937 0.508895767717 4.328000787402 Y
OC 0.50815 4.335980019685 0.48413011811 4.335984448819 N
OS 0.50815 4.33598996063
OC 0.507 4.343330019685 0.484128740157 4.335986515748 N
OC 0.5089 4.34593996063 0.508904429134 4.34394015748 Y
OS 6.561019980315 4.34593996063
OC 6.57035 4.33661003937 6.56102007874 4.33661003937 Y
OS 6.57035 3.05858996063
OC 6.563630019685 3.05566003937 6.566351082677 3.058590354331 Y
OC 6.5522 3.06088996063 6.550008759843 3.040995767717 N
OS 6.550419980315 3.06108996063
OS 6.550419980315 4.326
OS 0.50888996063 4.326
OE
SE
S P 0
OB 6.520869980315 2.42521003937 I
OS 6.52238996063 2.42483996063
OS 6.52238996063 2.414369980315
OC 6.57035 2.364680019685 6.572111220472 2.41437007874 N
OS 6.57035 2.3
OS 6.550419980315 2.3
OS 6.550419980315 2.348180019685
OC 6.50306003937 2.405169980315 6.572106889764 2.414375885827 Y
OS 6.50306003937 2.40935
OC 6.50246003937 2.41421003937 6.483047933071 2.409346456693 N
OS 6.50246003937 2.42711003937
OC 6.508619980315 2.430469980315 6.506459251969 2.427104724409 Y
OC 6.520869980315 2.42521003937 6.530515551181 2.464568503937 N
OE
SE
S P 0
OB 6.550419980315 1.915 I
OS 6.57035 1.915
OS 6.57035 0.922
OS 6.550419980315 0.922
OS 6.550419980315 1.915
OE
SE
S P 0
OB 6.18926003937 0.55193996063 I
OC 6.19116003937 0.549330019685 6.189254232283 0.549939173228 Y
OC 6.19 0.541969980315 6.214017814961 0.541955905512 N
OS 6.19 0.54196003937
OC 6.19115 0.534619980315 6.214021259843 0.541963484252 N
OC 6.18925 0.53201003937 6.189245570866 0.53400984252 Y
OS 3.161419980315 0.53201003937
OC 3.09201003937 0.4626 3.161419980315 0.462600098425 N
OS 3.09201003937 0.262
OS 3.07943996063 0.262
OS 3.07943996063 0.267919980315
OC 3.07236003937 0.28425 3.05706742126 0.26792007874 N
OS 3.07236003937 0.46978996063
OC 3.161419980315 0.55193996063 3.161419980315 0.462589370079 Y
OS 6.18926003937 0.55193996063
OE
SE
S P 0
OB 6.205 0.54133996063 I
OS 6.20551003937 0.54133996063
OS 6.20551003937 0.901569980315
OS 6.569880019685 0.901569980315
OS 6.569880019685 0.54058996063
OS 6.561769980315 0.532480019685
OS 6.205 0.532480019685
OS 6.205 0.54133996063
OE
SE
S P 0
OB 6.20551003937 3.9252 I
OS 6.20551003937 4.33661003937
OS 6.20551003937 4.3456
OS 6.562719980315 4.3456
OS 6.57018996063 4.338130019685
OS 6.57018996063 3.9252
OS 6.20551003937 3.9252
OE
SE
P 6.56038996 1.81205 9 P 0 8 0;2=26,4=1
P 6.56038996 1.77205 9 P 0 8 0;2=26,4=1
P 6.56038996 1.73205 9 P 0 8 0;2=26,4=1
P 6.56038996 1.69205 9 P 0 8 0;2=26,4=1
P 6.56038996 1.65205 9 P 0 8 0;2=26,4=1
P 6.56038996 1.61205 9 P 0 8 0;2=26,4=1
P 6.56038996 1.57205 9 P 0 8 0;2=26,4=1
P 6.56038996 1.53205 9 P 0 8 0;2=26,4=1
P 6.56038996 1.49205 9 P 0 8 0;2=26,4=1
P 6.56038996 1.45205 9 P 0 8 0;2=26,4=1
P 6.56038996 1.05205 9 P 0 8 0;2=26,4=1
P 6.56038996 1.01205 9 P 0 8 0;2=26,4=1
P 6.56038996 0.97205 9 P 0 8 0;2=26,4=1
P 6.56038996 0.93205 9 P 0 8 0;2=26,4=1
P 6.56038996 0.89205 9 P 0 8 0;2=26,4=1
P 6.56038996 0.85205 9 P 0 8 0;2=26,4=1
P 6.56038996 0.81205 9 P 0 8 0;2=26,4=1
P 6.56038996 0.77205 9 P 0 8 0;2=26,4=1
P 6.56038996 0.73205 9 P 0 8 0;2=26,4=1
P 6.56038996 0.69205 9 P 0 8 0;2=26,4=1
P 6.56038996 0.65205 9 P 0 8 0;2=26,4=1
P 6.56038996 0.61205 9 P 0 8 0;2=26,4=1
P 6.56038996 0.57205 9 P 0 8 0;2=26,4=1
P 6.53401998 0.54196998 9 P 0 8 0;2=26,4=1
P 6.49401998 0.54196998 9 P 0 8 0;2=26,4=1
P 6.29401998 0.54196998 9 P 0 8 0;2=26,4=1
P 6.25401998 0.54196998 9 P 0 8 0;2=26,4=1
P 6.21401998 0.54196998 9 P 0 8 0;2=26,4=1
P 6.17401998 0.54196998 9 P 0 8 0;2=26,4=1
P 6.13401998 0.54196998 9 P 0 8 0;2=26,4=1
P 6.09401998 0.54196998 9 P 0 8 0;2=26,4=1
P 6.05401998 0.54196998 9 P 0 8 0;2=26,4=1
P 6.01401998 0.54196998 9 P 0 8 0;2=26,4=1
P 5.97401998 0.54196998 9 P 0 8 0;2=26,4=1
P 5.93401998 0.54196998 9 P 0 8 0;2=26,4=1
P 5.89401998 0.54196998 9 P 0 8 0;2=26,4=1
P 5.85401998 0.54196998 9 P 0 8 0;2=26,4=1
P 5.81401998 0.54196998 9 P 0 8 0;2=26,4=1
P 5.77401998 0.54196998 9 P 0 8 0;2=26,4=1
P 5.73401998 0.54196998 9 P 0 8 0;2=26,4=1
P 5.69401998 0.54196998 9 P 0 8 0;2=26,4=1
P 5.65401998 0.54196998 9 P 0 8 0;2=26,4=1
P 5.61401998 0.54196998 9 P 0 8 0;2=26,4=1
P 5.57401998 0.54196998 9 P 0 8 0;2=26,4=1
P 5.53401998 0.54196998 9 P 0 8 0;2=26,4=1
P 5.49401998 0.54196998 9 P 0 8 0;2=26,4=1
P 5.45401998 0.54196998 9 P 0 8 0;2=26,4=1
P 5.41401998 0.54196998 9 P 0 8 0;2=26,4=1
P 5.37401998 0.54196998 9 P 0 8 0;2=26,4=1
P 5.33401998 0.54196998 9 P 0 8 0;2=26,4=1
P 5.29401998 0.54196998 9 P 0 8 0;2=26,4=1
P 5.25401998 0.54196998 9 P 0 8 0;2=26,4=1
P 5.21401998 0.54196998 9 P 0 8 0;2=26,4=1
P 5.17401998 0.54196998 9 P 0 8 0;2=26,4=1
P 5.13401998 0.54196998 9 P 0 8 0;2=26,4=1
P 5.09401998 0.54196998 9 P 0 8 0;2=26,4=1
P 5.05401998 0.54196998 9 P 0 8 0;2=26,4=1
P 5.01401998 0.54196998 9 P 0 8 0;2=26,4=1
P 4.97401998 0.54196998 9 P 0 8 0;2=26,4=1
P 4.93401998 0.54196998 9 P 0 8 0;2=26,4=1
P 4.89401998 0.54196998 9 P 0 8 0;2=26,4=1
P 4.85401998 0.54196998 9 P 0 8 0;2=26,4=1
P 4.81401998 0.54196998 9 P 0 8 0;2=26,4=1
P 4.77401998 0.54196998 9 P 0 8 0;2=26,4=1
P 4.73401998 0.54196998 9 P 0 8 0;2=26,4=1
P 4.69401998 0.54196998 9 P 0 8 0;2=26,4=1
P 4.65401998 0.54196998 9 P 0 8 0;2=26,4=1
P 4.61401998 0.54196998 9 P 0 8 0;2=26,4=1
P 4.57401998 0.54196998 9 P 0 8 0;2=26,4=1
P 4.53401998 0.54196998 9 P 0 8 0;2=26,4=1
P 4.49401998 0.54196998 9 P 0 8 0;2=26,4=1
P 4.45401998 0.54196998 9 P 0 8 0;2=26,4=1
P 4.41401998 0.54196998 9 P 0 8 0;2=26,4=1
P 4.37401998 0.54196998 9 P 0 8 0;2=26,4=1
P 4.33401998 0.54196998 9 P 0 8 0;2=26,4=1
P 4.29401998 0.54196998 9 P 0 8 0;2=26,4=1
P 4.25401998 0.54196998 9 P 0 8 0;2=26,4=1
P 4.21401998 0.54196998 9 P 0 8 0;2=26,4=1
P 4.17401998 0.54196998 9 P 0 8 0;2=26,4=1
P 2.80413002 4.33598002 9 P 0 8 0;2=26,4=1
P 2.84413002 4.33598002 9 P 0 8 0;2=26,4=1
P 2.88413002 4.33598002 9 P 0 8 0;2=26,4=1
P 2.92413002 4.33598002 9 P 0 8 0;2=26,4=1
P 2.96413002 4.33598002 9 P 0 8 0;2=26,4=1
P 3.00413002 4.33598002 9 P 0 8 0;2=26,4=1
P 3.04413002 4.33598002 9 P 0 8 0;2=26,4=1
P 3.08413002 4.33598002 9 P 0 8 0;2=26,4=1
P 3.12413002 4.33598002 9 P 0 8 0;2=26,4=1
P 3.16413002 4.33598002 9 P 0 8 0;2=26,4=1
P 3.20413002 4.33598002 9 P 0 8 0;2=26,4=1
P 3.24413002 4.33598002 9 P 0 8 0;2=26,4=1
P 3.28413002 4.33598002 9 P 0 8 0;2=26,4=1
P 3.32413002 4.33598002 9 P 0 8 0;2=26,4=1
P 3.36413002 4.33598002 9 P 0 8 0;2=26,4=1
P 3.40413002 4.33598002 9 P 0 8 0;2=26,4=1
P 3.44413002 4.33598002 9 P 0 8 0;2=26,4=1
P 3.48413002 4.33598002 9 P 0 8 0;2=26,4=1
P 3.52413002 4.33598002 9 P 0 8 0;2=26,4=1
P 3.56413002 4.33598002 9 P 0 8 0;2=26,4=1
P 3.60413002 4.33598002 9 P 0 8 0;2=26,4=1
P 3.64413002 4.33598002 9 P 0 8 0;2=26,4=1
P 3.68413002 4.33598002 9 P 0 8 0;2=26,4=1
P 3.72413002 4.33598002 9 P 0 8 0;2=26,4=1
P 3.76413002 4.33598002 9 P 0 8 0;2=26,4=1
P 3.80413002 4.33598002 9 P 0 8 0;2=26,4=1
P 3.84413002 4.33598002 9 P 0 8 0;2=26,4=1
P 3.88413002 4.33598002 9 P 0 8 0;2=26,4=1
P 3.92413002 4.33598002 9 P 0 8 0;2=26,4=1
P 3.96413002 4.33598002 9 P 0 8 0;2=26,4=1
P 4.00413002 4.33598002 9 P 0 8 0;2=26,4=1
P 4.04413002 4.33598002 9 P 0 8 0;2=26,4=1
P 4.08413002 4.33598002 9 P 0 8 0;2=26,4=1
P 4.12413002 4.33598002 9 P 0 8 0;2=26,4=1
P 4.16413002 4.33598002 9 P 0 8 0;2=26,4=1
P 4.20413002 4.33598002 9 P 0 8 0;2=26,4=1
P 4.24413002 4.33598002 9 P 0 8 0;2=26,4=1
P 4.28413002 4.33598002 9 P 0 8 0;2=26,4=1
P 4.32413002 4.33598002 9 P 0 8 0;2=26,4=1
P 4.36413002 4.33598002 9 P 0 8 0;2=26,4=1
P 4.40413002 4.33598002 9 P 0 8 0;2=26,4=1
P 4.44413002 4.33598002 9 P 0 8 0;2=26,4=1
P 4.48413002 4.33598002 9 P 0 8 0;2=26,4=1
P 4.52413002 4.33598002 9 P 0 8 0;2=26,4=1
P 4.56413002 4.33598002 9 P 0 8 0;2=26,4=1
P 4.60413002 4.33598002 9 P 0 8 0;2=26,4=1
P 4.64413002 4.33598002 9 P 0 8 0;2=26,4=1
P 4.68413002 4.33598002 9 P 0 8 0;2=26,4=1
P 4.72413002 4.33598002 9 P 0 8 0;2=26,4=1
P 4.76413002 4.33598002 9 P 0 8 0;2=26,4=1
P 4.80413002 4.33598002 9 P 0 8 0;2=26,4=1
P 4.84413002 4.33598002 9 P 0 8 0;2=26,4=1
P 4.88413002 4.33598002 9 P 0 8 0;2=26,4=1
P 4.92413002 4.33598002 9 P 0 8 0;2=26,4=1
P 4.96413002 4.33598002 9 P 0 8 0;2=26,4=1
P 5.00413002 4.33598002 9 P 0 8 0;2=26,4=1
P 5.04413002 4.33598002 9 P 0 8 0;2=26,4=1
P 5.08413002 4.33598002 9 P 0 8 0;2=26,4=1
P 5.12413002 4.33598002 9 P 0 8 0;2=26,4=1
P 5.16413002 4.33598002 9 P 0 8 0;2=26,4=1
P 5.20413002 4.33598002 9 P 0 8 0;2=26,4=1
P 5.24413002 4.33598002 9 P 0 8 0;2=26,4=1
P 5.28413002 4.33598002 9 P 0 8 0;2=26,4=1
P 5.32413002 4.33598002 9 P 0 8 0;2=26,4=1
P 5.36413002 4.33598002 9 P 0 8 0;2=26,4=1
P 5.40413002 4.33598002 9 P 0 8 0;2=26,4=1
P 5.44413002 4.33598002 9 P 0 8 0;2=26,4=1
P 5.48413002 4.33598002 9 P 0 8 0;2=26,4=1
P 5.52413002 4.33598002 9 P 0 8 0;2=26,4=1
P 5.56413002 4.33598002 9 P 0 8 0;2=26,4=1
P 5.60413002 4.33598002 9 P 0 8 0;2=26,4=1
P 5.64413002 4.33598002 9 P 0 8 0;2=26,4=1
P 5.68413002 4.33598002 9 P 0 8 0;2=26,4=1
P 5.72413002 4.33598002 9 P 0 8 0;2=26,4=1
P 5.76413002 4.33598002 9 P 0 8 0;2=26,4=1
P 5.80413002 4.33598002 9 P 0 8 0;2=26,4=1
P 5.84413002 4.33598002 9 P 0 8 0;2=26,4=1
P 5.88413002 4.33598002 9 P 0 8 0;2=26,4=1
P 5.92413002 4.33598002 9 P 0 8 0;2=26,4=1
P 5.96413002 4.33598002 9 P 0 8 0;2=26,4=1
P 6.00413002 4.33598002 9 P 0 8 0;2=26,4=1
P 6.04413002 4.33598002 9 P 0 8 0;2=26,4=1
P 6.08413002 4.33598002 9 P 0 8 0;2=26,4=1
P 6.12413002 4.33598002 9 P 0 8 0;2=26,4=1
P 6.16413002 4.33598002 9 P 0 8 0;2=26,4=1
P 6.20413002 4.33598002 9 P 0 8 0;2=26,4=1
P 6.24413002 4.33598002 9 P 0 8 0;2=26,4=1
P 6.28413002 4.33598002 9 P 0 8 0;2=26,4=1
P 6.32413002 4.33598002 9 P 0 8 0;2=26,4=1
P 6.36413002 4.33598002 9 P 0 8 0;2=26,4=1
P 6.40413002 4.33598002 9 P 0 8 0;2=26,4=1
P 6.44413002 4.33598002 9 P 0 8 0;2=26,4=1
P 6.48413002 4.33598002 9 P 0 8 0;2=26,4=1
P 6.52413002 4.33598002 9 P 0 8 0;2=26,4=1
P 6.56038996 4.31908996 9 P 0 8 0;2=26,4=1
P 6.56038996 4.27908996 9 P 0 8 0;2=26,4=1
P 6.56038996 4.23908996 9 P 0 8 0;2=26,4=1
P 6.56038996 4.19908996 9 P 0 8 0;2=26,4=1
P 6.56038996 4.15908996 9 P 0 8 0;2=26,4=1
P 6.56038996 4.11908996 9 P 0 8 0;2=26,4=1
P 6.56038996 4.07908996 9 P 0 8 0;2=26,4=1
P 6.56038996 4.03908996 9 P 0 8 0;2=26,4=1
P 6.56038996 3.99908996 9 P 0 8 0;2=26,4=1
P 6.56038996 3.95908996 9 P 0 8 0;2=26,4=1
P 6.56038996 3.91908996 9 P 0 8 0;2=26,4=1
P 6.56038996 3.87908996 9 P 0 8 0;2=26,4=1
P 6.56038996 3.83908996 9 P 0 8 0;2=26,4=1
P 6.56038996 3.79908996 9 P 0 8 0;2=26,4=1
P 6.56038996 3.75908996 9 P 0 8 0;2=26,4=1
P 6.56038996 3.71908996 9 P 0 8 0;2=26,4=1
P 6.56038996 3.67908996 9 P 0 8 0;2=26,4=1
P 6.56038996 3.63908996 9 P 0 8 0;2=26,4=1
P 6.56038996 3.59908996 9 P 0 8 0;2=26,4=1
P 6.56038996 3.55908996 9 P 0 8 0;2=26,4=1
P 6.56038996 3.51908996 9 P 0 8 0;2=26,4=1
P 6.56038996 3.47908996 9 P 0 8 0;2=26,4=1
P 6.56038996 3.43908996 9 P 0 8 0;2=26,4=1
P 6.56038996 3.39908996 9 P 0 8 0;2=26,4=1
P 6.56038996 3.35908996 9 P 0 8 0;2=26,4=1
P 6.56038996 3.31908996 9 P 0 8 0;2=26,4=1
P 6.56038996 3.27908996 9 P 0 8 0;2=26,4=1
P 6.56038996 3.23908996 9 P 0 8 0;2=26,4=1
P 6.56038996 3.19908996 9 P 0 8 0;2=26,4=1
P 6.56038996 3.15908996 9 P 0 8 0;2=26,4=1
P 6.56038996 3.11908996 9 P 0 8 0;2=26,4=1
P 6.56038996 2.35585 9 P 0 8 0;2=26,4=1
P 5.119 2.762 11 P 0 8 0;2=7,4=1
P 5.63341004 0.62101998 11 P 0 8 0;2=7,4=1
P 5.59941004 0.6212 11 P 0 8 0;2=7,4=1
P 2.419 2.388 11 P 0 8 0;2=7,4=1
P 2.805 2.243 11 P 0 8 0;2=7,4=1
P 2.7526 2.23 11 P 0 8 0;2=7,4=1
L 4.56091004 1.72531998 4.54123002 1.70563996 8 P 0 
P 4.56091004 1.72531998 10 P 0 8 0;0,2=5,4=0
P 4.278 1.003 11 P 0 8 0;2=7,4=1
P 3.08966998 2.04 11 P 0 8 0;2=7,4=1
P 2.41441004 2.15 11 P 0 8 0;2=7,4=1
P 2.69 2.15 11 P 0 8 0;2=7,4=1
P 5.83 1.92 11 P 0 8 0;2=7,4=1
L 5.89953002 2.28401998 5.88098002 2.28401998 8 P 0 
L 5.88098002 2.28401998 5.865 2.3 8 P 0 
P 5.805 1.945 11 P 0 8 0;2=7,4=1
P 5.089 3.775 63 P 0 8 0;0,2=2,4=0
P 5.045 3.76 11 P 0 8 0;2=7,4=1
P 5.05 3.795 11 P 0 8 0;2=7,4=1
P 5.05 3.837 88 P 0 8 0;0,2=21,4=0
P 4.588 3.927 71 P 0 8 0;0,2=21,4=0
P 4.53 3.891 58 P 0 8 0;0,2=2,4=0
P 4.54 3.97 11 P 0 8 0;2=7,4=1
P 4.54 3.935 11 P 0 8 0;2=7,4=1
P 4.62 2.5 11 P 0 8 0;2=7,4=1
P 3.23743996 2.865 43 P 0 8 0;0,2=37,4=0
L 3.23743996 2.865 3.285 2.865 8 P 0 
L 3.285 2.865 3.305 2.885 8 P 0 
L 3.305 2.885 3.305 2.915 8 P 0 
P 3.305 2.915 11 P 0 8 0;2=7,4=1
P 3.23743996 2.765 43 P 0 8 0;0,2=37,4=0
L 3.23743996 2.765 3.145 2.765 8 P 0 
P 3.145 2.765 11 P 0 8 0;2=7,4=1
P 3.95588002 2.88533002 116 P 0 8 0;0,2=32,4=0
P 6.071 2.225 63 P 0 8 0;0,2=2,4=0
P 6.071 2.27 63 P 0 8 0;0,2=2,4=0
P 6.105 2.27 11 P 0 8 0;2=7,4=1
P 6.141 2.278 58 P 0 8 0;0,2=2,4=0
P 6.141 2.241 11 P 0 8 0;2=7,4=1
P 2.54 2.135 11 P 0 8 0;2=7,4=1
P 2.59 2.23 11 P 0 8 0;2=7,4=1
L 5.50543996 3.021 5.42753002 3.021 8 P 0 
L 5.42753002 3.021 5.41346004 3.03506998 8 P 0 
P 5.859 0.796 11 P 0 8 0;2=7,4=1
L 5.772 0.658 5.805 0.658 7 P 0 
L 5.78043002 0.609 5.80643002 0.609 7 P 0 
P 5.78043002 0.609 33 P 0 8 0;0,2=14,4=0
P 5.80643002 0.609 11 P 0 8 0;2=7,4=1
P 5.772 0.658 58 P 0 8 0;0,2=2,4=0
P 5.805 0.658 11 P 0 8 0;2=7,4=1
P 5.37 0.69 11 P 0 8 0;2=7,4=1
P 5.43956998 0.635 33 P 0 8 0;0,2=14,4=0
L 5.43956998 0.635 5.43956998 0.60543002 6 P 0 
P 5.43956998 0.60543002 11 P 0 8 0;2=7,4=1
P 5.56533002 0.63511998 114 P 0 8 0;0,2=32,4=0
P 5.575 0.932 88 P 0 8 0;0,2=21,4=0
P 6.335 1.96873996 11 P 0 8 0;2=7,4=1
P 5.59 0.888 11 P 0 8 0;2=7,4=1
L 4.933 1.264 4.933 1.215 8 P 0 
P 4.933 1.215 11 P 0 8 0;2=7,4=1
P 4.933 1.264 71 P 0 8 0;0,2=21,4=0
P 4.894 1.263 11 P 0 8 0;2=7,4=1
P 4.79866998 1.38866998 11 P 0 8 0;2=7,4=1
P 5.001 1.43 63 P 0 8 0;0,2=2,4=0
P 5.0395 1.43 11 P 0 8 0;2=7,4=1
P 4.44 2.461 58 P 0 8 0;0,2=2,4=0
P 4.44 2.5 11 P 0 8 0;2=7,4=1
P 4.965 1.925 11 P 0 8 0;2=7,4=1
P 4.96 2.055 11 P 0 8 0;2=7,4=1
P 5.346 1.52 11 P 0 8 0;2=7,4=1
P 5.346 1.483 11 P 0 8 0;2=7,4=1
P 5.2975 1.595 78 P 0 8 0;0,2=57,4=0
P 5.2975 1.47 78 P 0 8 0;0,2=57,4=0
L 4.926 1.675 4.96 1.675 8 P 0 
P 4.96 1.675 11 P 0 8 0;2=7,4=1
L 4.46 0.973 4.46 0.987 8 P 0 
L 4.46 0.987 4.442 1.005 8 P 0 
P 3.99 2.25 11 P 0 8 0;2=7,4=1
P 3.99 2.21406998 11 P 0 8 0;2=7,4=1
P 3.7206 2.13 11 P 0 8 0;2=7,4=1
P 3.6956 2.13 11 P 0 8 0;2=7,4=1
L 3.41953002 2.40503996 3.41953002 2.38 6 P 0 
L 3.41953002 2.38 3.40953002 2.37 6 P 0 
L 3.415 2.335 3.415 2.33383996 6 P 0 
L 3.415 2.33383996 3.425 2.32383996 6 P 0 
L 3.425 2.32383996 3.45151998 2.32383996 6 P 0 
P 4.78 1.98 11 P 0 8 0;2=7,4=1
P 5.64 0.944 58 P 0 8 0;0,2=2,4=0
P 5.625 0.679 92 P 0 8 0;0,2=83,4=0
P 5.6065 0.7045 11 P 0 8 0;2=79,4=1
P 5.602 0.815 11 P 0 8 0;2=7,4=1
P 5.59 0.85 11 P 0 8 0;2=7,4=1
P 5.625 0.746 11 P 0 8 0;2=7,4=1
P 5.632 0.859 71 P 0 8 0;0,2=21,4=0
P 5.649 0.792 63 P 0 8 0;0,2=2,4=0
P 5.55 0.863 71 P 0 8 0;0,2=21,4=0
P 5.569 0.792 63 P 0 8 0;0,2=2,4=0
P 4.22 0.775 11 P 0 8 0;2=7,4=1
P 4.345 0.77 11 P 0 8 0;2=7,4=1
P 4.4843 0.8954 11 P 0 8 0;2=7,4=1
L 4.4843 0.8954 4.4843 0.8012 8 P 0 
L 4.4843 0.8012 4.4631 0.78 8 P 0 
L 4.4631 0.78 4.415 0.78 8 P 0 
L 4.415 0.78 4.414 0.781 8 P 0 
P 4.442 1.005 11 P 0 8 0;2=7,4=1
L 4.322 0.973 4.322 0.992 8 P 0 
L 4.322 0.992 4.335 1.005 8 P 0 
P 4.31 1.165 11 P 0 8 0;2=7,4=1
P 4.414 0.781 11 P 0 8 0;2=1,4=1
L 4.414 0.82366004 4.414 0.781 8 P 0 
P 4.414 0.82366004 59 P 0 8 0;0,2=12,4=0
P 4.46 0.973 63 P 0 8 0;0,2=2,4=0
P 4.335 1.005 11 P 0 8 0;2=7,4=1
P 4.322 0.973 63 P 0 8 0;0,2=2,4=0
P 4.23 1.005 11 P 0 8 0;2=7,4=1
P 3.12 2.955 11 P 0 8 0;2=7,4=1
P 2.995 2.955 11 P 0 8 0;2=7,4=1
P 2.92 2.9472 11 P 0 8 0;2=7,4=1
P 2.88 2.93 11 P 0 8 0;2=7,4=1
P 3.01 3.12 11 P 0 8 0;2=7,4=1
L 3.582 2.761 3.5485 2.761 7 P 0 
P 5.121 2.447 11 P 0 8 0;2=7,4=1
P 5.121 2.407 11 P 0 8 0;2=7,4=1
P 5.298 2.23 11 P 0 8 0;2=7,4=1
P 5.332 2.2 11 P 0 8 0;2=1,4=1
P 5.369 2.015 11 P 0 8 0;2=7,4=1
P 5.435 2.05 11 P 0 8 0;2=7,4=1
P 5.409 2.015 11 P 0 8 0;2=7,4=1
P 5.071 2.407 11 P 0 8 0;2=7,4=1
P 4.71838996 1.64658002 10 P 0 8 0;0,2=5,4=0
P 4.815 1.82016004 11 P 0 8 0;2=7,4=1
P 2.76986004 1.79121004 98 P 0 8 0;0,2=76,4=0
P 2.76986004 1.85026004 98 P 0 8 0;0,2=76,4=0
P 4.44 2.26 11 P 0 8 0;2=7,4=1
P 3.67 2.41243002 11 P 0 8 0;2=7,4=1
P 3.63673002 2.41243002 47 P 0 8 0;0,2=14,4=0
P 3.67 2.32 11 P 0 8 0;2=1,4=1
P 3.63673002 2.32556998 47 P 0 8 0;0,2=14,4=0
P 3.54975 2.479 11 P 0 8 0;2=7,4=1
P 3.605 2.43 11 P 0 8 0;2=7,4=1
P 3.55 2.425 11 P 0 8 0;2=7,4=1
P 3.415 2.335 11 P 0 8 0;2=7,4=1
P 3.45151998 2.32383996 60 P 0 8 0;0,2=49,4=0
P 3.505 2.295 11 P 0 8 0;2=7,4=1
P 3.40953002 2.37 11 P 0 8 0;2=7,4=1
P 3.41953002 2.40503996 30 P 0 8 0;0,2=50,4=0
P 3.116 2.524 11 P 0 8 0;2=7,4=1
P 3.12 2.344 11 P 0 8 0;2=7,4=1
L 3.159 2.344 3.12 2.344 8 P 0 
P 3.159 2.344 63 P 0 8 0;0,2=2,4=0
P 3.12 2.17 11 P 0 8 0;2=1,4=1
P 3.159 2.164 63 P 0 8 0;0,2=2,4=0
P 2.92733996 1.86995 98 P 0 8 0;0,2=76,4=0
P 3.512 1.966 11 P 0 8 0;2=7,4=1
L 3.512 1.966 3.50595 1.95995 5 P 0 
L 3.50595 1.95995 3.50595 1.93911004 5 P 0 
P 3.50595 1.93911004 69 P 0 8 0;0,2=55,4=0
L 4.28531998 2.15838996 4.26563996 2.17806998 8 P 0 
P 4.28531998 2.15838996 10 P 0 8 0;0,2=5,4=0
L 3.38483996 2.553 3.435 2.553 8 P 0 
L 3.159 2.524 3.116 2.524 9 P 0 
L 3.159 2.524 3.159 2.569 9 P 0 
P 5.385 2.057 88 P 0 8 0;0,2=21,4=0
P 5.056 2.474 63 P 0 8 0;0,2=2,4=0
P 4.56091004 1.33161004 10 P 0 8 0;0,2=5,4=0
P 4.67901998 1.37098002 10 P 0 8 0;0,2=5,4=0
L 4.67901998 1.37098002 4.6987 1.3513 8 P 0 
P 4.52153996 1.44973002 10 P 0 8 0;0,2=5,4=0
L 4.52153996 1.44973002 4.54121998 1.43005 8 P 0 
P 4.40343002 1.56783996 10 P 0 8 0;0,2=5,4=0
L 4.40343002 1.56783996 4.42311004 1.54816004 8 P 0 
P 4.40343002 1.41035 10 P 0 8 0;0,2=5,4=0
L 4.40343002 1.41035 4.42311004 1.39066998 8 P 0 
P 4.36406004 1.60721004 10 P 0 8 0;0,2=5,4=0
L 4.36406004 1.60721004 4.38373996 1.58753002 8 P 0 
P 4.36406004 1.52846998 10 P 0 8 0;0,2=5,4=0
L 4.36406004 1.52846998 4.38373996 1.50878996 8 P 0 
P 4.36406004 1.64658002 10 P 0 8 0;0,2=5,4=0
L 4.36406004 1.64658002 4.38373996 1.6269 8 P 0 
P 4.32468996 1.56783996 10 P 0 8 0;0,2=5,4=0
L 4.32468996 1.56783996 4.34436998 1.54816004 8 P 0 
P 4.32468996 1.68595 10 P 0 8 0;0,2=5,4=0
L 4.32468996 1.68595 4.34436998 1.66626998 8 P 0 
P 4.32468996 1.64658002 10 P 0 8 0;0,2=5,4=0
L 4.32468996 1.64658002 4.34436998 1.6269 8 P 0 
P 4.28531998 1.60721004 10 P 0 8 0;0,2=5,4=0
L 4.28531998 1.60721004 4.26563996 1.58753002 8 P 0 
P 4.28531998 1.37098002 10 P 0 8 0;0,2=5,4=0
L 4.28531998 1.37098002 4.26563996 1.3513 8 P 0 
P 4.28531998 1.64658002 10 P 0 8 0;0,2=5,4=0
L 4.28531998 1.64658002 4.26563996 1.6269 8 P 0 
P 4.28531998 1.68595 10 P 0 8 0;0,2=5,4=0
L 4.28531998 1.68595 4.26563996 1.66626998 8 P 0 
P 4.24595 1.56783996 10 P 0 8 0;0,2=5,4=0
L 4.24595 1.56783996 4.22626998 1.54816004 8 P 0 
P 4.24595 1.4891 10 P 0 8 0;0,2=5,4=0
L 4.24595 1.4891 4.22626998 1.46941998 8 P 0 
P 4.24595 1.64658002 10 P 0 8 0;0,2=5,4=0
L 4.24595 1.64658002 4.22626998 1.6269 8 P 0 
P 4.20658002 1.60721004 10 P 0 8 0;0,2=5,4=0
L 4.20658002 1.60721004 4.1869 1.58753002 8 P 0 
P 4.16721004 1.56783996 10 P 0 8 0;0,2=5,4=0
L 4.16721004 1.56783996 4.14753002 1.54816004 8 P 0 
P 4.16721004 1.33161004 10 P 0 8 0;0,2=5,4=0
L 4.16721004 1.33161004 4.14753002 1.31193002 8 P 0 
P 4.12783996 1.56783996 10 P 0 8 0;0,2=5,4=0
L 4.12783996 1.56783996 4.10816004 1.54816004 8 P 0 
P 4.12783996 1.52846998 10 P 0 8 0;0,2=5,4=0
L 4.12783996 1.52846998 4.10816004 1.50878996 8 P 0 
P 4.12783996 1.4891 10 P 0 8 0;0,2=5,4=0
L 4.12783996 1.4891 4.10816004 1.46941998 8 P 0 
P 4.08846998 1.4891 10 P 0 8 0;0,2=5,4=0
L 4.08846998 1.4891 4.06878996 1.46941998 8 P 0 
P 4.0491 1.4891 10 P 0 8 0;0,2=5,4=0
L 4.0491 1.4891 4.02941998 1.46941998 8 P 0 
P 4.0491 1.44973002 10 P 0 8 0;0,2=5,4=0
L 4.0491 1.44973002 4.02941998 1.43005 8 P 0 
P 4.00973002 1.44973002 10 P 0 8 0;0,2=5,4=0
L 4.00973002 1.44973002 3.99005 1.43005 8 P 0 
P 4.00973002 1.41035 10 P 0 8 0;0,2=5,4=0
L 4.00973002 1.41035 3.99005 1.39066998 8 P 0 
P 3.97035 1.41035 10 P 0 8 0;0,2=5,4=0
L 3.97035 1.41035 3.95066998 1.39066998 8 P 0 
P 3.89161004 2.15838996 10 P 0 8 0;0,2=5,4=0
L 3.89161004 2.15838996 3.87193002 2.17806998 8 P 0 
P 3.93098002 2.04028002 10 P 0 8 0;0,2=5,4=0
L 3.93098002 2.04028002 3.9113 2.05996004 8 P 0 
P 3.97035 1.92216998 10 P 0 8 0;0,2=5,4=0
L 3.97035 1.92216998 3.95066998 1.94185 8 P 0 
P 4.12783996 1.84343002 10 P 0 8 0;0,2=5,4=0
L 4.12783996 1.84343002 4.10816004 1.86311004 8 P 0 
P 4.00973002 1.80406004 10 P 0 8 0;0,2=5,4=0
L 4.00973002 1.80406004 3.99005 1.82373996 8 P 0 
P 4.20658002 1.76468996 10 P 0 8 0;0,2=5,4=0
L 4.20658002 1.76468996 4.1869 1.78436998 8 P 0 
P 4.12783996 1.76468996 10 P 0 8 0;0,2=5,4=0
L 4.12783996 1.76468996 4.10816004 1.78436998 8 P 0 
P 4.00973002 1.76468996 10 P 0 8 0;0,2=5,4=0
L 4.00973002 1.76468996 3.99005 1.78436998 8 P 0 
P 3.89161004 1.76468996 10 P 0 8 0;0,2=5,4=0
L 3.89161004 1.76468996 3.87193002 1.78436998 8 P 0 
P 3.97035 1.76468996 10 P 0 8 0;0,2=5,4=0
L 3.97035 1.76468996 3.95066998 1.78436998 8 P 0 
P 3.93098002 1.76468996 10 P 0 8 0;0,2=5,4=0
L 3.93098002 1.76468996 3.9113 1.78436998 8 P 0 
P 4.24595 1.72531998 10 P 0 8 0;0,2=5,4=0
L 4.24595 1.72531998 4.22626998 1.70563996 8 P 0 
P 4.16721004 1.72531998 10 P 0 8 0;0,2=5,4=0
L 4.16721004 1.72531998 4.14753002 1.70563996 8 P 0 
P 4.08846998 1.72531998 10 P 0 8 0;0,2=5,4=0
L 4.08846998 1.72531998 4.06878996 1.70563996 8 P 0 
P 4.0491 1.72531998 10 P 0 8 0;0,2=5,4=0
L 4.0491 1.72531998 4.02941998 1.70563996 8 P 0 
P 3.89161004 1.72531998 10 P 0 8 0;0,2=5,4=0
L 3.89161004 1.72531998 3.87193002 1.70563996 8 P 0 
P 4.20658002 1.68595 10 P 0 8 0;0,2=5,4=0
L 4.20658002 1.68595 4.1869 1.66626998 8 P 0 
P 4.12783996 1.68595 10 P 0 8 0;0,2=5,4=0
L 4.12783996 1.68595 4.10816004 1.66626998 8 P 0 
P 3.97035 1.68595 10 P 0 8 0;0,2=5,4=0
L 3.97035 1.68595 3.95066998 1.66626998 8 P 0 
P 3.89161004 1.64658002 10 P 0 8 0;0,2=5,4=0
L 3.89161004 1.64658002 3.87193002 1.6269 8 P 0 
P 4.16721004 1.64658002 10 P 0 8 0;0,2=5,4=0
L 4.16721004 1.64658002 4.14753002 1.6269 8 P 0 
P 4.12783996 1.64658002 10 P 0 8 0;0,2=5,4=0
L 4.12783996 1.64658002 4.10816004 1.6269 8 P 0 
P 4.0491 1.64658002 10 P 0 8 0;0,2=5,4=0
L 4.0491 1.64658002 4.02941998 1.6269 8 P 0 
P 4.12783996 1.60721004 10 P 0 8 0;0,2=5,4=0
L 4.12783996 1.60721004 4.10816004 1.58753002 8 P 0 
P 4.00973002 1.60721004 10 P 0 8 0;0,2=5,4=0
L 4.00973002 1.60721004 3.99005 1.58753002 8 P 0 
P 3.89161004 1.56783996 10 P 0 8 0;0,2=5,4=0
L 3.89161004 1.56783996 3.87193002 1.54816004 8 P 0 
P 4.0491 1.56783996 10 P 0 8 0;0,2=5,4=0
L 4.0491 1.56783996 4.02941998 1.54816004 8 P 0 
P 3.97035 1.52846998 10 P 0 8 0;0,2=5,4=0
L 3.97035 1.52846998 3.95066998 1.50878996 8 P 0 
P 3.89161004 1.4891 10 P 0 8 0;0,2=5,4=0
L 3.89161004 1.4891 3.87193002 1.46941998 8 P 0 
P 3.89161004 1.41035 10 P 0 8 0;0,2=5,4=0
L 3.89161004 1.41035 3.87193002 1.39066998 8 P 0 
P 3.93098002 1.41035 10 P 0 8 0;0,2=5,4=0
L 3.93098002 1.41035 3.9113 1.39066998 8 P 0 
P 3.89161004 1.37098002 10 P 0 8 0;0,2=5,4=0
L 3.89161004 1.37098002 3.87193002 1.3513 8 P 0 
P 4.67901998 2.15838996 10 P 0 8 0;0,2=5,4=0
L 4.67901998 2.15838996 4.6987 2.17806998 8 P 0 
P 4.56091004 2.11901998 10 P 0 8 0;0,2=5,4=0
L 4.56091004 2.11901998 4.58058996 2.1387 8 P 0 
P 4.48216998 1.96153996 10 P 0 8 0;0,2=5,4=0
L 4.48216998 1.96153996 4.50185 1.98121998 8 P 0 
P 4.4428 2.07965 10 P 0 8 0;0,2=5,4=0
L 4.4428 2.07965 4.46248002 2.09933002 8 P 0 
P 4.36406004 1.92216998 10 P 0 8 0;0,2=5,4=0
L 4.36406004 1.92216998 4.38373996 1.94185 7 P 0 
P 4.32468996 2.04028002 10 P 0 8 0;0,2=5,4=0
L 4.32468996 2.04028002 4.34436998 2.05996004 8 P 0 
P 4.24595 1.8828 10 P 0 8 0;0,2=5,4=0
L 4.24595 1.8828 4.22626998 1.90248002 8 P 0 
P 4.20658002 2.00091004 10 P 0 8 0;0,2=5,4=0
L 4.20658002 2.00091004 4.1869 2.02058996 8 P 0 
P 4.16721004 2.11901998 10 P 0 8 0;0,2=5,4=0
L 4.16721004 2.11901998 4.14753002 2.1387 8 P 0 
P 4.08846998 1.96153996 10 P 0 8 0;0,2=5,4=0
L 4.08846998 1.96153996 4.06878996 1.98121998 8 P 0 
P 4.0491 2.07965 10 P 0 8 0;0,2=5,4=0
L 4.0491 2.07965 4.02941998 2.09933002 8 P 0 
P 4.71838996 2.04028002 10 P 0 8 0;0,2=5,4=0
L 4.71838996 2.04028002 4.73806998 2.05996004 8 P 0 
P 4.60028002 2.00091004 10 P 0 8 0;0,2=5,4=0
L 4.60028002 2.00091004 4.61996004 2.02058996 8 P 0 
P 4.63965 1.8828 10 P 0 8 0;0,2=5,4=0
L 4.63965 1.8828 4.65933002 1.90248002 8 P 0 
P 4.52153996 1.84343002 10 P 0 8 0;0,2=5,4=0
L 4.52153996 1.84343002 4.54121998 1.86311004 8 P 0 
P 4.40343002 1.80406004 10 P 0 8 0;0,2=5,4=0
L 4.40343002 1.80406004 4.42311004 1.82373996 8 P 0 
P 4.67901998 1.76468996 10 P 0 8 0;0,2=5,4=0
L 4.67901998 1.76468996 4.6987 1.78436998 8 P 0 
P 4.4428 1.76468996 10 P 0 8 0;0,2=5,4=0
L 4.4428 1.76468996 4.46248002 1.78436998 8 P 0 
P 4.48216998 1.72531998 10 P 0 8 0;0,2=5,4=0
L 4.48216998 1.72531998 4.50185 1.70563996 8 P 0 
P 4.40343002 1.72531998 10 P 0 8 0;0,2=5,4=0
L 4.40343002 1.72531998 4.42311004 1.70563996 8 P 0 
P 4.32468996 1.72531998 10 P 0 8 0;0,2=5,4=0
L 4.32468996 1.72531998 4.34436998 1.70563996 8 P 0 
P 4.4428 1.68595 10 P 0 8 0;0,2=5,4=0
L 4.4428 1.68595 4.46248002 1.66626998 8 P 0 
P 4.36406004 1.68595 10 P 0 8 0;0,2=5,4=0
L 4.36406004 1.68595 4.38373996 1.66626998 8 P 0 
P 4.48216998 1.64658002 10 P 0 8 0;0,2=5,4=0
L 4.48216998 1.64658002 4.50185 1.6269 8 P 0 
P 4.40343002 1.64658002 10 P 0 8 0;0,2=5,4=0
L 4.40343002 1.64658002 4.42311004 1.6269 8 P 0 
P 4.60028002 1.60721004 10 P 0 8 0;0,2=5,4=0
L 4.60028002 1.60721004 4.61996004 1.58753002 8 P 0 
P 4.4428 1.60721004 10 P 0 8 0;0,2=5,4=0
L 4.4428 1.60721004 4.46248002 1.58753002 8 P 0 
P 4.48216998 1.56783996 10 P 0 8 0;0,2=5,4=0
L 4.48216998 1.56783996 4.50185 1.54816004 8 P 0 
P 4.63965 1.4891 10 P 0 8 0;0,2=5,4=0
L 4.63965 1.4891 4.65933002 1.46941998 8 P 0 
L 4.78656004 3.67205 4.75305 3.67205 8 P 0 
L 4.75305 3.67205 4.714 3.633 8 P 0 
P 4.395 3.37891998 9 P 0 8 0;2=26,4=1
P 4.44 4.165 9 P 0 8 0;2=26,4=1
P 2.86151004 3.295 9 P 0 8 0;2=26,4=1
L 3.435 2.589 3.435 2.553 8 P 0 
L 3.285 2.589 3.285 2.553 8 P 0 
P 4.134 2.936 71 P 0 8 0;0,2=21,4=0
P 4.134 2.855 71 P 0 8 0;0,2=21,4=0
P 4.145 2.792 63 P 0 8 0;0,2=2,4=0
L 3.21898996 3.43 3.24441998 3.40456998 7 P 0 
L 3.24441998 3.40456998 3.2815 3.40456998 7 P 0 
P 3.21898996 3.43 11 P 0 8 0;2=7,4=1
P 3.287 4.137 63 P 0 8 0;0,2=2,4=0
P 3.255 4.202 71 P 0 8 0;0,2=21,4=0
P 3.34118996 4.06613002 37 P 0 8 0;0,2=87,4=0
P 3.31953996 4.06613002 37 P 0 8 0;0,2=87,4=0
P 3.29788002 4.06613002 37 P 0 8 0;0,2=87,4=0
P 3.29788002 3.95786998 37 P 0 8 0;0,2=87,4=0
P 3.31953996 3.95786998 37 P 0 8 0;0,2=87,4=0
P 3.34118996 3.95786998 37 P 0 8 0;0,2=87,4=0
P 3.307 3.887 63 P 0 8 0;0,2=2,4=0
P 3.285 3.827 71 P 0 8 0;0,2=21,4=0
P 3.662 2.976 58 P 0 8 0;0,2=2,4=0
P 3.797 2.969 58 P 0 8 0;0,2=2,4=0
P 3.797 2.891 58 P 0 8 0;0,2=2,4=0
P 3.732 2.952 88 P 0 8 0;0,2=21,4=0
P 3.729 2.87 88 P 0 8 0;0,2=21,4=0
P 3.594 4.197 63 P 0 8 0;0,2=2,4=0
P 3.548 2.898 9 P 0 8 0;2=26,4=1
L 3.582 2.898 3.548 2.898 7 P 0 
P 3.582 2.898 58 P 0 8 0;0,2=2,4=0
P 3.621 2.91 11 P 0 8 0;2=7,4=1
P 3.658 2.861 11 P 0 8 0;2=7,4=1
P 3.658 2.911 11 P 0 8 0;2=7,4=1
P 3.623 2.861 11 P 0 8 0;2=7,4=1
P 3.615 2.961 11 P 0 8 0;2=7,4=1
P 3.253 3.917 11 P 0 8 0;2=7,4=1
P 3.253 3.962 11 P 0 8 0;2=7,4=1
P 3.248 4.107 11 P 0 8 0;2=7,4=1
P 3.213 4.167 11 P 0 8 0;2=7,4=1
P 3.248 4.152 11 P 0 8 0;2=7,4=1
P 3.213 4.236 11 P 0 8 0;2=1,4=1
P 3.253 3.872 11 P 0 8 0;2=7,4=1
P 4.465 2.895 9 P 0 8 0;2=26,4=1
P 4.093 2.863 11 P 0 8 0;2=7,4=1
P 4.091 2.813 11 P 0 8 0;2=7,4=1
P 4.092 2.917 11 P 0 8 0;2=7,4=1
P 3.78 2.735 11 P 0 8 0;2=7,4=1
L 3.816 2.68 3.816 2.725 8 P 0 
L 3.78 2.735 3.79 2.725 7 P 0 
L 3.79 2.725 3.816 2.725 7 P 0 
P 3.816 2.725 63 P 0 8 0;0,2=2,4=0
P 3.435 2.589 11 P 0 8 0;2=7,4=1
P 3.5485 2.761 9 P 0 8 0;2=26,4=1
P 3.582 2.761 58 P 0 8 0;0,2=2,4=0
P 3.285 2.589 11 P 0 8 0;2=1,4=1
P 4.775 2.59 11 P 0 8 0;2=7,4=1
P 4.71 2.592 11 P 0 8 0;2=1,4=1
P 4.918 2.777 11 P 0 8 0;2=7,4=1
L 4.95256998 2.777 4.918 2.777 7 P 0 
P 4.95256998 2.777 33 P 0 8 0;0,2=14,4=0
P 4.925 2.722 11 P 0 8 0;2=7,4=1
L 4.961 2.728 4.931 2.728 7 P 0 
L 4.931 2.728 4.925 2.722 7 P 0 
P 4.961 2.728 58 P 0 8 0;0,2=2,4=0
P 3.106 3.305 9 P 0 8 0;2=26,4=1
P 3.222 3.25 9 P 0 8 0;2=26,4=1
P 3.975 3.129 11 P 0 8 0;2=7,4=1
L 3.975 3.129 3.982 3.122 7 P 0 
L 3.982 3.122 3.982 3.10043002 7 P 0 
P 3.982 3.10043002 47 P 0 8 0;0,2=14,4=0
P 3.998 2.784 11 P 0 8 0;2=7,4=1
P 3.96243002 2.774 33 P 0 8 0;0,2=14,4=0
P 3.83 2.932 11 P 0 8 0;2=7,4=1
P 3.78 2.932 11 P 0 8 0;2=7,4=1
P 3.703 2.911 11 P 0 8 0;2=7,4=1
P 3.748 2.911 11 P 0 8 0;2=7,4=1
P 3.933 3.125 11 P 0 8 0;2=7,4=1
L 3.933 3.092 3.933 3.125 7 P 0 
P 3.933 3.092 63 P 0 8 0;0,2=2,4=0
L 3.6 4.024 3.592 4.032 7 P 0 
L 3.592 4.032 3.564 4.032 7 P 0 
P 3.564 4.032 63 P 0 8 0;0,2=2,4=0
P 3.6 4.024 11 P 0 8 0;2=7,4=1
P 3.631 4.228 11 P 0 8 0;2=7,4=1
P 3.60311004 4.0988 11 P 0 8 0;2=7,4=1
L 3.54743002 4.121 3.588 4.121 7 P 0 
L 3.588 4.121 3.6 4.109 7 P 0 
L 3.6 4.109 3.6 4.10191004 7 P 0 
L 3.6 4.10191004 3.60311004 4.0988 7 P 0 
P 3.54743002 4.121 33 P 0 8 0;0,2=14,4=0
P 3.564 4.077 63 P 0 8 0;0,2=2,4=0
P 3.631 4.183 11 P 0 8 0;2=7,4=1
P 3.38 3.15 11 P 0 8 0;2=7,4=1
P 4.43 3.965 9 P 0 8 0;2=26,4=1
P 4.43 4.015 9 P 0 8 0;2=26,4=1
L 4.396 4.015 4.43 4.015 8 P 0 
P 4.396 3.915 63 P 0 8 0;0,2=2,4=0
L 4.396 3.915 4.396 3.965 8 P 0 
P 4.396 3.965 63 P 0 8 0;0,2=2,4=0
L 4.396 3.965 4.396 4.015 8 P 0 
P 4.396 4.015 63 P 0 8 0;0,2=2,4=0
P 4.714 3.633 11 P 0 8 0;2=7,4=1
P 4.78656004 3.67205 106 P 0 8 0;0,2=20,4=0
P 4.71 3.47 11 P 0 8 0;2=7,4=1
P 3.159 2.569 63 P 0 8 0;0,2=2,4=0
P 4.94093996 4.12008002 21 P 0 8 0;2=89,4=0
P 4.94093996 3.09646004 21 P 0 8 0;2=89,4=0
P 3.8865 2.9265 11 P 0 8 0;2=79,4=1
P 3.912 2.945 100 P 0 8 0;0,2=83,4=0
L 5.517 2.563 5.50543996 2.57456004 8 P 0 
L 5.50543996 2.57456004 5.50543996 2.621 8 P 0 
P 2.55906004 4.12008002 21 P 0 8 0;2=89,4=0
P 2.55906004 3.09646004 21 P 0 8 0;2=89,4=0
P 5.815 2.67 11 P 0 8 0;2=7,4=1
P 5.517 2.563 11 P 0 8 0;2=7,4=1
P 5.50543996 2.621 43 P 0 8 0;0,2=37,4=0
P 5.49 2.675 11 P 0 8 0;2=7,4=1
P 5.328 2.611 58 P 0 8 0;0,2=2,4=0
P 5.3035 2.5748 11 P 0 8 0;2=7,4=1
P 5.122 2.587 11 P 0 8 0;2=7,4=1
P 5.123 2.544 11 P 0 8 0;2=7,4=1
P 5.121 2.495 11 P 0 8 0;2=7,4=1
P 5.121 2.625 11 P 0 8 0;2=7,4=1
P 5.41346004 3.03506998 11 P 0 8 0;2=7,4=1
P 5.50543996 3.021 43 P 0 8 0;0,2=37,4=0
P 5.814 2.9225 11 P 0 8 0;2=7,4=1
P 5.25176004 4.11925 11 P 0 8 0;2=7,4=1
L 5.283 4.15048996 5.25176004 4.11925 8 P 0 
P 5.283 4.15048996 24 P 0 8 0;0,2=36,4=0
P 5.88778996 3.34448996 18 P 0 8 0;2=72,4=0
P 5.88778996 3.50983996 18 P 0 8 0;2=72,4=0
P 5.88778996 3.67518996 18 P 0 8 0;2=72,4=0
P 5.162 2.592 63 P 0 8 0;0,2=2,4=0
P 5.084 2.597 63 P 0 8 0;0,2=2,4=0
P 5.08 2.534 71 P 0 8 0;0,2=21,4=0
S P 0
OB 0.413280019685 0.36811003937 I
OC 0.413280019685 0.36811003937 0.295280019685 0.36811003937 Y
OE
OB 0.370280019685 0.36811003937 H
OC 0.370280019685 0.36811003937 0.295280019685 0.36811003937 N
OE
SE
P 5.331 2.238 58 P 0 8 0;0,2=2,4=0
P 5.52086998 2.14318996 79 P 0 8 0;0,2=87,4=0
P 5.52086998 2.12153996 79 P 0 8 0;0,2=87,4=0
P 5.52086998 2.09988002 79 P 0 8 0;0,2=87,4=0
P 5.45 2.089 58 P 0 8 0;0,2=2,4=0
P 5.7 2.109 58 P 0 8 0;0,2=2,4=0
P 5.62913002 2.09988002 79 P 0 8 0;0,2=87,4=0
P 5.62913002 2.12153996 79 P 0 8 0;0,2=87,4=0
P 5.62913002 2.14318996 79 P 0 8 0;0,2=87,4=0
P 6.51581998 2.07086998 105 P 0 8 0;0,2=90,4=0
P 6.51581998 2.14961004 105 P 0 8 0;0,2=90,4=0
P 6.289 1.97073996 58 P 0 8 0;0,2=2,4=0
P 6.225 1.97073996 88 P 0 8 0;0,2=21,4=0
L 5.538 2.402 5.555 2.385 6 P 0 
L 5.555 2.385 5.555 2.366 6 P 0 
P 5.51 2.35043002 47 P 0 8 0;0,2=14,4=0
P 5.555 2.366 58 P 0 8 0;0,2=2,4=0
P 5.538 2.402 11 P 0 8 0;2=7,4=1
P 5.666 2.129 9 P 0 8 0;2=26,4=1
P 5.647 2.044 11 P 0 8 0;2=7,4=1
P 5.687 2.043 11 P 0 8 0;2=7,4=1
P 5.732 2.043 11 P 0 8 0;2=7,4=1
P 5.865 2.3 11 P 0 8 0;2=7,4=1
P 5.89953002 2.28401998 63 P 0 8 0;0,2=2,4=0
P 6.36 2.16141998 11 P 0 8 0;2=7,4=1
P 5.162 2.521 71 P 0 8 0;0,2=21,4=0
S P 0
OB 6.51838996063 4.17835 I
OC 6.51838996063 4.17835 6.40038996063 4.17835 Y
OE
OB 6.47538996063 4.17835 H
OC 6.47538996063 4.17835 6.40038996063 4.17835 N
OE
SE
P 6.51581998 2.23623002 103 P 0 8 0;2=91,4=0
P 6.51581998 1.98425 104 P 0 8 0;2=92,4=0
P 6.40951998 2.20866998 14 P 0 8 0;2=93,4=0
P 6.40951998 2.01181004 14 P 0 8 0;2=93,4=0
P 3.546 2.513 58 P 0 8 0;0,2=2,4=0
P 4.74 2.5415 28 P 0 8 0;0,2=57,4=0
P 3.285 2.553 58 P 0 8 0;0,2=2,4=0
P 3.38483996 2.553 58 P 0 8 0;0,2=2,4=0
P 3.435 2.553 58 P 0 8 0;0,2=2,4=0
P 0.06038996 1.38346004 16 P 0 8 0;2=94,4=0
P 0.26038996 1.38346004 16 P 0 8 0;2=94,4=0
P 0.06038996 1.18346004 16 P 0 8 0;2=94,4=0
P 0.26038996 1.18346004 16 P 0 8 0;2=94,4=0
P 0.06038996 0.8126 16 P 0 8 0;2=94,4=0
P 0.26038996 0.8126 16 P 0 8 0;2=94,4=0
P 0.06038996 0.6126 16 P 0 8 0;2=94,4=0
P 0.26038996 0.6126 16 P 0 8 0;2=94,4=0
P 0.06038996 2.5252 16 P 0 8 0;2=94,4=0
P 0.26038996 2.5252 16 P 0 8 0;2=94,4=0
P 0.06038996 2.3252 16 P 0 8 0;2=94,4=0
P 0.26038996 2.3252 16 P 0 8 0;2=94,4=0
P 0.06038996 1.95433002 16 P 0 8 0;2=94,4=0
P 0.26038996 1.95433002 16 P 0 8 0;2=94,4=0
P 0.06038996 1.75433002 16 P 0 8 0;2=94,4=0
P 0.26038996 1.75433002 16 P 0 8 0;2=94,4=0
P 1.26066998 1.84043002 17 P 0 8 0;2=75,4=0
P 3.2815 3.40456998 94 P 0 8 0;0,2=10,4=0
P 3.159 2.524 63 P 0 8 0;0,2=2,4=0
L 3.159 2.524 3.159 2.479 9 P 0 
P 3.159 2.479 63 P 0 8 0;0,2=2,4=0
P 4.926 1.72 63 P 0 8 0;0,2=2,4=0
L 4.926 1.72 4.926 1.675 8 P 0 
P 4.926 1.675 63 P 0 8 0;0,2=2,4=0
P 4.566 2.895 63 P 0 8 0;0,2=2,4=0
L 4.566 2.945 4.566 2.895 8 P 0 
P 4.566 2.945 63 P 0 8 0;0,2=2,4=0
P 0.50356998 1 33 P 0 8 0;0,2=14,4=0
P 1.03441998 3.578 40 P 0 8 0;0,2=18,4=0
P 5.46443002 3.967 63 P 0 8 0;0,2=2,4=0
L 5.46443002 3.967 5.43 3.967 8 P 0 
P 5.762 3.517 63 P 0 8 0;0,2=2,4=0
L 5.762 3.517 5.762 3.567 8 P 0 
P 5.762 3.567 63 P 0 8 0;0,2=2,4=0
P 4.2391 3.992 85 P 0 8 0;0,2=0,4=0
P 5.96046998 2.04418002 36 P 0 8 0;0,2=22,4=0
L 5.96046998 2.04418002 5.96046998 2.02946998 1 P 0 
L 5.96046998 2.02946998 5.934 2.003 1 P 0 
L 5.934 2.003 5.91901998 2.003 1 P 0 
L 5.91901998 2.003 5.91901998 1.95065 1 P 0 
P 5.91901998 2.003 9 P 0 8 0;2=24,4=1
P 5.91901998 1.95065 58 P 0 8 0;0,2=2,4=0
P 6.01953002 2.04418002 36 P 0 8 0;0,2=22,4=0
L 6.01953002 2.04418002 6.04481998 2.04418002 1 P 0 
L 6.04481998 2.04418002 6.06901998 2.01998002 1 P 0 
L 6.06901998 2.01998002 6.06901998 2.004 1 P 0 
L 6.06901998 1.95065 6.06901998 2.004 1 P 0 
P 6.06901998 2.004 9 P 0 8 0;2=24,4=1
P 6.06901998 1.95065 58 P 0 8 0;0,2=2,4=0
L 3.119 1.895 3.106 1.882 3 P 0 
A 3.106 1.882 3.0793 1.882 3.09265 1.89535 3 P 0 Y
L 3.0793 1.882 3.04543996 1.91586004 3 P 0 
A 3.04543996 1.91586004 3.01758002 1.9274 3.0175751 1.88798839 3 P 0 N
L 3.01758002 1.9274 2.97258996 1.9274 3 P 0 
L 2.97258996 1.9274 2.97098996 1.929 3 P 0 
L 2.97098996 1.929 2.92733996 1.929 3 P 0 
P 3.119 1.895 63 P 0 8 0;0,2=2,4=0
P 2.92733996 1.929 98 P 0 8 0;0,2=76,4=0
L 3.119 1.85 3.11048002 1.85851998 3 P 0 
A 3.11048002 1.85851998 3.10381998 1.86336004 3.09182776 1.8398563 3 P 0 N
A 3.10381998 1.86336004 3.06868996 1.87138996 3.09264941 1.8953502 3 P 0 Y
L 3.06868996 1.87138996 3.03483002 1.90525 3 P 0 
A 3.03483002 1.90525 3.01756998 1.9124 3.017569 1.88798996 3 P 0 N
L 3.01756998 1.9124 2.97475 1.9124 3 P 0 
A 2.97475 1.9124 2.97123002 1.91118996 2.97474213 1.90669803 3 P 0 N
A 2.97123002 1.91118996 2.96583996 1.90931998 2.96583494 1.9180375 3 P 0 Y
L 2.96583996 1.90931998 2.92733996 1.90931998 3 P 0 
P 3.119 1.85 63 P 0 8 0;0,2=2,4=0
P 2.92733996 1.90931998 98 P 0 8 0;0,2=76,4=0
P 3.49 0.825 9 P 0 8 0;2=24,4=1
P 2.65966998 0.93443002 17 P 0 8 0;2=75,4=0
L 5.07 1.885 5.138 1.885 1 P 0 
L 5.138 1.885 5.2174 1.9644 1 P 0 
L 5.2174 1.9644 5.2174 2.3274 1 P 0 
L 5.2174 2.3274 5.39 2.5 1 P 0 
L 5.39 2.5 6.05 2.5 1 P 0 
L 6.05 2.5 6.095 2.545 1 P 0 
L 5.07 1.885 5.04 1.915 1 P 0 
L 5.04 1.915 5.04 1.935 1 P 0 
L 5.04 1.935 4.97533002 1.99966998 1 P 0 
L 4.97533002 1.99966998 4.95066998 1.99966998 1 P 0 
L 4.95066998 1.99966998 4.926 1.975 1 P 0 
P 6.095 2.545 11 P 0 8 0;2=1,4=1
P 4.926 1.975 63 P 0 8 0;0,2=2,4=0
P 5.07 1.885 11 P 0 8 0;2=7,4=1
P 5.33 0.995 9 P 0 8 0;2=26,4=1
P 3.54 0.825 11 P 0 8 0;2=7,4=1
L 5.07 1.925 5.1383 1.925 1 P 0 
L 5.1383 1.925 5.1989 1.9856 1 P 0 
L 5.1989 1.9856 5.1989 2.18091998 1 P 0 
L 5.1989 2.18091998 5.1942 2.18561998 1 P 0 
L 5.1942 2.18561998 5.154 2.18561998 1 P 0 
L 5.154 2.18561998 5.1493 2.19031998 1 P 0 
L 5.1493 2.19031998 5.1493 2.20561998 1 P 0 
L 5.1493 2.20561998 5.154 2.21031998 1 P 0 
L 5.154 2.21031998 5.1942 2.21031998 1 P 0 
L 5.1942 2.21031998 5.1989 2.21501998 1 P 0 
L 5.1989 2.21501998 5.1989 2.23031998 1 P 0 
L 5.1989 2.23031998 5.1942 2.23501998 1 P 0 
L 5.1942 2.23501998 5.154 2.23501998 1 P 0 
L 5.154 2.23501998 5.1493 2.23971998 1 P 0 
L 5.1493 2.23971998 5.1493 2.25501998 1 P 0 
L 5.1493 2.25501998 5.154 2.25971998 1 P 0 
L 5.154 2.25971998 5.1942 2.25971998 1 P 0 
L 5.1942 2.25971998 5.1989 2.26441998 1 P 0 
L 5.1989 2.26441998 5.1989 2.27971998 1 P 0 
L 5.1989 2.27971998 5.1942 2.28441998 1 P 0 
L 5.1942 2.28441998 5.154 2.28441998 1 P 0 
L 5.154 2.28441998 5.1493 2.28911998 1 P 0 
L 5.1493 2.28911998 5.1493 2.30441998 1 P 0 
L 5.1493 2.30441998 5.154 2.30911998 1 P 0 
L 5.154 2.30911998 5.1942 2.30911998 1 P 0 
L 5.1942 2.30911998 5.1989 2.31381998 1 P 0 
L 5.1989 2.31381998 5.1989 2.33388996 1 P 0 
L 5.1989 2.33388996 5.38268002 2.51766998 1 P 0 
L 5.38268002 2.51766998 6.01266998 2.51766998 1 P 0 
L 6.01266998 2.51766998 6.04 2.545 1 P 0 
L 4.926 2.025 4.985 2.025 1 P 0 
L 4.985 2.025 5.06 1.95 1 P 0 
L 5.06 1.95 5.06 1.935 1 P 0 
L 5.06 1.935 5.07 1.925 1 P 0 
P 6.04 2.545 11 P 0 8 0;2=1,4=1
P 4.926 2.025 63 P 0 8 0;0,2=2,4=0
P 5.07 1.925 11 P 0 8 0;2=7,4=1
P 5.33 0.95 9 P 0 8 0;2=26,4=1
P 2.53966998 0.93443002 17 P 0 8 0;2=75,4=0
P 3.123 1.8 63 P 0 8 0;0,2=2,4=0
L 3.123 1.8 3.10971998 1.78671998 0 P 0 
A 3.10971998 1.78671998 3.09591998 1.781 3.09591998 1.80050689 0 P 0 Y
L 3.09591998 1.781 3.07711004 1.781 0 P 0 
A 3.07711004 1.781 3.06331004 1.77528996 3.07710197 1.76148848 0 P 0 N
L 3.06331004 1.77528996 3.01023002 1.72221004 0 P 0 
A 3.01023002 1.72221004 3.00491998 1.72 3.00491191 1.72750354 0 P 0 Y
L 3.00491998 1.72 2.8871 1.72 0 P 0 
A 2.8871 1.72 2.88178996 1.72221004 2.88710797 1.72750354 0 P 0 Y
L 2.88178996 1.72221004 2.84203002 1.76196998 0 P 0 
A 2.84203002 1.76196998 2.82823002 1.76768002 2.82823799 1.7481685 0 P 0 N
L 2.82823002 1.76768002 2.82353996 1.76768002 0 P 0 
A 2.82353996 1.76768002 2.81956004 1.76933002 2.82353996 1.77330512 0 P 0 Y
L 2.81956004 1.76933002 2.81901998 1.76986998 0 P 0 
A 2.81901998 1.76986998 2.81503996 1.77151998 2.81503996 1.76589488 0 P 0 N
L 2.81503996 1.77151998 2.76986004 1.77151998 0 P 0 
P 2.76986004 1.77151998 98 P 0 8 0;0,2=76,4=0
P 3.123 1.75 63 P 0 8 0;0,2=2,4=0
L 3.123 1.75 3.10971998 1.76328002 0 P 0 
A 3.10971998 1.76328002 3.09591998 1.769 3.09591998 1.74949311 0 P 0 N
L 3.09591998 1.769 3.07711004 1.769 0 P 0 
A 3.07711004 1.769 3.0718 1.7668 3.07710994 1.76149183 0 P 0 N
L 3.0718 1.7668 3.01871998 1.71371998 0 P 0 
A 3.01871998 1.71371998 3.00491998 1.708 3.00491998 1.72750689 0 P 0 Y
L 3.00491998 1.708 2.8871 1.708 0 P 0 
A 2.8871 1.708 2.8733 1.71371998 2.8870999 1.72750689 0 P 0 Y
L 2.8733 1.71371998 2.83353996 1.75348002 0 P 0 
A 2.83353996 1.75348002 2.82823002 1.75568002 2.82822992 1.74817175 0 P 0 N
L 2.82823002 1.75568002 2.82353996 1.75568002 0 P 0 
A 2.82353996 1.75568002 2.81956004 1.75403002 2.82353996 1.75005492 0 P 0 N
L 2.81956004 1.75403002 2.81901998 1.75348996 0 P 0 
A 2.81901998 1.75348996 2.81503996 1.75183996 2.81503986 1.75746516 0 P 0 Y
L 2.81503996 1.75183996 2.76986004 1.75183996 0 P 0 
P 2.76986004 1.75183996 98 P 0 8 0;0,2=76,4=0
A 2.802 1.987 2.811 2.00873002 2.78026988 2.00872874 0 P 0 N
L 2.811 2.00873002 2.811 2.03333002 0 P 0 
A 2.811 2.03333002 2.81851004 2.05148996 2.83666191 2.03335039 0 P 0 Y
L 2.81851004 2.05148996 2.83401004 2.06698002 0 P 0 
A 2.83401004 2.06698002 2.89198996 2.091 2.89199921 2.00899094 0 P 0 Y
L 2.89198996 2.091 3.14188996 2.091 0 P 0 
A 3.14188996 2.091 3.15403002 2.09603002 3.14188996 2.10816506 0 P 0 N
L 3.15403002 2.09603002 3.168 2.11 0 P 0 
L 2.802 1.987 2.80876004 1.98025 0 P 0 
A 2.80876004 1.98025 2.813 1.97 2.79850719 1.97000689 0 P 0 Y
L 2.813 1.97 2.81301004 1.96061004 0 P 0 
A 2.81301004 1.96061004 2.81646998 1.95073002 2.8289125 1.96063317 0 P 0 N
L 2.81646998 1.95073002 2.82033002 1.94588996 0 P 0 
A 2.82033002 1.94588996 2.824 1.938 2.81422589 1.93825207 0 P 0 Y
L 2.824 1.938 2.824 1.93098002 0 P 0 
A 2.824 1.93098002 2.81818002 1.92516004 2.81818002 1.93098002 0 P 0 Y
L 2.81818002 1.92516004 2.81518002 1.92516004 0 P 0 
A 2.81518002 1.92516004 2.8112 1.92681004 2.81517992 1.93078514 0 P 0 Y
L 2.8112 1.92681004 2.81066004 1.92735 0 P 0 
A 2.81066004 1.92735 2.80668002 1.929 2.80668002 1.9233749 0 P 0 N
L 2.80668002 1.929 2.76986004 1.929 0 P 0 
P 2.802 1.987 9 P 0 8 0;2=26,4=1
P 3.168 2.11 63 P 0 8 0;0,2=2,4=0
P 2.76986004 1.929 98 P 0 8 0;0,2=76,4=0
L 2.834 1.987 2.83148996 1.98951998 0 P 0 
A 2.83148996 1.98951998 2.823 2.01 2.85196654 2.01000827 0 P 0 Y
L 2.823 2.01 2.823 2.03333996 0 P 0 
A 2.823 2.03333996 2.827 2.043 2.83665965 2.03334193 0 P 0 Y
L 2.827 2.043 2.8425 2.05848996 0 P 0 
A 2.8425 2.05848996 2.892 2.079 2.89200778 2.00899321 0 P 0 Y
L 2.892 2.079 3.14188002 2.079 0 P 0 
A 3.14188002 2.079 3.15403996 2.07396004 3.14187992 2.06181083 0 P 0 Y
L 3.15403996 2.07396004 3.168 2.06 0 P 0 
L 2.834 1.987 2.83066004 1.98365 0 P 0 
A 2.83066004 1.98365 2.825 1.97001004 2.84430699 1.96999272 0 P 0 N
L 2.825 1.97001004 2.82501004 1.96063002 0 P 0 
A 2.82501004 1.96063002 2.82586004 1.95821004 2.82891083 1.96064085 0 P 0 N
L 2.82586004 1.95821004 2.82905 1.95421998 0 P 0 
A 2.82905 1.95421998 2.83601004 1.938 2.81422785 1.9382564 0 P 0 Y
L 2.83601004 1.938 2.836 1.938 0 P 0 
L 2.836 1.938 2.836 1.93098002 0 P 0 
A 2.836 1.93098002 2.81818002 1.91316004 2.81818002 1.93098002 0 P 0 Y
L 2.81818002 1.91316004 2.8135 1.91316004 0 P 0 
A 2.8135 1.91316004 2.80951998 1.91151004 2.8135 1.90753484 0 P 0 N
L 2.80951998 1.91151004 2.80898002 1.91096998 0 P 0 
A 2.80898002 1.91096998 2.805 1.90931998 2.805 1.91494508 0 P 0 Y
L 2.805 1.90931998 2.76986004 1.90931998 0 P 0 
P 2.834 1.987 9 P 0 8 0;2=26,4=1
P 3.168 2.06 63 P 0 8 0;0,2=2,4=0
P 2.76986004 1.90931998 98 P 0 8 0;0,2=76,4=0
P 2.845 1.875 9 P 0 8 0;2=26,4=1
L 2.845 1.875 2.83571998 1.86571998 0 P 0 
A 2.83571998 1.86571998 2.83198002 1.86441998 2.8325122 1.8689186 0 P 0 Y
L 2.83198002 1.86441998 2.83196998 1.86441998 0 P 0 
L 2.83196998 1.86441998 2.83196004 1.86441004 0 P 0 
L 2.83196004 1.86441004 2.83196004 1.86438002 0 P 0 
A 2.83196004 1.86438002 2.82888002 1.86713002 2.83262057 1.86821969 0 P 0 Y
A 2.82888002 1.86713002 2.8219 1.87908996 2.80265591 1.85984193 0 P 0 N
L 2.8219 1.87908996 2.82088996 1.8801 0 P 0 
A 2.82088996 1.8801 2.80718996 1.88578996 2.80714675 1.86634793 0 P 0 N
A 2.80718996 1.88578996 2.8032 1.88743996 2.80718996 1.89143927 0 P 0 Y
L 2.8032 1.88743996 2.80266004 1.88798002 0 P 0 
A 2.80266004 1.88798002 2.79868002 1.88963002 2.79868002 1.88400492 0 P 0 N
L 2.79868002 1.88963002 2.76986004 1.88963002 0 P 0 
L 3.168 2.015 3.15403002 2.00103002 0 P 0 
A 3.15403002 2.00103002 3.14188996 1.996 3.14188996 2.01316506 0 P 0 Y
L 3.14188996 1.996 2.92315 1.996 0 P 0 
A 2.92315 1.996 2.899 1.986 2.92314114 1.96186014 0 P 0 N
L 2.899 1.986 2.88053996 1.96753996 0 P 0 
A 2.88053996 1.96753996 2.867 1.93483002 2.91326102 1.93483799 0 P 0 N
L 2.867 1.93483002 2.867 1.8696 0 P 0 
A 2.867 1.8696 2.8624 1.865 2.8624 1.8696 0 P 0 Y
L 2.8624 1.865 2.8569 1.865 0 P 0 
A 2.8569 1.865 2.85366004 1.86633996 2.8568999 1.86958701 0 P 0 Y
L 2.85366004 1.86633996 2.845 1.875 0 P 0 
P 2.76986004 1.88963002 98 P 0 8 0;0,2=76,4=0
P 3.168 2.015 63 P 0 8 0;0,2=2,4=0
P 2.845 1.843 9 P 0 8 0;2=26,4=1
L 2.845 1.843 2.8402 1.8478 0 P 0 
A 2.8402 1.8478 2.8307 1.85243002 2.82873553 1.83633819 0 P 0 N
A 2.8307 1.85243002 2.81731998 1.86388002 2.83261949 1.86821575 0 P 0 Y
A 2.81731998 1.86388002 2.81341004 1.8706 2.80265236 1.85984321 0 P 0 N
L 2.81341004 1.8706 2.8124 1.87161004 0 P 0 
A 2.8124 1.87161004 2.80713002 1.87378996 2.80713829 1.8663501 0 P 0 N
L 2.80713002 1.87378996 2.80585 1.87378996 0 P 0 
A 2.80585 1.87378996 2.80298002 1.8726 2.8058499 1.86973415 0 P 0 N
L 2.80298002 1.8726 2.80198996 1.87161004 0 P 0 
A 2.80198996 1.87161004 2.798 1.86995 2.79799282 1.87559213 0 P 0 Y
L 2.798 1.86995 2.76986004 1.86995 0 P 0 
L 3.168 1.965 3.15403996 1.97896004 0 P 0 
A 3.15403996 1.97896004 3.14188002 1.984 3.14187992 1.96681083 0 P 0 N
L 3.14188002 1.984 2.92315 1.984 0 P 0 
A 2.92315 1.984 2.90748996 1.97751004 2.92314961 1.9618624 0 P 0 N
L 2.90748996 1.97751004 2.88903002 1.95905 0 P 0 
A 2.88903002 1.95905 2.879 1.93483002 2.91325768 1.93482992 0 P 0 N
L 2.879 1.93483002 2.879 1.8696 0 P 0 
A 2.879 1.8696 2.8624 1.853 2.8624 1.8696 0 P 0 Y
L 2.8624 1.853 2.85661998 1.853 0 P 0 
A 2.85661998 1.853 2.85385 1.85185 2.85661998 1.84908898 0 P 0 N
L 2.85385 1.85185 2.845 1.843 0 P 0 
P 2.76986004 1.86995 98 P 0 8 0;0,2=76,4=0
P 3.168 1.965 63 P 0 8 0;0,2=2,4=0
P 2.77866998 0.93443002 17 P 0 8 0;2=75,4=0
L 4.97 1.54 4.97 1.586 1 P 0 
L 4.97 1.586 4.926 1.63 1 P 0 
P 4.97 1.54 11 P 0 8 0;2=8,4=0
P 4.926 1.63 63 P 0 8 0;0,2=2,4=0
P 4.9806 1.855 11 P 0 8 0;2=1,4=1
P 1.26066998 1.04043002 17 P 0 8 0;2=75,4=0
L 0.724 2.646 0.731 2.646 1 P 0 
L 0.731 2.646 0.746 2.661 1 P 0 
L 0.746 2.661 0.75896998 2.661 1 P 0 
L 0.68448002 2.664 0.706 2.664 1 P 0 
L 0.706 2.664 0.724 2.646 1 P 0 
P 0.724 2.646 11 P 0 8 0;2=1,4=1
P 0.68448002 2.664 63 P 0 8 0;0,2=2,4=0
P 0.75896998 2.661 45 P 0 8 0;0,2=48,4=0
L 0.714 2.79 0.714 2.771 1 P 0 
L 0.714 2.771 0.742 2.743 1 P 0 
L 0.742 2.743 0.758 2.743 1 P 0 
L 0.758 2.743 0.758 2.734 1 P 0 
L 0.758 2.734 0.77963996 2.71236004 1 P 0 
L 0.77963996 2.71236004 0.77963996 2.69151004 1 P 0 
P 0.758 2.743 9 P 0 8 0;2=9,4=1
P 0.714 2.79 63 P 0 8 0;0,2=2,4=0
P 0.77963996 2.69151004 32 P 0 8 0;0,2=52,4=0
L 3.275 2.32 3.225 2.32 1 P 0 
L 3.225 2.32 3.204 2.299 1 P 0 
L 3.204 2.299 3.201 2.299 1 P 0 
L 3.32848002 2.30416004 3.29083996 2.30416004 1 P 0 
L 3.29083996 2.30416004 3.275 2.32 1 P 0 
P 3.235 2.63 11 P 0 8 0;2=8,4=0
P 3.275 2.32 9 P 0 8 0;2=9,4=1
P 3.201 2.389 63 P 0 8 0;0,2=2,4=0
L 3.201 2.389 3.201 2.344 1 P 0 
P 3.201 2.299 63 P 0 8 0;0,2=2,4=0
L 3.201 2.299 3.201 2.344 1 P 0 
P 3.201 2.344 63 P 0 8 0;0,2=2,4=0
P 3.32848002 2.30416004 60 P 0 8 0;0,2=49,4=0
L 3.24 2.275 3.255 2.275 1 P 0 
L 3.255 2.275 3.2849 2.2451 1 P 0 
L 3.2849 2.2451 3.32848002 2.2451 1 P 0 
L 3.201 2.254 3.222 2.275 1 P 0 
L 3.222 2.275 3.24 2.275 1 P 0 
P 3.24 2.275 11 P 0 8 0;2=1,4=1
P 3.201 2.254 63 P 0 8 0;0,2=2,4=0
P 3.32848002 2.2451 60 P 0 8 0;0,2=49,4=0
P 3.305 2.65 11 P 0 8 0;2=8,4=0
P 3.375 2.65 11 P 0 8 0;2=8,4=0
P 3.326 2.466 9 P 0 8 0;2=9,4=1
L 3.326 2.466 3.337 2.466 1 P 0 
L 3.337 2.466 3.38016004 2.42283996 1 P 0 
L 3.38016004 2.42283996 3.38016004 2.40503996 1 P 0 
L 3.335 2.511 3.335 2.491 1 P 0 
L 3.335 2.491 3.326 2.482 1 P 0 
L 3.326 2.482 3.326 2.466 1 P 0 
P 3.335 2.511 58 P 0 8 0;0,2=2,4=0
P 3.38016004 2.40503996 30 P 0 8 0;0,2=50,4=0
P 2.1481 0.7881 9 P 0 8 0;2=24,4=1
P 5.08 1.105 11 P 0 8 0;2=7,4=1
P 5.225 1.145 11 P 0 8 0;2=7,4=1
P 5.132 0.66 11 P 0 8 0;2=7,4=1
P 2.0816 0.7399 11 P 0 8 0;2=7,4=1
P 2.03 0.75 9 P 0 8 0;2=24,4=1
P 5.08 1.155 11 P 0 8 0;2=7,4=1
P 5.08 1.055 11 P 0 8 0;2=7,4=1
P 2.0788 0.7874 9 P 0 8 0;2=24,4=1
P 2.29581998 0.48918002 11 P 0 8 0;2=8,4=0
P 2.633 0.522 9 P 0 8 0;2=26,4=1
L 2.633 0.522 2.633 0.579 1 P 0 
L 2.633 0.579 2.637 0.583 1 P 0 
L 2.637 0.583 2.637 0.605 1 P 0 
L 2.637 0.605 2.637 0.655 1 P 0 
P 2.637 0.655 63 P 0 8 0;0,2=2,4=0
P 2.754 0.605 70 P 0 8 0;0,2=58,4=0
L 2.754 0.605 2.7217 0.605 1 P 0 
L 2.7217 0.605 2.688 0.5713 1 P 0 
L 2.688 0.5713 2.688 0.547 1 P 0 
L 2.688 0.547 2.663 0.522 1 P 0 
L 2.663 0.522 2.633 0.522 1 P 0 
P 2.637 0.605 63 P 0 8 0;0,2=2,4=0
P 3.455 0.87 11 P 0 8 0;2=7,4=1
L 4.82 0.835 4.8278 0.8428 1 P 0 
L 4.8278 0.8428 4.8855 0.8428 1 P 0 
L 0.8825 1.7725 0.8825 1.6775 1 P 0 
L 0.8825 1.6775 0.91 1.65 1 P 0 
L 0.91 1.65 0.91 1.48 1 P 0 
L 0.91 1.48 0.93265 1.45735 1 P 0 
L 0.93265 1.45735 0.93265 1.44573996 1 P 0 
L 0.93265 1.44573996 0.94 1.43838996 1 P 0 
L 0.94 1.43838996 0.94 1.345 1 P 0 
L 0.94 1.345 0.97 1.315 1 P 0 
L 0.97 1.315 0.97 1.02 1 P 0 
L 0.97 1.02 0.9275 0.9775 1 P 0 
L 0.9275 0.9775 0.9225 0.9775 1 P 0 
P 0.9225 0.9775 11 P 0 8 0;2=7,4=1
P 4.82 0.835 11 P 0 8 0;2=1,4=1
P 4.8855 0.8428 94 P 0 8 0;0,2=10,4=0
P 0.8825 1.7725 11 P 0 8 0;2=7,4=1
P 3.405 0.87 11 P 0 8 0;2=7,4=1
L 0.965 0.98 0.99 1.005 1 P 0 
L 0.99 1.005 0.99 1.535 1 P 0 
L 0.99 1.535 0.955 1.57 1 P 0 
L 0.955 1.57 0.955 1.60838996 1 P 0 
L 0.955 1.60838996 0.96735 1.62073996 1 P 0 
L 0.96735 1.62073996 0.96735 1.63926004 1 P 0 
L 0.96735 1.63926004 0.95 1.65661004 1 P 0 
L 0.95 1.65661004 0.95 1.775 1 P 0 
L 0.95 1.775 0.91 1.815 1 P 0 
P 0.965 0.98 11 P 0 8 0;2=7,4=1
P 0.91 1.815 11 P 0 8 0;2=1,4=1
L 4.78 0.78 4.79398002 0.76601998 1 P 0 
L 4.79398002 0.76601998 4.8855 0.76601998 1 P 0 
P 4.78 0.78 11 P 0 8 0;2=7,4=1
P 4.8855 0.76601998 94 P 0 8 0;0,2=10,4=0
P 4.42311004 1.86311004 9 P 0 8 0;2=67,4=1
L 4.40343002 1.84343002 4.42311004 1.86311004 1 P 0 
P 4.40343002 1.84343002 10 P 0 8 0;0,2=5,4=0
P 3.58206998 1.89186998 69 P 0 8 0;0,2=55,4=0
P 3.65101004 1.88358996 9 P 0 8 0;2=38,4=1
L 3.58206998 1.89186998 3.6115 1.89186998 3 P 0 
L 3.6115 1.89186998 3.61153002 1.8919 3 P 0 
L 3.61153002 1.8919 3.63441004 1.8919 3 P 0 
A 3.63441004 1.8919 3.63693996 1.89203002 3.63447392 1.91533425 3 P 0 N
A 3.63693996 1.89203002 3.65101004 1.88358996 3.62710778 1.85969134 3 P 0 Y
P 4.46248002 1.86311004 9 P 0 8 0;2=67,4=1
L 4.4428 1.84343002 4.46248002 1.86311004 1 P 0 
P 4.4428 1.84343002 10 P 0 8 0;0,2=5,4=0
P 3.58206998 1.90761998 69 P 0 8 0;0,2=55,4=0
P 3.65101004 1.91558996 9 P 0 8 0;2=38,4=1
L 3.58206998 1.90761998 3.61148996 1.90761998 3 P 0 
L 3.61148996 1.90761998 3.61221004 1.9069 3 P 0 
L 3.61221004 1.9069 3.63441998 1.9069 3 P 0 
A 3.63441998 1.9069 3.63671004 1.90721004 3.63444439 1.91533189 3 P 0 N
A 3.63671004 1.90721004 3.65101004 1.91558996 3.62782411 1.93876457 3 P 0 N
L 3.065 1.695 3.124 1.695 1 P 0 
P 3.124 1.695 63 P 0 8 0;0,2=2,4=0
P 3.065 1.695 11 P 0 8 0;2=8,4=0
P 2.98283996 1.75183996 11 P 0 8 0;2=7,4=1
L 2.98283996 1.75183996 2.92733996 1.75183996 1 P 0 
P 2.92733996 1.75183996 98 P 0 8 0;0,2=76,4=0
L 5.914 1.125 5.865 1.125 1 P 0 
L 2.2628 3.245 2.4235 3.245 1 P 0 
L 2.4235 3.245 2.50025 3.32175 1 P 0 
L 2.50025 3.32175 2.71775 3.32175 1 P 0 
L 2.71775 3.32175 2.821 3.425 1 P 0 
L 2.821 3.425 3.155 3.425 1 P 0 
L 3.155 3.425 3.18 3.4 1 P 0 
L 3.18 3.4 3.18 3.365 1 P 0 
L 3.18 3.365 3.2428 3.3022 1 P 0 
L 3.2428 3.3022 3.2815 3.3022 1 P 0 
L 4.595 2.62 4.53 2.62 1 P 0 
L 4.53 2.62 4.5117 2.6017 1 P 0 
L 4.5117 2.6017 4.38366004 2.6017 1 P 0 
L 4.38366004 2.6017 4.29036004 2.695 1 P 0 
L 4.29036004 2.695 4.11 2.695 1 P 0 
L 4.11 2.695 4.045 2.76 1 P 0 
L 4.045 2.76 4.045 3.04 1 P 0 
L 4.045 3.04 4.025 3.06 1 P 0 
L 4.025 3.06 4.025 3.08 1 P 0 
L 2.225 3.245 2.2628 3.245 1 P 0 
P 2.225 3.245 11 P 0 8 0;2=7,4=1
P 2.2628 3.245 58 P 0 8 0;0,2=2,4=0
P 3.2815 3.3022 94 P 0 8 0;0,2=10,4=0
P 4.595 2.62 11 P 0 8 0;2=7,4=1
P 4.025 3.08 11 P 0 8 0;2=7,4=1
P 0.62 3.07 11 P 0 8 0;2=7,4=1
P 5.865 1.125 11 P 0 8 0;2=1,4=1
P 5.914 1.125 63 P 0 8 0;0,2=2,4=0
L 5.914 1.125 5.914 1.08 1 P 0 
P 5.914 1.08 63 P 0 8 0;0,2=2,4=0
L 5.865 1.07 5.88 1.055 1 P 0 
L 5.88 1.055 5.9513 1.055 1 P 0 
L 5.9513 1.055 5.956 1.0503 1 P 0 
L 5.956 1.0503 5.956 1.025 1 P 0 
L 6.0845 1.0578 6.0228 1.0578 1 P 0 
L 6.0228 1.0578 5.99 1.025 1 P 0 
L 5.99 1.025 5.956 1.025 1 P 0 
L 2.265 3.34 2.71 3.34 1 P 0 
L 2.71 3.34 2.82 3.45 1 P 0 
L 2.82 3.45 3.16 3.45 1 P 0 
L 3.16 3.45 3.195 3.415 1 P 0 
L 3.195 3.415 3.195 3.37498996 1 P 0 
L 3.195 3.37498996 3.24218996 3.3278 1 P 0 
L 3.24218996 3.3278 3.2815 3.3278 1 P 0 
P 6.0845 1.0578 93 P 0 8 0;0,2=42,4=0
P 5.865 1.07 11 P 0 8 0;2=1,4=1
L 2.265 3.34 2.175 3.34 1 P 0 
L 2.175 3.34 2.1478 3.3128 1 P 0 
L 2.1478 3.3128 2.1478 3.2655 1 P 0 
L 4.57 2.585 4.52498996 2.585 1 P 0 
L 4.52498996 2.585 4.51998996 2.58 1 P 0 
L 4.51998996 2.58 4.37 2.58 1 P 0 
L 4.37 2.58 4.275 2.675 1 P 0 
L 4.275 2.675 4.09463996 2.675 1 P 0 
L 4.09463996 2.675 4.025 2.74463996 1 P 0 
L 4.025 2.74463996 4.025 3.025 1 P 0 
L 4.025 3.025 4.02 3.03 1 P 0 
P 2.1478 3.2655 50 P 0 8 0;0,2=42,4=0
P 2.265 3.34 11 P 0 8 0;2=7,4=1
P 3.2815 3.3278 94 P 0 8 0;0,2=10,4=0
P 4.57 2.585 11 P 0 8 0;2=7,4=1
P 4.02 3.03 11 P 0 8 0;2=7,4=1
P 0.645 2.9675 11 P 0 8 0;2=7,4=1
P 5.956 1.025 63 P 0 8 0;0,2=2,4=0
L 4.00973002 1.8828 3.99005 1.90248002 1 P 0 
L 5.43503996 4.21653996 5.48828996 4.16328996 1 P 0 
P 5.48828996 4.16328996 11 P 0 8 0;2=1,4=1
P 5.43503996 4.21653996 24 P 0 8 0;0,2=36,4=0
P 4.00973002 1.8828 10 P 0 8 0;0,2=5,4=0
P 3.99005 1.90248002 9 P 0 8 0;2=4,4=1
L 4.00973002 1.84343002 3.99005 1.86311004 1 P 0 
L 5.55315 4.21653996 5.55315 4.175 1 P 0 
P 5.55315 4.175 11 P 0 8 0;2=1,4=1
P 5.55315 4.21653996 24 P 0 8 0;0,2=36,4=0
P 3.99005 1.86311004 9 P 0 8 0;2=4,4=1
P 4.00973002 1.84343002 10 P 0 8 0;0,2=5,4=0
L 3.95066998 1.82373996 3.97035 1.80406004 1 P 0 
L 5.67126004 4.21653996 5.67126004 4.175 1 P 0 
P 5.67126004 4.175 11 P 0 8 0;2=1,4=1
P 5.67126004 4.21653996 24 P 0 8 0;0,2=36,4=0
P 3.95066998 1.82373996 9 P 0 8 0;2=4,4=1
P 3.97035 1.80406004 10 P 0 8 0;0,2=5,4=0
L 3.9113 1.82373996 3.93098002 1.80406004 1 P 0 
L 5.78936998 4.21653996 5.78936998 4.175 1 P 0 
P 5.78936998 4.175 11 P 0 8 0;2=1,4=1
P 5.78936998 4.21653996 24 P 0 8 0;0,2=36,4=0
P 3.9113 1.82373996 9 P 0 8 0;2=4,4=1
P 3.93098002 1.80406004 10 P 0 8 0;0,2=5,4=0
L 4.205 2.295 4.11 2.2 1 P 0 
L 4.11 2.2 4.11 2.13686004 1 P 0 
L 4.11 2.13686004 4.12783996 2.11901998 1 P 0 
P 4.205 2.295 11 P 0 8 0;2=8,4=0
P 4.12783996 2.11901998 10 P 0 8 0;0,2=5,4=0
P 4.65933002 1.6269 11 P 0 8 0;2=8,4=0
P 4.63965 1.64658002 10 P 0 8 0;0,2=5,4=0
L 4.63965 1.64658002 4.65933002 1.6269 1 P 0 
L 4.254 2.296 4.12783996 2.16983996 1 P 0 
L 4.12783996 2.16983996 4.12783996 2.15838996 1 P 0 
P 4.254 2.296 11 P 0 8 0;2=8,4=0
P 4.12783996 2.15838996 10 P 0 8 0;0,2=5,4=0
L 4.23 2.354 4.202 2.326 1 P 0 
L 4.202 2.326 4.11938996 2.326 1 P 0 
L 4.11938996 2.326 4.03 2.23661004 1 P 0 
L 4.03 2.23661004 4.03 2.13811998 1 P 0 
L 4.03 2.13811998 4.0491 2.11901998 1 P 0 
P 4.23 2.354 11 P 0 8 0;2=8,4=0
P 4.0491 2.11901998 10 P 0 8 0;0,2=5,4=0
P 4.915 1.485 11 P 0 8 0;2=8,4=0
P 4.65933002 1.54816004 9 P 0 8 0;2=4,4=1
L 4.63965 1.56783996 4.65933002 1.54816004 1 P 0 
P 4.63965 1.56783996 10 P 0 8 0;0,2=5,4=0
P 3.94 2.235 11 P 0 8 0;2=8,4=0
L 3.94 2.235 3.96038002 2.21461998 1 P 0 
L 3.96038002 2.21461998 3.96038002 2.19461998 1 P 0 
L 3.96038002 2.19461998 3.99 2.165 1 P 0 
L 3.99 2.165 3.99 2.13875 1 P 0 
L 3.99 2.13875 4.00973002 2.11901998 1 P 0 
P 4.00973002 2.11901998 10 P 0 8 0;0,2=5,4=0
P 4.85 1.54 11 P 0 8 0;2=8,4=0
L 4.85 1.54 4.8 1.59 1 P 0 
L 4.8 1.59 4.69623002 1.59 1 P 0 
L 4.69623002 1.59 4.67901998 1.60721004 1 P 0 
P 4.67901998 1.60721004 10 P 0 8 0;0,2=5,4=0
L 4.149 2.298 4.149 2.289 1 P 0 
L 4.149 2.289 4.0491 2.1891 1 P 0 
L 4.0491 2.1891 4.0491 2.15838996 1 P 0 
P 4.149 2.298 11 P 0 8 0;2=8,4=0
P 4.0491 2.15838996 10 P 0 8 0;0,2=5,4=0
L 4.00973002 2.15838996 4.00973002 2.18138996 1 P 0 
L 4.00973002 2.18138996 4.014 2.18566004 1 P 0 
L 4.014 2.18566004 4.014 2.265 1 P 0 
L 4.014 2.265 4.103 2.354 1 P 0 
L 4.103 2.354 4.161 2.354 1 P 0 
P 4.161 2.354 11 P 0 8 0;2=8,4=0
P 4.00973002 2.15838996 10 P 0 8 0;0,2=5,4=0
P 3.75 2.1 11 P 0 8 0;2=8,4=0
L 3.75 2.1 3.79 2.14 1 P 0 
L 3.79 2.14 3.91 2.14 1 P 0 
L 3.91 2.14 3.93098002 2.11901998 1 P 0 
P 3.93098002 2.11901998 10 P 0 8 0;0,2=5,4=0
P 4.975 1.485 11 P 0 8 0;2=8,4=0
P 4.58058996 1.58753002 9 P 0 8 0;2=4,4=1
L 4.56091004 1.60721004 4.58058996 1.58753002 1 P 0 
P 4.56091004 1.60721004 10 P 0 8 0;0,2=5,4=0
P 3.8 2.1 11 P 0 8 0;2=8,4=0
L 3.8 2.1 3.81901998 2.11901998 1 P 0 
L 3.81901998 2.11901998 3.89161004 2.11901998 1 P 0 
P 3.89161004 2.11901998 10 P 0 8 0;0,2=5,4=0
P 4.73806998 1.54816004 11 P 0 8 0;2=8,4=0
P 4.71838996 1.56783996 10 P 0 8 0;0,2=5,4=0
L 4.71838996 1.56783996 4.73806998 1.54816004 1 P 0 
P 3.9 2.325 11 P 0 8 0;2=8,4=0
L 3.9 2.325 3.9 2.22873996 1 P 0 
L 3.9 2.22873996 3.97035 2.15838996 1 P 0 
P 3.97035 2.15838996 10 P 0 8 0;0,2=5,4=0
P 4.73806998 1.50878996 11 P 0 8 0;2=8,4=0
P 4.71838996 1.52846998 10 P 0 8 0;0,2=5,4=0
L 4.71838996 1.52846998 4.73806998 1.50878996 1 P 0 
L 3.83 2.325 3.875 2.28 1 P 0 
L 3.875 2.28 3.875 2.21436998 1 P 0 
L 3.875 2.21436998 3.93098002 2.15838996 1 P 0 
P 3.83 2.325 11 P 0 8 0;2=8,4=0
P 3.93098002 2.15838996 10 P 0 8 0;0,2=5,4=0
L 3.28 3.065 3.24 3.105 1 P 0 
L 3.24 3.105 3.07 3.105 1 P 0 
L 3.07 3.105 3.005 3.04 1 P 0 
L 3.005 3.04 2.90671004 3.04 1 P 0 
L 2.90671004 3.04 2.815 3.13171004 1 P 0 
L 2.815 3.13171004 2.815 3.39 1 P 0 
L 2.815 3.39 2.82956998 3.40456998 1 P 0 
L 2.82956998 3.40456998 3.0425 3.40456998 1 P 0 
L 0.846 2.489 0.8338 2.4768 1 P 0 
L 0.8338 2.4768 0.8338 2.4275 1 P 0 
P 0.8338 2.4275 50 P 0 8 0;0,2=42,4=0
P 0.846 2.489 9 P 0 8 0;2=9,4=1
P 3.28 3.065 11 P 0 8 0;2=7,4=1
P 3.0425 3.40456998 94 P 0 8 0;0,2=10,4=0
L 3.325 3.065 3.265 3.125 1 P 0 
L 3.265 3.125 3.05 3.125 1 P 0 
L 3.05 3.125 2.99 3.065 1 P 0 
L 2.99 3.065 2.91 3.065 1 P 0 
L 2.91 3.065 2.835 3.14 1 P 0 
L 2.835 3.14 2.835 3.37 1 P 0 
L 2.835 3.37 2.84398002 3.37898002 1 P 0 
L 2.84398002 3.37898002 3.0425 3.37898002 1 P 0 
L 0.796 2.489 0.8082 2.4768 1 P 0 
L 0.8082 2.4768 0.8082 2.4275 1 P 0 
P 0.8082 2.4275 50 P 0 8 0;0,2=42,4=0
P 0.796 2.489 9 P 0 8 0;2=9,4=1
P 3.325 3.065 11 P 0 8 0;2=7,4=1
P 3.0425 3.37898002 94 P 0 8 0;0,2=10,4=0
L 5.03 3.546 5.03 3.715 1 P 0 
L 5.03 3.715 4.99 3.755 1 P 0 
L 4.99 3.755 4.99 3.78 1 P 0 
L 4.99 3.78 4.94046998 3.82953002 1 P 0 
L 4.94046998 3.82953002 4.91548996 3.82953002 1 P 0 
L 4.985 3.546 5.03 3.546 1 P 0 
P 4.985 3.546 58 P 0 8 0;0,2=2,4=0
P 5.03 3.546 9 P 0 8 0;2=9,4=1
P 4.91548996 3.82953002 106 P 0 8 0;0,2=20,4=0
L 4.91548996 3.75078996 4.96921004 3.75078996 1 P 0 
L 4.96921004 3.75078996 5.0127 3.7073 1 P 0 
L 5.0127 3.7073 5.0127 3.5947 1 P 0 
L 5.0127 3.5947 5.008 3.59 1 P 0 
L 5.008 3.59 4.98698996 3.59 1 P 0 
L 4.98698996 3.59 4.98228996 3.5947 1 P 0 
L 4.98228996 3.5947 4.98228996 3.6203 1 P 0 
L 4.98228996 3.6203 4.97758996 3.625 1 P 0 
L 4.97758996 3.625 4.96228996 3.625 1 P 0 
L 4.96228996 3.625 4.95758996 3.6203 1 P 0 
L 4.95758996 3.6203 4.95758996 3.5947 1 P 0 
L 4.95758996 3.5947 4.95288996 3.59 1 P 0 
L 4.95288996 3.59 4.935 3.59 1 P 0 
P 4.935 3.546 58 P 0 8 0;0,2=2,4=0
L 4.935 3.546 4.885 3.546 1 P 0 
L 4.935 3.59 4.935 3.546 1 P 0 
P 4.885 3.546 58 P 0 8 0;0,2=2,4=0
P 4.935 3.59 9 P 0 8 0;2=9,4=1
P 4.91548996 3.75078996 106 P 0 8 0;0,2=20,4=0
P 4.785 3.546 58 P 0 8 0;0,2=2,4=0
L 4.785 3.546 4.735 3.546 1 P 0 
P 4.735 3.546 58 P 0 8 0;0,2=2,4=0
L 4.735 3.546 4.679 3.546 1 P 0 
L 4.679 3.546 4.67 3.555 1 P 0 
L 4.78656004 3.82953002 4.72653002 3.82953002 1 P 0 
L 4.72653002 3.82953002 4.711 3.814 1 P 0 
L 4.711 3.814 4.711 3.754 1 P 0 
L 4.711 3.754 4.655 3.698 1 P 0 
L 4.655 3.698 4.655 3.57 1 P 0 
L 4.655 3.57 4.67 3.555 1 P 0 
P 4.67 3.555 11 P 0 8 0;2=8,4=0
P 4.78656004 3.82953002 106 P 0 8 0;0,2=20,4=0
L 4.885 3.59 4.885 3.59921004 1 P 0 
L 4.885 3.59921004 4.91548996 3.6297 1 P 0 
L 4.91548996 3.6297 4.91548996 3.67205 1 P 0 
P 4.885 3.59 9 P 0 8 0;2=24,4=1
P 4.91548996 3.67205 106 P 0 8 0;0,2=20,4=0
L 4.835 3.546 4.787 3.594 1 P 0 
L 4.787 3.594 4.698 3.594 1 P 0 
L 4.698 3.594 4.681 3.611 1 P 0 
L 4.681 3.611 4.681 3.671 1 P 0 
L 4.681 3.671 4.70461998 3.69461998 1 P 0 
P 4.835 3.546 58 P 0 8 0;0,2=2,4=0
P 4.70461998 3.69461998 9 P 0 8 0;2=9,4=1
L 4.78656004 3.75078996 4.76078996 3.75078996 1 P 0 
L 4.76078996 3.75078996 4.70461998 3.69461998 1 P 0 
P 4.78656004 3.75078996 106 P 0 8 0;0,2=20,4=0
P 4.50185 1.82373996 9 P 0 8 0;2=4,4=1
P 5.395 2.92 11 P 0 8 0;2=1,4=1
L 4.50185 1.82373996 4.48216998 1.80406004 1 P 0 
P 4.48216998 1.80406004 10 P 0 8 0;0,2=5,4=0
P 5.015 1.925 11 P 0 8 0;2=7,4=1
P 5.39976998 2.75123996 9 P 0 8 0;2=24,4=1
P 4.46248002 1.82373996 9 P 0 8 0;2=4,4=1
P 5.375 2.96606998 9 P 0 8 0;2=24,4=1
L 4.4428 1.80406004 4.46248002 1.82373996 1 P 0 
P 4.4428 1.80406004 10 P 0 8 0;0,2=5,4=0
P 4.58058996 1.78436998 9 P 0 8 0;2=4,4=1
P 5.4525 2.563 9 P 0 8 0;2=24,4=1
P 4.56091004 1.76468996 10 P 0 8 0;0,2=5,4=0
L 4.56091004 1.76468996 4.58058996 1.78436998 1 P 0 
P 3.545 0.6092 11 P 0 8 0;2=7,4=1
L 1.395 0.625 1.421 0.599 1 P 0 
L 1.421 0.599 1.4293 0.599 1 P 0 
L 1.4293 0.599 1.434 0.5943 1 P 0 
L 1.434 0.5943 1.434 0.5737 1 P 0 
L 1.434 0.5737 1.4293 0.569 1 P 0 
L 1.4293 0.569 1.362 0.569 1 P 0 
L 1.362 0.569 1.3505 0.5805 1 P 0 
L 1.3505 0.5805 1.3505 0.613 1 P 0 
L 5.085 0.645 5.08 0.65 1 P 0 
L 5.08 0.65 5.08 0.73673002 1 P 0 
L 5.08 0.73673002 5.0837 0.74043002 1 P 0 
L 5.0837 0.74043002 5.1245 0.74043002 1 P 0 
P 5.1245 0.74043002 94 P 0 8 0;0,2=10,4=0
P 1.395 0.625 9 P 0 8 0;2=24,4=1
P 5.085 0.645 11 P 0 8 0;2=7,4=1
P 1.3505 0.613 63 P 0 8 0;0,2=2,4=0
P 3.495 0.61 11 P 0 8 0;2=7,4=1
L 1.485 0.625 1.45 0.66 1 P 0 
L 1.45 0.66 1.45 0.705 1 P 0 
L 1.45 0.705 1.435 0.72 1 P 0 
L 1.435 0.72 1.395 0.72 1 P 0 
L 1.395 0.72 1.383 0.708 1 P 0 
L 1.383 0.708 1.3507 0.708 1 P 0 
L 5.04 0.645 5.04 0.77701998 1 P 0 
L 5.04 0.77701998 5.08018002 0.8172 1 P 0 
L 5.08018002 0.8172 5.1245 0.8172 1 P 0 
P 5.1245 0.8172 94 P 0 8 0;0,2=10,4=0
P 5.04 0.645 11 P 0 8 0;2=7,4=1
P 1.485 0.625 9 P 0 8 0;2=24,4=1
P 1.3507 0.708 63 P 0 8 0;0,2=2,4=0
L 4.00973002 1.64658002 3.99005 1.6269 0 P 0 
P 3.99005 1.6269 9 P 0 8 0;2=67,4=1
P 4.00973002 1.64658002 10 P 0 8 0;0,2=5,4=0
P 2.95835 0.385 9 P 0 8 0;2=38,4=1
L 2.8996 0.13781004 2.8996 0.21808002 3 P 0 
A 2.8996 0.21808002 2.90396004 0.2286 2.91447156 0.21807992 3 P 0 Y
L 2.90396004 0.2286 2.90768996 0.23233002 3 P 0 
A 2.90768996 0.23233002 2.912 0.24273002 2.89729744 0.24273002 3 P 0 N
L 2.912 0.24273002 2.912 0.3543 3 P 0 
A 2.912 0.3543 2.93353002 0.37593996 2.93364026 0.3542999 3 P 0 Y
L 2.93353002 0.37593996 2.94511998 0.376 3 P 0 
L 2.94511998 0.376 2.94616004 0.376 3 P 0 
A 2.94616004 0.376 2.95163002 0.37826998 2.94615541 0.38373642 3 P 0 N
L 2.95163002 0.37826998 2.95835 0.385 3 P 0 
P 2.8996 0.13781004 62 P 0 8 0;0,2=74,4=0
L 3.97035 1.64658002 3.95066998 1.6269 0 P 0 
P 3.95066998 1.6269 9 P 0 8 0;2=67,4=1
P 3.97035 1.64658002 10 P 0 8 0;0,2=5,4=0
P 2.95835 0.353 9 P 0 8 0;2=38,4=1
L 2.93896998 0.13781004 2.93896998 0.21563996 3 P 0 
A 2.93896998 0.21563996 2.9329 0.23028996 2.918256 0.21563996 3 P 0 N
L 2.9329 0.23028996 2.93273996 0.23045 3 P 0 
A 2.93273996 0.23045 2.927 0.24431004 2.94660344 0.24430994 3 P 0 Y
L 2.927 0.24431004 2.927 0.3543 3 P 0 
A 2.927 0.3543 2.93361004 0.36093996 2.93364006 0.3542999 3 P 0 Y
L 2.93361004 0.36093996 2.94516004 0.361 3 P 0 
L 2.94516004 0.361 2.94616998 0.361 3 P 0 
A 2.94616998 0.361 2.9533 0.35803996 2.94616181 0.35091329 3 P 0 Y
L 2.9533 0.35803996 2.95835 0.353 3 P 0 
P 2.93896998 0.13781004 62 P 0 8 0;0,2=74,4=0
L 3.93098002 1.68595 3.9113 1.66626998 0 P 0 
P 3.9113 1.66626998 9 P 0 8 0;2=67,4=1
P 3.93098002 1.68595 10 P 0 8 0;0,2=5,4=0
P 2.80086998 0.385 9 P 0 8 0;2=38,4=1
L 2.74211998 0.13781004 2.74211998 0.21585 3 P 0 
A 2.74211998 0.21585 2.74805 0.23016998 2.7623753 0.2158499 3 P 0 Y
L 2.74805 0.23016998 2.75106998 0.23318996 3 P 0 
A 2.75106998 0.23318996 2.755 0.24266998 2.74160108 0.24266998 3 P 0 N
L 2.755 0.24266998 2.755 0.35138996 3 P 0 
A 2.755 0.35138996 2.78061004 0.377 2.78061004 0.35138996 3 P 0 Y
L 2.78061004 0.377 2.78993996 0.377 3 P 0 
A 2.78993996 0.377 2.79493996 0.37906998 2.78993996 0.38407362 3 P 0 N
L 2.79493996 0.37906998 2.80086998 0.385 3 P 0 
P 2.74211998 0.13781004 62 P 0 8 0;0,2=74,4=0
L 3.89161004 1.68595 3.87193002 1.66626998 0 P 0 
P 3.87193002 1.66626998 9 P 0 8 0;2=67,4=1
P 3.89161004 1.68595 10 P 0 8 0;0,2=5,4=0
P 2.80086998 0.353 9 P 0 8 0;2=38,4=1
L 2.78148996 0.13781004 2.78148996 0.21563996 3 P 0 
A 2.78148996 0.21563996 2.77541998 0.23028996 2.76077608 0.21563996 3 P 0 N
L 2.77541998 0.23028996 2.77503996 0.23066998 3 P 0 
A 2.77503996 0.23066998 2.77 0.24283996 2.78721339 0.24283986 3 P 0 Y
L 2.77 0.24283996 2.77 0.35138996 3 P 0 
A 2.77 0.35138996 2.78061004 0.362 2.78061004 0.35138996 3 P 0 Y
L 2.78061004 0.362 2.78943002 0.362 3 P 0 
A 2.78943002 0.362 2.79358996 0.36026998 2.78942165 0.35611348 3 P 0 Y
L 2.79358996 0.36026998 2.80086998 0.353 3 P 0 
P 2.78148996 0.13781004 62 P 0 8 0;0,2=74,4=0
L 4.00973002 1.72531998 3.99005 1.70563996 0 P 0 
P 3.99005 1.70563996 9 P 0 8 0;2=67,4=1
P 4.00973002 1.72531998 10 P 0 8 0;0,2=5,4=0
P 2.64338996 0.385 9 P 0 8 0;2=38,4=1
L 2.58463996 0.13781004 2.58463996 0.22171004 3 P 0 
A 2.58463996 0.22171004 2.58671998 0.22673002 2.5917378 0.22170994 3 P 0 Y
L 2.58671998 0.22673002 2.59253996 0.23255 3 P 0 
A 2.59253996 0.23255 2.59681998 0.24288002 2.58221398 0.24288002 3 P 0 N
L 2.59681998 0.24288002 2.59681998 0.35186998 3 P 0 
A 2.59681998 0.35186998 2.60461004 0.36986004 2.62145325 0.35188484 3 P 0 Y
A 2.60461004 0.36986004 2.6202 0.376 2.62016634 0.35322303 3 P 0 Y
L 2.6202 0.376 2.63251998 0.376 3 P 0 
L 2.63251998 0.376 2.63251998 0.3765 3 P 0 
A 2.63251998 0.3765 2.63656004 0.37816998 2.63252411 0.38221171 3 P 0 N
L 2.63656004 0.37816998 2.64338996 0.385 3 P 0 
P 2.58463996 0.13781004 62 P 0 8 0;0,2=74,4=0
P 3.95066998 1.70563996 9 P 0 8 0;2=67,4=1
L 3.97035 1.72531998 3.95066998 1.70563996 0 P 0 
P 3.97035 1.72531998 10 P 0 8 0;0,2=5,4=0
P 2.64338996 0.353 9 P 0 8 0;2=38,4=1
L 2.62401004 0.13781004 2.62401004 0.2169 3 P 0 
A 2.62401004 0.2169 2.619 0.229 2.60690049 0.21690295 3 P 0 N
L 2.619 0.229 2.61543996 0.23256004 3 P 0 
A 2.61543996 0.23256004 2.61181998 0.2413 2.62418081 0.2413 3 P 0 Y
L 2.61181998 0.2413 2.61181998 0.35186998 3 P 0 
A 2.61181998 0.35186998 2.61486998 0.3589 2.62144675 0.35186998 3 P 0 Y
A 2.61486998 0.3589 2.62018996 0.361 2.62018278 0.35322943 3 P 0 Y
L 2.62018996 0.361 2.63303002 0.361 3 P 0 
A 2.63303002 0.361 2.63706004 0.35933002 2.63302904 0.3553 3 P 0 Y
L 2.63706004 0.35933002 2.64338996 0.353 3 P 0 
P 2.62401004 0.13781004 62 P 0 8 0;0,2=74,4=0
L 3.93098002 1.60721004 3.9113 1.58753002 0 P 0 
P 3.9113 1.58753002 9 P 0 8 0;2=67,4=1
P 3.93098002 1.60721004 10 P 0 8 0;0,2=5,4=0
P 2.95835 0.481 9 P 0 8 0;2=38,4=1
L 2.95835 0.481 2.95553996 0.4782 3 P 0 
A 2.95553996 0.4782 2.943 0.473 2.94299291 0.49073711 3 P 0 Y
L 2.943 0.473 2.65908002 0.473 3 P 0 
A 2.65908002 0.473 2.577 0.439 2.65908691 0.35690787 3 P 0 N
L 2.577 0.439 2.556 0.418 3 P 0 
A 2.556 0.418 2.50528996 0.397 2.50530089 0.4686998 3 P 0 Y
L 2.50528996 0.397 2.48366004 0.397 3 P 0 
A 2.48366004 0.397 2.44973002 0.38295 2.48365413 0.34901949 3 P 0 N
L 2.44973002 0.38295 2.41393002 0.34715 3 P 0 
A 2.41393002 0.34715 2.4 0.31351004 2.44757018 0.31351575 3 P 0 N
L 2.4 0.31351004 2.4 0.24441004 3 P 0 
A 2.4 0.24441004 2.39436998 0.23081998 2.38078287 0.24440994 3 P 0 Y
L 2.39436998 0.23081998 2.39288002 0.22933002 3 P 0 
A 2.39288002 0.22933002 2.38778996 0.21705 2.40514823 0.2170499 3 P 0 N
L 2.38778996 0.21705 2.38778996 0.13781004 3 P 0 
P 2.38778996 0.13781004 62 P 0 8 0;0,2=74,4=0
P 2.95835 0.449 9 P 0 8 0;2=38,4=1
L 3.89161004 1.60721004 3.87193002 1.58753002 0 P 0 
P 3.87193002 1.58753002 9 P 0 8 0;2=67,4=1
P 3.89161004 1.60721004 10 P 0 8 0;0,2=5,4=0
L 2.42716004 0.13781004 2.42716004 0.21806004 3 P 0 
A 2.42716004 0.21806004 2.4228 0.22858002 2.41228848 0.21805994 3 P 0 N
L 2.4228 0.22858002 2.42041998 0.23096004 3 P 0 
A 2.42041998 0.23096004 2.415 0.24405 2.43351703 0.24405 3 P 0 Y
L 2.415 0.24405 2.415 0.31351004 3 P 0 
A 2.415 0.31351004 2.42453996 0.33653996 2.44756772 0.31350994 3 P 0 Y
L 2.42453996 0.33653996 2.46033996 0.37233996 3 P 0 
A 2.46033996 0.37233996 2.48366004 0.382 2.48365994 0.34902185 3 P 0 Y
L 2.48366004 0.382 2.50528996 0.382 3 P 0 
A 2.50528996 0.382 2.56661004 0.40738996 2.50530709 0.46870148 3 P 0 N
L 2.56661004 0.40738996 2.58761004 0.42838996 3 P 0 
A 2.58761004 0.42838996 2.65908996 0.458 2.65909311 0.35690955 3 P 0 Y
L 2.65908996 0.458 2.941 0.458 3 P 0 
A 2.941 0.458 2.95526004 0.4521 2.94100807 0.43783661 3 P 0 Y
L 2.95526004 0.4521 2.95835 0.449 3 P 0 
P 2.42716004 0.13781004 62 P 0 8 0;0,2=74,4=0
P 3.125 0.875 9 P 0 8 0;2=38,4=1
L 4.00973002 1.56783996 3.99005 1.54816004 0 P 0 
P 3.99005 1.54816004 9 P 0 8 0;2=67,4=1
P 4.00973002 1.56783996 10 P 0 8 0;0,2=5,4=0
P 3.14763002 0.85236998 9 P 0 8 0;2=38,4=1
L 3.97035 1.56783996 3.95066998 1.54816004 0 P 0 
P 3.95066998 1.54816004 9 P 0 8 0;2=67,4=1
P 3.97035 1.56783996 10 P 0 8 0;0,2=5,4=0
P 2.81855 0.763 9 P 0 8 0;2=38,4=1
L 3.93098002 1.52846998 3.9113 1.50878996 0 P 0 
P 3.9113 1.50878996 9 P 0 8 0;2=67,4=1
P 3.93098002 1.52846998 10 P 0 8 0;0,2=5,4=0
P 2.85055 0.763 9 P 0 8 0;2=38,4=1
L 3.89161004 1.52846998 3.87193002 1.50878996 0 P 0 
P 3.87193002 1.50878996 9 P 0 8 0;2=67,4=1
P 3.89161004 1.52846998 10 P 0 8 0;0,2=5,4=0
P 2.66706998 0.763 9 P 0 8 0;2=38,4=1
L 4.00973002 1.4891 3.99005 1.46941998 0 P 0 
P 3.99005 1.46941998 9 P 0 8 0;2=67,4=1
P 4.00973002 1.4891 10 P 0 8 0;0,2=5,4=0
P 2.69906998 0.763 9 P 0 8 0;2=38,4=1
L 3.97035 1.4891 3.95066998 1.46941998 0 P 0 
P 3.95066998 1.46941998 9 P 0 8 0;2=67,4=1
P 3.97035 1.4891 10 P 0 8 0;0,2=5,4=0
P 2.47021998 0.763 9 P 0 8 0;2=38,4=1
L 3.93098002 1.44973002 3.9113 1.43005 0 P 0 
P 3.9113 1.43005 9 P 0 8 0;2=67,4=1
P 3.93098002 1.44973002 10 P 0 8 0;0,2=5,4=0
P 2.50221998 0.763 9 P 0 8 0;2=38,4=1
L 3.89161004 1.44973002 3.87193002 1.43005 0 P 0 
P 3.87193002 1.43005 9 P 0 8 0;2=67,4=1
P 3.89161004 1.44973002 10 P 0 8 0;0,2=5,4=0
P 1.889 0.5496 11 P 0 8 0;2=7,4=1
L 2.435 0.4865 2.435 0.592 1 P 0 
L 2.435 0.592 2.469 0.626 1 P 0 
L 2.469 0.626 2.51121998 0.626 1 P 0 
P 2.51121998 0.626 58 P 0 8 0;0,2=2,4=0
P 2.435 0.4865 9 P 0 8 0;2=9,4=1
L 3.56 3.023 3.542 3.005 1 P 0 
L 3.542 3.005 3.385 3.005 1 P 0 
L 3.385 3.005 3.375 3.015 1 P 0 
L 3.375 3.015 3.375 3.075 1 P 0 
L 3.375 3.075 3.31585 3.13415 1 P 0 
L 3.31585 3.13415 3.31585 3.14078996 1 P 0 
L 3.31585 3.14078996 3.3292 3.15413996 1 P 0 
L 3.3292 3.15413996 3.3292 3.16078002 1 P 0 
L 3.3292 3.16078002 3.31836998 3.17161004 1 P 0 
L 3.31836998 3.17161004 3.31173002 3.17161004 1 P 0 
L 3.31173002 3.17161004 3.29838002 3.15826004 1 P 0 
L 3.29838002 3.15826004 3.29173996 3.15826004 1 P 0 
L 3.29173996 3.15826004 3.2825 3.1675 1 P 0 
L 3.2825 3.1675 3.2075 3.1675 1 P 0 
L 3.2075 3.1675 3.155 3.22 1 P 0 
L 3.155 3.22 3.155 3.33498996 1 P 0 
L 3.155 3.33498996 3.11998996 3.37 1 P 0 
L 3.11998996 3.37 3.093 3.37 1 P 0 
L 3.093 3.37 3.07638996 3.35338996 1 P 0 
L 3.07638996 3.35338996 3.0425 3.35338996 1 P 0 
P 3.56 3.023 11 P 0 8 0;2=1,4=1
P 3.0425 3.35338996 94 P 0 8 0;0,2=10,4=0
L 3.57 2.955 3.545 2.98 1 P 0 
L 3.545 2.98 3.385 2.98 1 P 0 
L 3.385 2.98 3.355 3.01 1 P 0 
L 3.355 3.01 3.355 3.07 1 P 0 
L 3.355 3.07 3.275 3.15 1 P 0 
L 3.275 3.15 3.195 3.15 1 P 0 
L 3.195 3.15 3.131 3.214 1 P 0 
L 3.131 3.214 3.131 3.315 1 P 0 
L 3.131 3.315 3.1182 3.3278 1 P 0 
L 3.1182 3.3278 3.0425 3.3278 1 P 0 
P 3.57 2.955 11 P 0 8 0;2=1,4=1
P 3.0425 3.3278 94 P 0 8 0;0,2=10,4=0
P 2.848 0.57941004 70 P 0 8 0;0,2=58,4=0
L 2.848 0.57941004 2.949 0.57941004 1 P 0 
L 2.949 0.57941004 2.954 0.57441004 1 P 0 
P 2.954 0.57441004 63 P 0 8 0;0,2=2,4=0
L 5.03005 0.99493996 5 0.96488996 1 P 0 
L 5 0.96488996 5 0.72501004 1 P 0 
L 5 0.72501004 4.94998996 0.675 1 P 0 
L 4.94998996 0.675 4.725 0.675 1 P 0 
L 4.725 0.675 4.705 0.655 1 P 0 
L 4.705 0.655 3.63 0.655 1 P 0 
L 3.63 0.655 3.57 0.715 1 P 0 
L 3.57 0.715 3.12753002 0.715 1 P 0 
L 3.12753002 0.715 3.042 0.62946998 1 P 0 
L 3.042 0.62946998 3.042 0.57693996 1 P 0 
L 3.042 0.57693996 3.01511998 0.55006004 1 P 0 
L 3.01511998 0.55006004 2.95493996 0.55006004 1 P 0 
L 2.95493996 0.55006004 2.954 0.551 1 P 0 
L 2.954 0.551 2.954 0.57441004 1 P 0 
L 4.975 2.14 4.97 2.135 1 P 0 
L 4.97 2.135 4.97 2.10998996 1 P 0 
L 4.97 2.10998996 4.93001004 2.07 1 P 0 
L 4.93001004 2.07 4.926 2.07 1 P 0 
P 4.975 2.14 11 P 0 8 0;2=7,4=1
P 4.926 2.07 63 P 0 8 0;0,2=2,4=0
P 5.03005 0.99493996 11 P 0 8 0;2=1,4=1
P 6.4105 2.13583002 87 P 0 8 0;0,2=56,4=0
P 2.19093996 0.13781004 62 P 0 8 0;0,2=74,4=0
P 3.01771004 0.13781004 62 P 0 8 0;0,2=74,4=0
P 2.30905 0.13781004 62 P 0 8 0;0,2=74,4=0
P 2.1122 0.13781004 62 P 0 8 0;0,2=74,4=0
P 0.7574 3.3935 53 P 0 8 0;0,2=6,4=0
P 0.6826 3.3935 53 P 0 8 0;0,2=6,4=0
P 6.23248996 2.31483996 53 P 0 8 0;0,2=6,4=0
P 6.30728996 2.31483996 53 P 0 8 0;0,2=6,4=0
P 3.55188996 1.94555 109 P 0 8 0;0,2=68,4=0
P 3.53613996 1.94555 109 P 0 8 0;0,2=68,4=0
P 2.754 0.63058996 70 P 0 8 0;0,2=58,4=0
P 3.98 0.75216998 90 P 0 8 0;0,2=13,4=0
P 4.364 0.82366004 59 P 0 8 0;0,2=12,4=0
P 5.68466998 0.679 75 P 0 8 0;0,2=22,4=0
P 5.04833002 2.707 75 P 0 8 0;0,2=22,4=0
P 3.912 3.00466998 36 P 0 8 0;0,2=22,4=0
P 2.92733996 1.77151998 98 P 0 8 0;0,2=76,4=0
P 2.92733996 1.79121004 98 P 0 8 0;0,2=76,4=0
P 2.92733996 1.81088996 98 P 0 8 0;0,2=76,4=0
P 2.76986004 1.81088996 98 P 0 8 0;0,2=76,4=0
P 2.92733996 1.83058002 98 P 0 8 0;0,2=76,4=0
P 2.76986004 1.83058002 98 P 0 8 0;0,2=76,4=0
P 2.92733996 1.85026004 98 P 0 8 0;0,2=76,4=0
P 3.45151998 2.30416004 60 P 0 8 0;0,2=49,4=0
P 3.45151998 2.28446998 60 P 0 8 0;0,2=49,4=0
P 3.45151998 2.26478996 60 P 0 8 0;0,2=49,4=0
P 3.45151998 2.2451 60 P 0 8 0;0,2=49,4=0
P 3.32848002 2.26478996 60 P 0 8 0;0,2=49,4=0
P 3.32848002 2.28446998 60 P 0 8 0;0,2=49,4=0
P 3.32848002 2.36321004 60 P 0 8 0;0,2=49,4=0
P 3.32848002 2.3829 60 P 0 8 0;0,2=49,4=0
P 3.45151998 2.40258002 60 P 0 8 0;0,2=49,4=0
P 4.20306004 3.8954 38 P 0 8 0;0,2=47,4=0
P 4.18336998 3.8969 39 P 0 8 0;0,2=46,4=0
P 4.16368996 3.8969 39 P 0 8 0;0,2=46,4=0
P 4.20058996 3.4824 49 P 0 8 0;0,2=11,4=0
P 4.00558996 3.4804 49 P 0 8 0;0,2=11,4=0
P 1.73966998 3.015 75 P 0 8 0;0,2=22,4=0
P 1.03441998 3.12 40 P 0 8 0;0,2=18,4=0
P 1.352 3.4179 96 P 0 8 0;0,2=18,4=0
P 1.352 3.39821004 96 P 0 8 0;0,2=18,4=0
P 1.352 3.37853002 96 P 0 8 0;0,2=18,4=0
P 1.352 3.35883996 96 P 0 8 0;0,2=18,4=0
P 1.352 3.31946998 96 P 0 8 0;0,2=18,4=0
P 1.352 3.29978996 96 P 0 8 0;0,2=18,4=0
P 1.352 3.2801 96 P 0 8 0;0,2=18,4=0
P 1.23126998 3.12 40 P 0 8 0;0,2=18,4=0
P 1.21158002 3.12 40 P 0 8 0;0,2=18,4=0
P 1.1919 3.12 40 P 0 8 0;0,2=18,4=0
P 1.17221004 3.12 40 P 0 8 0;0,2=18,4=0
P 1.13283996 3.12 40 P 0 8 0;0,2=18,4=0
P 1.11316004 3.12 40 P 0 8 0;0,2=18,4=0
P 5.638 3.907 11 P 0 8 0;2=1,4=1
P 1.8317 0.5639 9 P 0 8 0;2=24,4=1
L 3.82999902 -1.25 3.82999902 -1.33 4 P 0 ;1,3=95,5=0.000000
L 3.8070003 -1.25 3.85299961 -1.25 4 P 0 ;1,3=95,5=0.000000
L 3.90999902 -1.33 3.90199892 -1.32866703 4 P 0 ;1,3=95,5=0.000000
L 3.90199892 -1.32866703 3.89500039 -1.32333484 4 P 0 ;1,3=95,5=0.000000
L 3.89500039 -1.32333484 3.8889999 -1.31533406 4 P 0 ;1,3=95,5=0.000000
L 3.8889999 -1.31533406 3.88499892 -1.3060003 4 P 0 ;1,3=95,5=0.000000
L 3.88499892 -1.3060003 3.88299931 -1.29533346 4 P 0 ;1,3=95,5=0.000000
L 3.88299931 -1.29533346 3.88299931 -1.28466663 4 P 0 ;1,3=95,5=0.000000
L 3.88299931 -1.28466663 3.88499892 -1.2739998 4 P 0 ;1,3=95,5=0.000000
L 3.88499892 -1.2739998 3.8889999 -1.26466604 4 P 0 ;1,3=95,5=0.000000
L 3.8889999 -1.26466604 3.89500039 -1.25666772 4 P 0 ;1,3=95,5=0.000000
L 3.89500039 -1.25666772 3.90199892 -1.25133307 4 P 0 ;1,3=95,5=0.000000
L 3.90199892 -1.25133307 3.90999902 -1.25 4 P 0 ;1,3=95,5=0.000000
L 3.90999902 -1.25 3.91799911 -1.25133307 4 P 0 ;1,3=95,5=0.000000
L 3.91799911 -1.25133307 3.92499951 -1.25666772 4 P 0 ;1,3=95,5=0.000000
L 3.92499951 -1.25666772 3.931 -1.26466604 4 P 0 ;1,3=95,5=0.000000
L 3.931 -1.26466604 3.93500098 -1.2739998 4 P 0 ;1,3=95,5=0.000000
L 3.93500098 -1.2739998 3.93700059 -1.28466663 4 P 0 ;1,3=95,5=0.000000
L 3.93700059 -1.28466663 3.93700059 -1.29533346 4 P 0 ;1,3=95,5=0.000000
L 3.93700059 -1.29533346 3.93500098 -1.3060003 4 P 0 ;1,3=95,5=0.000000
L 3.93500098 -1.3060003 3.931 -1.31533406 4 P 0 ;1,3=95,5=0.000000
L 3.931 -1.31533406 3.92499951 -1.32333484 4 P 0 ;1,3=95,5=0.000000
L 3.92499951 -1.32333484 3.91799911 -1.32866703 4 P 0 ;1,3=95,5=0.000000
L 3.91799911 -1.32866703 3.90999902 -1.33 4 P 0 ;1,3=95,5=0.000000
L 3.96999961 -1.33 3.96999961 -1.25 4 P 0 ;1,3=95,5=0.000000
L 3.96999961 -1.25 3.994 -1.25 4 P 0 ;1,3=95,5=0.000000
L 3.994 -1.25 4.0020001 -1.25400167 4 P 0 ;1,3=95,5=0.000000
L 4.0020001 -1.25400167 4.00800069 -1.26333297 4 P 0 ;1,3=95,5=0.000000
L 4.00800069 -1.26333297 4.0100003 -1.2739998 4 P 0 ;1,3=95,5=0.000000
L 4.0100003 -1.2739998 4.00800069 -1.28466663 4 P 0 ;1,3=95,5=0.000000
L 4.00800069 -1.28466663 4.0029999 -1.29266732 4 P 0 ;1,3=95,5=0.000000
L 4.0029999 -1.29266732 3.994 -1.296669 4 P 0 ;1,3=95,5=0.000000
L 3.994 -1.296669 3.96999961 -1.296669 4 P 0 ;1,3=95,5=0.000000
L 1.78346624 4.29166683 1.78726663 4.29666585 4 P 0 ;1,3=96,5=0.000000
L 1.78726663 4.29666585 1.7917002 4.29916683 4 P 0 ;1,3=96,5=0.000000
L 1.7917002 4.29916683 1.79676693 4.3 4 P 0 ;1,3=96,5=0.000000
L 1.79676693 4.3 1.8031001 4.29833366 4 P 0 ;1,3=96,5=0.000000
L 1.8031001 4.29833366 1.80753366 4.29416634 4 P 0 ;1,3=96,5=0.000000
L 1.80753366 4.29416634 1.8088 4.28916742 4 P 0 ;1,3=96,5=0.000000
L 1.8088 4.28916742 1.80816683 4.28416545 4 P 0 ;1,3=96,5=0.000000
L 1.80816683 4.28416545 1.80563287 4.27999961 4 P 0 ;1,3=96,5=0.000000
L 1.80563287 4.27999961 1.79296654 4.27166654 4 P 0 ;1,3=96,5=0.000000
L 1.79296654 4.27166654 1.78726663 4.26583297 4 P 0 ;1,3=96,5=0.000000
L 1.78726663 4.26583297 1.78346624 4.25749833 4 P 0 ;1,3=96,5=0.000000
L 1.78346624 4.25749833 1.7821999 4.25 4 P 0 ;1,3=96,5=0.000000
L 1.7821999 4.25 1.8088 4.25 4 P 0 ;1,3=96,5=0.000000
L 1.84649941 4.3 1.84143258 4.29833366 4 P 0 ;1,3=96,5=0.000000
L 1.84143258 4.29833366 1.83763346 4.29416634 4 P 0 ;1,3=96,5=0.000000
L 1.83763346 4.29416634 1.83509951 4.28916742 4 P 0 ;1,3=96,5=0.000000
L 1.83509951 4.28916742 1.8331999 4.28249911 4 P 0 ;1,3=96,5=0.000000
L 1.8331999 4.28249911 1.83256673 4.27499921 4 P 0 ;1,3=96,5=0.000000
L 1.83256673 4.27499921 1.8331999 4.26749931 4 P 0 ;1,3=96,5=0.000000
L 1.8331999 4.26749931 1.83509951 4.26083248 4 P 0 ;1,3=96,5=0.000000
L 1.83509951 4.26083248 1.83763346 4.25583209 4 P 0 ;1,3=96,5=0.000000
L 1.83763346 4.25583209 1.84143258 4.25166624 4 P 0 ;1,3=96,5=0.000000
L 1.84143258 4.25166624 1.84649941 4.25 4 P 0 ;1,3=96,5=0.000000
L 1.84649941 4.25 1.85156614 4.25166624 4 P 0 ;1,3=96,5=0.000000
L 1.85156614 4.25166624 1.85536644 4.25583209 4 P 0 ;1,3=96,5=0.000000
L 1.85536644 4.25583209 1.85790039 4.26083248 4 P 0 ;1,3=96,5=0.000000
L 1.85790039 4.26083248 1.8598 4.26749931 4 P 0 ;1,3=96,5=0.000000
L 1.8598 4.26749931 1.86043317 4.27499921 4 P 0 ;1,3=96,5=0.000000
L 1.86043317 4.27499921 1.8598 4.28249911 4 P 0 ;1,3=96,5=0.000000
L 1.8598 4.28249911 1.85790039 4.28916742 4 P 0 ;1,3=96,5=0.000000
L 1.85790039 4.28916742 1.85536644 4.29416634 4 P 0 ;1,3=96,5=0.000000
L 1.85536644 4.29416634 1.85156614 4.29833366 4 P 0 ;1,3=96,5=0.000000
L 1.85156614 4.29833366 1.84649941 4.3 4 P 0 ;1,3=96,5=0.000000
L 1.88546624 4.29166683 1.88926663 4.29666585 4 P 0 ;1,3=96,5=0.000000
L 1.88926663 4.29666585 1.8937002 4.29916683 4 P 0 ;1,3=96,5=0.000000
L 1.8937002 4.29916683 1.89876693 4.3 4 P 0 ;1,3=96,5=0.000000
L 1.89876693 4.3 1.9051001 4.29833366 4 P 0 ;1,3=96,5=0.000000
L 1.9051001 4.29833366 1.90953366 4.29416634 4 P 0 ;1,3=96,5=0.000000
L 1.90953366 4.29416634 1.9108 4.28916742 4 P 0 ;1,3=96,5=0.000000
L 1.9108 4.28916742 1.91016683 4.28416545 4 P 0 ;1,3=96,5=0.000000
L 1.91016683 4.28416545 1.90763287 4.27999961 4 P 0 ;1,3=96,5=0.000000
L 1.90763287 4.27999961 1.89496654 4.27166654 4 P 0 ;1,3=96,5=0.000000
L 1.89496654 4.27166654 1.88926663 4.26583297 4 P 0 ;1,3=96,5=0.000000
L 1.88926663 4.26583297 1.88546624 4.25749833 4 P 0 ;1,3=96,5=0.000000
L 1.88546624 4.25749833 1.8841999 4.25 4 P 0 ;1,3=96,5=0.000000
L 1.8841999 4.25 1.9108 4.25 4 P 0 ;1,3=96,5=0.000000
L 1.93646624 4.29166683 1.94026663 4.29666585 4 P 0 ;1,3=96,5=0.000000
L 1.94026663 4.29666585 1.9447002 4.29916683 4 P 0 ;1,3=96,5=0.000000
L 1.9447002 4.29916683 1.94976693 4.3 4 P 0 ;1,3=96,5=0.000000
L 1.94976693 4.3 1.9561001 4.29833366 4 P 0 ;1,3=96,5=0.000000
L 1.9561001 4.29833366 1.96053366 4.29416634 4 P 0 ;1,3=96,5=0.000000
L 1.96053366 4.29416634 1.9618 4.28916742 4 P 0 ;1,3=96,5=0.000000
L 1.9618 4.28916742 1.96116683 4.28416545 4 P 0 ;1,3=96,5=0.000000
L 1.96116683 4.28416545 1.95863287 4.27999961 4 P 0 ;1,3=96,5=0.000000
L 1.95863287 4.27999961 1.94596654 4.27166654 4 P 0 ;1,3=96,5=0.000000
L 1.94596654 4.27166654 1.94026663 4.26583297 4 P 0 ;1,3=96,5=0.000000
L 1.94026663 4.26583297 1.93646624 4.25749833 4 P 0 ;1,3=96,5=0.000000
L 1.93646624 4.25749833 1.9351999 4.25 4 P 0 ;1,3=96,5=0.000000
L 1.9351999 4.25 1.9618 4.25 4 P 0 ;1,3=96,5=0.000000
L 1.99126663 4.26666614 2.00773327 4.26666614 4 P 0 ;1,3=96,5=0.000000
L 2.05049941 4.3 2.04543258 4.29833366 4 P 0 ;1,3=96,5=0.000000
L 2.04543258 4.29833366 2.04163346 4.29416634 4 P 0 ;1,3=96,5=0.000000
L 2.04163346 4.29416634 2.03909951 4.28916742 4 P 0 ;1,3=96,5=0.000000
L 2.03909951 4.28916742 2.0371999 4.28249911 4 P 0 ;1,3=96,5=0.000000
L 2.0371999 4.28249911 2.03656673 4.27499921 4 P 0 ;1,3=96,5=0.000000
L 2.03656673 4.27499921 2.0371999 4.26749931 4 P 0 ;1,3=96,5=0.000000
L 2.0371999 4.26749931 2.03909951 4.26083248 4 P 0 ;1,3=96,5=0.000000
L 2.03909951 4.26083248 2.04163346 4.25583209 4 P 0 ;1,3=96,5=0.000000
L 2.04163346 4.25583209 2.04543258 4.25166624 4 P 0 ;1,3=96,5=0.000000
L 2.04543258 4.25166624 2.05049941 4.25 4 P 0 ;1,3=96,5=0.000000
L 2.05049941 4.25 2.05556614 4.25166624 4 P 0 ;1,3=96,5=0.000000
L 2.05556614 4.25166624 2.05936644 4.25583209 4 P 0 ;1,3=96,5=0.000000
L 2.05936644 4.25583209 2.06190039 4.26083248 4 P 0 ;1,3=96,5=0.000000
L 2.06190039 4.26083248 2.0638 4.26749931 4 P 0 ;1,3=96,5=0.000000
L 2.0638 4.26749931 2.06443317 4.27499921 4 P 0 ;1,3=96,5=0.000000
L 2.06443317 4.27499921 2.0638 4.28249911 4 P 0 ;1,3=96,5=0.000000
L 2.0638 4.28249911 2.06190039 4.28916742 4 P 0 ;1,3=96,5=0.000000
L 2.06190039 4.28916742 2.05936644 4.29416634 4 P 0 ;1,3=96,5=0.000000
L 2.05936644 4.29416634 2.05556614 4.29833366 4 P 0 ;1,3=96,5=0.000000
L 2.05556614 4.29833366 2.05049941 4.3 4 P 0 ;1,3=96,5=0.000000
L 2.08946624 4.29166683 2.09326663 4.29666585 4 P 0 ;1,3=96,5=0.000000
L 2.09326663 4.29666585 2.0977002 4.29916683 4 P 0 ;1,3=96,5=0.000000
L 2.0977002 4.29916683 2.10276693 4.3 4 P 0 ;1,3=96,5=0.000000
L 2.10276693 4.3 2.1091001 4.29833366 4 P 0 ;1,3=96,5=0.000000
L 2.1091001 4.29833366 2.11353366 4.29416634 4 P 0 ;1,3=96,5=0.000000
L 2.11353366 4.29416634 2.1148 4.28916742 4 P 0 ;1,3=96,5=0.000000
L 2.1148 4.28916742 2.11416683 4.28416545 4 P 0 ;1,3=96,5=0.000000
L 2.11416683 4.28416545 2.11163287 4.27999961 4 P 0 ;1,3=96,5=0.000000
L 2.11163287 4.27999961 2.09896654 4.27166654 4 P 0 ;1,3=96,5=0.000000
L 2.09896654 4.27166654 2.09326663 4.26583297 4 P 0 ;1,3=96,5=0.000000
L 2.09326663 4.26583297 2.08946624 4.25749833 4 P 0 ;1,3=96,5=0.000000
L 2.08946624 4.25749833 2.0881999 4.25 4 P 0 ;1,3=96,5=0.000000
L 2.0881999 4.25 2.1148 4.25 4 P 0 ;1,3=96,5=0.000000
L 2.14426663 4.26666614 2.16073327 4.26666614 4 P 0 ;1,3=96,5=0.000000
L 2.19146624 4.29166683 2.19526663 4.29666585 4 P 0 ;1,3=96,5=0.000000
L 2.19526663 4.29666585 2.1997002 4.29916683 4 P 0 ;1,3=96,5=0.000000
L 2.1997002 4.29916683 2.20476693 4.3 4 P 0 ;1,3=96,5=0.000000
L 2.20476693 4.3 2.2111001 4.29833366 4 P 0 ;1,3=96,5=0.000000
L 2.2111001 4.29833366 2.21553366 4.29416634 4 P 0 ;1,3=96,5=0.000000
L 2.21553366 4.29416634 2.2168 4.28916742 4 P 0 ;1,3=96,5=0.000000
L 2.2168 4.28916742 2.21616683 4.28416545 4 P 0 ;1,3=96,5=0.000000
L 2.21616683 4.28416545 2.21363287 4.27999961 4 P 0 ;1,3=96,5=0.000000
L 2.21363287 4.27999961 2.20096654 4.27166654 4 P 0 ;1,3=96,5=0.000000
L 2.20096654 4.27166654 2.19526663 4.26583297 4 P 0 ;1,3=96,5=0.000000
L 2.19526663 4.26583297 2.19146624 4.25749833 4 P 0 ;1,3=96,5=0.000000
L 2.19146624 4.25749833 2.1901999 4.25 4 P 0 ;1,3=96,5=0.000000
L 2.1901999 4.25 2.2168 4.25 4 P 0 ;1,3=96,5=0.000000
L 2.24056673 4.25749833 2.24436585 4.25333258 4 P 0 ;1,3=96,5=0.000000
L 2.24436585 4.25333258 2.24879941 4.25083307 4 P 0 ;1,3=96,5=0.000000
L 2.24879941 4.25083307 2.25449941 4.25 4 P 0 ;1,3=96,5=0.000000
L 2.25449941 4.25 2.26020049 4.25166624 4 P 0 ;1,3=96,5=0.000000
L 2.26020049 4.25166624 2.26463287 4.25499892 4 P 0 ;1,3=96,5=0.000000
L 2.26463287 4.25499892 2.2678 4.26083248 4 P 0 ;1,3=96,5=0.000000
L 2.2678 4.26083248 2.26843317 4.26749931 4 P 0 ;1,3=96,5=0.000000
L 2.26843317 4.26749931 2.26716683 4.27416604 4 P 0 ;1,3=96,5=0.000000
L 2.26716683 4.27416604 2.2639997 4.27833337 4 P 0 ;1,3=96,5=0.000000
L 2.2639997 4.27833337 2.25956614 4.28166594 4 P 0 ;1,3=96,5=0.000000
L 2.25956614 4.28166594 2.25513376 4.28249911 4 P 0 ;1,3=96,5=0.000000
L 2.25513376 4.28249911 2.2507002 4.28166594 4 P 0 ;1,3=96,5=0.000000
L 2.2507002 4.28166594 2.2450002 4.27833337 4 P 0 ;1,3=96,5=0.000000
L 2.2450002 4.27833337 2.2468998 4.3 4 P 0 ;1,3=96,5=0.000000
L 2.2468998 4.3 2.2639997 4.3 4 P 0 ;1,3=96,5=0.000000
L 0.83383307 4.24833002 0.83383307 4.29833002 4 P 0 ;1,3=97,5=0.000000
L 0.83383307 4.29833002 0.84966654 4.29833002 4 P 0 ;1,3=97,5=0.000000
L 0.84966654 4.29833002 0.85473327 4.29582894 4 P 0 ;1,3=97,5=0.000000
L 0.85473327 4.29582894 0.85790039 4.29249636 4 P 0 ;1,3=97,5=0.000000
L 0.85790039 4.29249636 0.85916683 4.28582963 4 P 0 ;1,3=97,5=0.000000
L 0.85916683 4.28582963 0.85790039 4.2791628 4 P 0 ;1,3=97,5=0.000000
L 0.85790039 4.2791628 0.8541001 4.27499705 4 P 0 ;1,3=97,5=0.000000
L 0.8541001 4.27499705 0.84966654 4.27249606 4 P 0 ;1,3=97,5=0.000000
L 0.84966654 4.27249606 0.83383307 4.27249606 4 P 0 ;1,3=97,5=0.000000
L 0.84966654 4.27249606 0.85916683 4.24833002 4 P 0 ;1,3=97,5=0.000000
L 0.9051001 4.24833002 0.9051001 4.29833002 4 P 0 ;1,3=97,5=0.000000
L 0.9051001 4.29833002 0.88166594 4.26249665 4 P 0 ;1,3=97,5=0.000000
L 0.88166594 4.26249665 0.91333396 4.26249665 4 P 0 ;1,3=97,5=0.000000
L 0.94849941 4.29833002 0.94343258 4.29666368 4 P 0 ;1,3=97,5=0.000000
L 0.94343258 4.29666368 0.93963346 4.29249636 4 P 0 ;1,3=97,5=0.000000
L 0.93963346 4.29249636 0.93709951 4.28749744 4 P 0 ;1,3=97,5=0.000000
L 0.93709951 4.28749744 0.9351999 4.28082913 4 P 0 ;1,3=97,5=0.000000
L 0.9351999 4.28082913 0.93456673 4.27332923 4 P 0 ;1,3=97,5=0.000000
L 0.93456673 4.27332923 0.9351999 4.26582933 4 P 0 ;1,3=97,5=0.000000
L 0.9351999 4.26582933 0.93709951 4.2591625 4 P 0 ;1,3=97,5=0.000000
L 0.93709951 4.2591625 0.93963346 4.25416211 4 P 0 ;1,3=97,5=0.000000
L 0.93963346 4.25416211 0.94343258 4.24999626 4 P 0 ;1,3=97,5=0.000000
L 0.94343258 4.24999626 0.94849941 4.24833002 4 P 0 ;1,3=97,5=0.000000
L 0.94849941 4.24833002 0.95356614 4.24999626 4 P 0 ;1,3=97,5=0.000000
L 0.95356614 4.24999626 0.95736644 4.25416211 4 P 0 ;1,3=97,5=0.000000
L 0.95736644 4.25416211 0.95990039 4.2591625 4 P 0 ;1,3=97,5=0.000000
L 0.95990039 4.2591625 0.9618 4.26582933 4 P 0 ;1,3=97,5=0.000000
L 0.9618 4.26582933 0.96243317 4.27332923 4 P 0 ;1,3=97,5=0.000000
L 0.96243317 4.27332923 0.9618 4.28082913 4 P 0 ;1,3=97,5=0.000000
L 0.9618 4.28082913 0.95990039 4.28749744 4 P 0 ;1,3=97,5=0.000000
L 0.95990039 4.28749744 0.95736644 4.29249636 4 P 0 ;1,3=97,5=0.000000
L 0.95736644 4.29249636 0.95356614 4.29666368 4 P 0 ;1,3=97,5=0.000000
L 0.95356614 4.29666368 0.94849941 4.29833002 4 P 0 ;1,3=97,5=0.000000
L 0.99949941 4.29833002 0.99443258 4.29666368 4 P 0 ;1,3=97,5=0.000000
L 0.99443258 4.29666368 0.99063346 4.29249636 4 P 0 ;1,3=97,5=0.000000
L 0.99063346 4.29249636 0.98809951 4.28749744 4 P 0 ;1,3=97,5=0.000000
L 0.98809951 4.28749744 0.9861999 4.28082913 4 P 0 ;1,3=97,5=0.000000
L 0.9861999 4.28082913 0.98556673 4.27332923 4 P 0 ;1,3=97,5=0.000000
L 0.98556673 4.27332923 0.9861999 4.26582933 4 P 0 ;1,3=97,5=0.000000
L 0.9861999 4.26582933 0.98809951 4.2591625 4 P 0 ;1,3=97,5=0.000000
L 0.98809951 4.2591625 0.99063346 4.25416211 4 P 0 ;1,3=97,5=0.000000
L 0.99063346 4.25416211 0.99443258 4.24999626 4 P 0 ;1,3=97,5=0.000000
L 0.99443258 4.24999626 0.99949941 4.24833002 4 P 0 ;1,3=97,5=0.000000
L 0.99949941 4.24833002 1.00456614 4.24999626 4 P 0 ;1,3=97,5=0.000000
L 1.00456614 4.24999626 1.00836644 4.25416211 4 P 0 ;1,3=97,5=0.000000
L 1.00836644 4.25416211 1.01090039 4.2591625 4 P 0 ;1,3=97,5=0.000000
L 1.01090039 4.2591625 1.0128 4.26582933 4 P 0 ;1,3=97,5=0.000000
L 1.0128 4.26582933 1.01343317 4.27332923 4 P 0 ;1,3=97,5=0.000000
L 1.01343317 4.27332923 1.0128 4.28082913 4 P 0 ;1,3=97,5=0.000000
L 1.0128 4.28082913 1.01090039 4.28749744 4 P 0 ;1,3=97,5=0.000000
L 1.01090039 4.28749744 1.00836644 4.29249636 4 P 0 ;1,3=97,5=0.000000
L 1.00836644 4.29249636 1.00456614 4.29666368 4 P 0 ;1,3=97,5=0.000000
L 1.00456614 4.29666368 0.99949941 4.29833002 4 P 0 ;1,3=97,5=0.000000
L 1.03846624 4.26916191 1.0428998 4.27499705 4 P 0 ;1,3=97,5=0.000000
L 1.0428998 4.27499705 1.0467002 4.27832963 4 P 0 ;1,3=97,5=0.000000
L 1.0467002 4.27832963 1.05176693 4.27999596 4 P 0 ;1,3=97,5=0.000000
L 1.05176693 4.27999596 1.05620049 4.27832963 4 P 0 ;1,3=97,5=0.000000
L 1.05620049 4.27832963 1.05936644 4.27499705 4 P 0 ;1,3=97,5=0.000000
L 1.05936644 4.27499705 1.06190039 4.26999656 4 P 0 ;1,3=97,5=0.000000
L 1.06190039 4.26999656 1.06253366 4.26416299 4 P 0 ;1,3=97,5=0.000000
L 1.06253366 4.26416299 1.06190039 4.2591625 4 P 0 ;1,3=97,5=0.000000
L 1.06190039 4.2591625 1.05936644 4.25416211 4 P 0 ;1,3=97,5=0.000000
L 1.05936644 4.25416211 1.05556614 4.24999626 4 P 0 ;1,3=97,5=0.000000
L 1.05556614 4.24999626 1.05113376 4.24833002 4 P 0 ;1,3=97,5=0.000000
L 1.05113376 4.24833002 1.04606703 4.24999626 4 P 0 ;1,3=97,5=0.000000
L 1.04606703 4.24999626 1.04163346 4.25499518 4 P 0 ;1,3=97,5=0.000000
L 1.04163346 4.25499518 1.03909951 4.26249665 4 P 0 ;1,3=97,5=0.000000
L 1.03909951 4.26249665 1.03846624 4.27082972 4 P 0 ;1,3=97,5=0.000000
L 1.03846624 4.27082972 1.03973268 4.2816623 4 P 0 ;1,3=97,5=0.000000
L 1.03973268 4.2816623 1.04163346 4.28749744 4 P 0 ;1,3=97,5=0.000000
L 1.04163346 4.28749744 1.04479941 4.29332953 4 P 0 ;1,3=97,5=0.000000
L 1.04479941 4.29332953 1.04923297 4.29749685 4 P 0 ;1,3=97,5=0.000000
L 1.04923297 4.29749685 1.05366654 4.29833002 4 P 0 ;1,3=97,5=0.000000
L 1.05366654 4.29833002 1.0581001 4.29666368 4 P 0 ;1,3=97,5=0.000000
L 1.0581001 4.29666368 1.06126722 4.29249636 4 P 0 ;1,3=97,5=0.000000
L 1.09326663 4.26499616 1.10973327 4.26499616 4 P 0 ;1,3=97,5=0.000000
L 1.15756614 4.27499705 1.1601001 4.27749656 4 P 0 ;1,3=97,5=0.000000
L 1.1601001 4.27749656 1.1619997 4.2816623 4 P 0 ;1,3=97,5=0.000000
L 1.1619997 4.2816623 1.16326722 4.28749744 4 P 0 ;1,3=97,5=0.000000
L 1.16326722 4.28749744 1.1619997 4.29249636 4 P 0 ;1,3=97,5=0.000000
L 1.1619997 4.29249636 1.15946683 4.29582894 4 P 0 ;1,3=97,5=0.000000
L 1.15946683 4.29582894 1.15503337 4.29833002 4 P 0 ;1,3=97,5=0.000000
L 1.15503337 4.29833002 1.13793346 4.29833002 4 P 0 ;1,3=97,5=0.000000
L 1.13793346 4.29833002 1.13793346 4.24833002 4 P 0 ;1,3=97,5=0.000000
L 1.13793346 4.24833002 1.15883366 4.24833002 4 P 0 ;1,3=97,5=0.000000
L 1.15883366 4.24833002 1.16326722 4.2516626 4 P 0 ;1,3=97,5=0.000000
L 1.16326722 4.2516626 1.1658 4.25666309 4 P 0 ;1,3=97,5=0.000000
L 1.1658 4.25666309 1.16706644 4.26249665 4 P 0 ;1,3=97,5=0.000000
L 1.16706644 4.26249665 1.1658 4.26832874 4 P 0 ;1,3=97,5=0.000000
L 1.1658 4.26832874 1.1619997 4.27332923 4 P 0 ;1,3=97,5=0.000000
L 1.1619997 4.27332923 1.15756614 4.27499705 4 P 0 ;1,3=97,5=0.000000
L 1.15756614 4.27499705 1.13793346 4.27499705 4 P 0 ;1,3=97,5=0.000000
L 1.20349941 4.29833002 1.19843258 4.29666368 4 P 0 ;1,3=97,5=0.000000
L 1.19843258 4.29666368 1.19463346 4.29249636 4 P 0 ;1,3=97,5=0.000000
L 1.19463346 4.29249636 1.19209951 4.28749744 4 P 0 ;1,3=97,5=0.000000
L 1.19209951 4.28749744 1.1901999 4.28082913 4 P 0 ;1,3=97,5=0.000000
L 1.1901999 4.28082913 1.18956673 4.27332923 4 P 0 ;1,3=97,5=0.000000
L 1.18956673 4.27332923 1.1901999 4.26582933 4 P 0 ;1,3=97,5=0.000000
L 1.1901999 4.26582933 1.19209951 4.2591625 4 P 0 ;1,3=97,5=0.000000
L 1.19209951 4.2591625 1.19463346 4.25416211 4 P 0 ;1,3=97,5=0.000000
L 1.19463346 4.25416211 1.19843258 4.24999626 4 P 0 ;1,3=97,5=0.000000
L 1.19843258 4.24999626 1.20349941 4.24833002 4 P 0 ;1,3=97,5=0.000000
L 1.20349941 4.24833002 1.20856614 4.24999626 4 P 0 ;1,3=97,5=0.000000
L 1.20856614 4.24999626 1.21236644 4.25416211 4 P 0 ;1,3=97,5=0.000000
L 1.21236644 4.25416211 1.21490039 4.2591625 4 P 0 ;1,3=97,5=0.000000
L 1.21490039 4.2591625 1.2168 4.26582933 4 P 0 ;1,3=97,5=0.000000
L 1.2168 4.26582933 1.21743317 4.27332923 4 P 0 ;1,3=97,5=0.000000
L 1.21743317 4.27332923 1.2168 4.28082913 4 P 0 ;1,3=97,5=0.000000
L 1.2168 4.28082913 1.21490039 4.28749744 4 P 0 ;1,3=97,5=0.000000
L 1.21490039 4.28749744 1.21236644 4.29249636 4 P 0 ;1,3=97,5=0.000000
L 1.21236644 4.29249636 1.20856614 4.29666368 4 P 0 ;1,3=97,5=0.000000
L 1.20856614 4.29666368 1.20349941 4.29833002 4 P 0 ;1,3=97,5=0.000000
L 1.25449941 4.29833002 1.24943258 4.29666368 4 P 0 ;1,3=97,5=0.000000
L 1.24943258 4.29666368 1.24563346 4.29249636 4 P 0 ;1,3=97,5=0.000000
L 1.24563346 4.29249636 1.24309951 4.28749744 4 P 0 ;1,3=97,5=0.000000
L 1.24309951 4.28749744 1.2411999 4.28082913 4 P 0 ;1,3=97,5=0.000000
L 1.2411999 4.28082913 1.24056673 4.27332923 4 P 0 ;1,3=97,5=0.000000
L 1.24056673 4.27332923 1.2411999 4.26582933 4 P 0 ;1,3=97,5=0.000000
L 1.2411999 4.26582933 1.24309951 4.2591625 4 P 0 ;1,3=97,5=0.000000
L 1.24309951 4.2591625 1.24563346 4.25416211 4 P 0 ;1,3=97,5=0.000000
L 1.24563346 4.25416211 1.24943258 4.24999626 4 P 0 ;1,3=97,5=0.000000
L 1.24943258 4.24999626 1.25449941 4.24833002 4 P 0 ;1,3=97,5=0.000000
L 1.25449941 4.24833002 1.25956614 4.24999626 4 P 0 ;1,3=97,5=0.000000
L 1.25956614 4.24999626 1.26336644 4.25416211 4 P 0 ;1,3=97,5=0.000000
L 1.26336644 4.25416211 1.26590039 4.2591625 4 P 0 ;1,3=97,5=0.000000
L 1.26590039 4.2591625 1.2678 4.26582933 4 P 0 ;1,3=97,5=0.000000
L 1.2678 4.26582933 1.26843317 4.27332923 4 P 0 ;1,3=97,5=0.000000
L 1.26843317 4.27332923 1.2678 4.28082913 4 P 0 ;1,3=97,5=0.000000
L 1.2678 4.28082913 1.26590039 4.28749744 4 P 0 ;1,3=97,5=0.000000
L 1.26590039 4.28749744 1.26336644 4.29249636 4 P 0 ;1,3=97,5=0.000000
L 1.26336644 4.29249636 1.25956614 4.29666368 4 P 0 ;1,3=97,5=0.000000
L 1.25956614 4.29666368 1.25449941 4.29833002 4 P 0 ;1,3=97,5=0.000000
L 1.30549941 4.29833002 1.30043258 4.29666368 4 P 0 ;1,3=97,5=0.000000
L 1.30043258 4.29666368 1.29663346 4.29249636 4 P 0 ;1,3=97,5=0.000000
L 1.29663346 4.29249636 1.29409951 4.28749744 4 P 0 ;1,3=97,5=0.000000
L 1.29409951 4.28749744 1.2921999 4.28082913 4 P 0 ;1,3=97,5=0.000000
L 1.2921999 4.28082913 1.29156673 4.27332923 4 P 0 ;1,3=97,5=0.000000
L 1.29156673 4.27332923 1.2921999 4.26582933 4 P 0 ;1,3=97,5=0.000000
L 1.2921999 4.26582933 1.29409951 4.2591625 4 P 0 ;1,3=97,5=0.000000
L 1.29409951 4.2591625 1.29663346 4.25416211 4 P 0 ;1,3=97,5=0.000000
L 1.29663346 4.25416211 1.30043258 4.24999626 4 P 0 ;1,3=97,5=0.000000
L 1.30043258 4.24999626 1.30549941 4.24833002 4 P 0 ;1,3=97,5=0.000000
L 1.30549941 4.24833002 1.31056614 4.24999626 4 P 0 ;1,3=97,5=0.000000
L 1.31056614 4.24999626 1.31436644 4.25416211 4 P 0 ;1,3=97,5=0.000000
L 1.31436644 4.25416211 1.31690039 4.2591625 4 P 0 ;1,3=97,5=0.000000
L 1.31690039 4.2591625 1.3188 4.26582933 4 P 0 ;1,3=97,5=0.000000
L 1.3188 4.26582933 1.31943317 4.27332923 4 P 0 ;1,3=97,5=0.000000
L 1.31943317 4.27332923 1.3188 4.28082913 4 P 0 ;1,3=97,5=0.000000
L 1.3188 4.28082913 1.31690039 4.28749744 4 P 0 ;1,3=97,5=0.000000
L 1.31690039 4.28749744 1.31436644 4.29249636 4 P 0 ;1,3=97,5=0.000000
L 1.31436644 4.29249636 1.31056614 4.29666368 4 P 0 ;1,3=97,5=0.000000
L 1.31056614 4.29666368 1.30549941 4.29833002 4 P 0 ;1,3=97,5=0.000000
L 1.35649941 4.24833002 1.35649941 4.29833002 4 P 0 ;1,3=97,5=0.000000
L 1.35649941 4.29833002 1.3488998 4.28833061 4 P 0 ;1,3=97,5=0.000000
L 1.3488998 4.24833002 1.36409892 4.24833002 4 P 0 ;1,3=97,5=0.000000
L 1.39926663 4.26499616 1.41573327 4.26499616 4 P 0 ;1,3=97,5=0.000000
L 1.45849941 4.29833002 1.45343258 4.29666368 4 P 0 ;1,3=97,5=0.000000
L 1.45343258 4.29666368 1.44963346 4.29249636 4 P 0 ;1,3=97,5=0.000000
L 1.44963346 4.29249636 1.44709951 4.28749744 4 P 0 ;1,3=97,5=0.000000
L 1.44709951 4.28749744 1.4451999 4.28082913 4 P 0 ;1,3=97,5=0.000000
L 1.4451999 4.28082913 1.44456673 4.27332923 4 P 0 ;1,3=97,5=0.000000
L 1.44456673 4.27332923 1.4451999 4.26582933 4 P 0 ;1,3=97,5=0.000000
L 1.4451999 4.26582933 1.44709951 4.2591625 4 P 0 ;1,3=97,5=0.000000
L 1.44709951 4.2591625 1.44963346 4.25416211 4 P 0 ;1,3=97,5=0.000000
L 1.44963346 4.25416211 1.45343258 4.24999626 4 P 0 ;1,3=97,5=0.000000
L 1.45343258 4.24999626 1.45849941 4.24833002 4 P 0 ;1,3=97,5=0.000000
L 1.45849941 4.24833002 1.46356614 4.24999626 4 P 0 ;1,3=97,5=0.000000
L 1.46356614 4.24999626 1.46736644 4.25416211 4 P 0 ;1,3=97,5=0.000000
L 1.46736644 4.25416211 1.46990039 4.2591625 4 P 0 ;1,3=97,5=0.000000
L 1.46990039 4.2591625 1.4718 4.26582933 4 P 0 ;1,3=97,5=0.000000
L 1.4718 4.26582933 1.47243317 4.27332923 4 P 0 ;1,3=97,5=0.000000
L 1.47243317 4.27332923 1.4718 4.28082913 4 P 0 ;1,3=97,5=0.000000
L 1.4718 4.28082913 1.46990039 4.28749744 4 P 0 ;1,3=97,5=0.000000
L 1.46990039 4.28749744 1.46736644 4.29249636 4 P 0 ;1,3=97,5=0.000000
L 1.46736644 4.29249636 1.46356614 4.29666368 4 P 0 ;1,3=97,5=0.000000
L 1.46356614 4.29666368 1.45849941 4.29833002 4 P 0 ;1,3=97,5=0.000000
L 1.49746624 4.28999685 1.50126663 4.29499587 4 P 0 ;1,3=97,5=0.000000
L 1.50126663 4.29499587 1.5057002 4.29749685 4 P 0 ;1,3=97,5=0.000000
L 1.5057002 4.29749685 1.51076693 4.29833002 4 P 0 ;1,3=97,5=0.000000
L 1.51076693 4.29833002 1.5171001 4.29666368 4 P 0 ;1,3=97,5=0.000000
L 1.5171001 4.29666368 1.52153366 4.29249636 4 P 0 ;1,3=97,5=0.000000
L 1.52153366 4.29249636 1.5228 4.28749744 4 P 0 ;1,3=97,5=0.000000
L 1.5228 4.28749744 1.52216683 4.28249547 4 P 0 ;1,3=97,5=0.000000
L 1.52216683 4.28249547 1.51963287 4.27832963 4 P 0 ;1,3=97,5=0.000000
L 1.51963287 4.27832963 1.50696654 4.26999656 4 P 0 ;1,3=97,5=0.000000
L 1.50696654 4.26999656 1.50126663 4.26416299 4 P 0 ;1,3=97,5=0.000000
L 1.50126663 4.26416299 1.49746624 4.25582835 4 P 0 ;1,3=97,5=0.000000
L 1.49746624 4.25582835 1.4961999 4.24833002 4 P 0 ;1,3=97,5=0.000000
L 1.4961999 4.24833002 1.5228 4.24833002 4 P 0 ;1,3=97,5=0.000000
L 1.5415 4.23166388 1.5795 4.23166388 4 P 0 ;1,3=97,5=0.000000
L 1.59883307 4.24833002 1.59883307 4.29833002 4 P 0 ;1,3=97,5=0.000000
L 1.59883307 4.29833002 1.61466654 4.29833002 4 P 0 ;1,3=97,5=0.000000
L 1.61466654 4.29833002 1.61973327 4.29582894 4 P 0 ;1,3=97,5=0.000000
L 1.61973327 4.29582894 1.62290039 4.29249636 4 P 0 ;1,3=97,5=0.000000
L 1.62290039 4.29249636 1.62416683 4.28582963 4 P 0 ;1,3=97,5=0.000000
L 1.62416683 4.28582963 1.62290039 4.2791628 4 P 0 ;1,3=97,5=0.000000
L 1.62290039 4.2791628 1.6191001 4.27499705 4 P 0 ;1,3=97,5=0.000000
L 1.6191001 4.27499705 1.61466654 4.27249606 4 P 0 ;1,3=97,5=0.000000
L 1.61466654 4.27249606 1.59883307 4.27249606 4 P 0 ;1,3=97,5=0.000000
L 1.61466654 4.27249606 1.62416683 4.24833002 4 P 0 ;1,3=97,5=0.000000
L 1.66249941 4.29833002 1.65743258 4.29666368 4 P 0 ;1,3=97,5=0.000000
L 1.65743258 4.29666368 1.65363346 4.29249636 4 P 0 ;1,3=97,5=0.000000
L 1.65363346 4.29249636 1.65109951 4.28749744 4 P 0 ;1,3=97,5=0.000000
L 1.65109951 4.28749744 1.6491999 4.28082913 4 P 0 ;1,3=97,5=0.000000
L 1.6491999 4.28082913 1.64856673 4.27332923 4 P 0 ;1,3=97,5=0.000000
L 1.64856673 4.27332923 1.6491999 4.26582933 4 P 0 ;1,3=97,5=0.000000
L 1.6491999 4.26582933 1.65109951 4.2591625 4 P 0 ;1,3=97,5=0.000000
L 1.65109951 4.2591625 1.65363346 4.25416211 4 P 0 ;1,3=97,5=0.000000
L 1.65363346 4.25416211 1.65743258 4.24999626 4 P 0 ;1,3=97,5=0.000000
L 1.65743258 4.24999626 1.66249941 4.24833002 4 P 0 ;1,3=97,5=0.000000
L 1.66249941 4.24833002 1.66756614 4.24999626 4 P 0 ;1,3=97,5=0.000000
L 1.66756614 4.24999626 1.67136644 4.25416211 4 P 0 ;1,3=97,5=0.000000
L 1.67136644 4.25416211 1.67390039 4.2591625 4 P 0 ;1,3=97,5=0.000000
L 1.67390039 4.2591625 1.6758 4.26582933 4 P 0 ;1,3=97,5=0.000000
L 1.6758 4.26582933 1.67643317 4.27332923 4 P 0 ;1,3=97,5=0.000000
L 1.67643317 4.27332923 1.6758 4.28082913 4 P 0 ;1,3=97,5=0.000000
L 1.6758 4.28082913 1.67390039 4.28749744 4 P 0 ;1,3=97,5=0.000000
L 1.67390039 4.28749744 1.67136644 4.29249636 4 P 0 ;1,3=97,5=0.000000
L 1.67136644 4.29249636 1.66756614 4.29666368 4 P 0 ;1,3=97,5=0.000000
L 1.66756614 4.29666368 1.66249941 4.29833002 4 P 0 ;1,3=97,5=0.000000
L 1.71349941 4.24833002 1.71349941 4.29833002 4 P 0 ;1,3=97,5=0.000000
L 1.71349941 4.29833002 1.7058998 4.28833061 4 P 0 ;1,3=97,5=0.000000
L 1.7058998 4.24833002 1.72109892 4.24833002 4 P 0 ;1,3=97,5=0.000000
P 5.78 1.165 13 P 0 8 0;0,2=98,4=0
P 0.95 0.845 13 P 0 8 0;0,2=98,4=0
P 1.105 4.145 13 P 0 8 0;0,2=98,4=0
P 2.68566998 1.12143002 16 P 0 8 0;2=99,4=0
P 2.68566998 2.55943002 16 P 0 8 0;2=99,4=0
P 1.46066998 2.68043002 16 P 0 8 0;2=99,4=0
P 1.43566998 1.06043002 16 P 0 8 0;2=99,4=0
P 6.40038996 0.65353996 20 P 0 8 0;2=100,4=0
P 0.29528002 3.73031004 20 P 0 8 0;2=100,4=0
P 0.29528002 0.36811004 20 P 0 8 0;2=100,4=0
P 6.40038996 4.17835 20 P 0 8 0;2=100,4=0
P 6.34055 3.34448996 19 P 0 8 0;2=101,4=0
P 6.34055 3.67518996 19 P 0 8 0;2=101,4=0
L 3.16 -0.655 3.16 -1.58 6 P 0 ;1
L 1.36 -0.655 1.36 -1.58 6 P 0 ;1
L 1.36 -1.58 5.06 -1.58 6 P 0 ;1
L 5.06 -1.58 5.06 -0.655 6 P 0 ;1
L 5.06 -0.655 1.36 -0.655 6 P 0 ;1
A 1.559 -1.33655 1.559 -1.33655 1.55268002 -1.33655 4 P 0 N;1
A 1.54775 -1.205 1.54775 -1.205 1.53883002 -1.205 4 P 0 N;1
A 1.54763996 -0.99775 1.54763996 -0.99775 1.53871998 -0.99775 4 P 0 N;1
A 1.54063996 -1.10118002 1.54063996 -1.10118002 1.52603996 -1.10118002 4 P 0 N;1
A 1.49695 -1.10118002 1.49695 -1.10118002 1.48656998 -1.10118002 4 P 0 N;1
A 1.45963996 -1.10118002 1.45963996 -1.10118002 1.4533 -1.10118002 4 P 0 N;1
A 1.52135 -0.98681004 1.52135 -0.98681004 1.51503002 -0.98681004 4 P 0 N;1
A 1.79433002 -1.43586998 1.79433002 -1.43586998 1.78798996 -1.43586998 4 P 0 N;1
A 1.79841004 -1.40261004 1.79841004 -1.40261004 1.78798996 -1.40261004 4 P 0 N;1
A 1.80255 -1.36311004 1.80255 -1.36311004 1.78798996 -1.36311004 4 P 0 N;1
A 1.80668996 -1.31528002 1.80668996 -1.31528002 1.78798996 -1.31528002 4 P 0 N;1
A 1.68013002 -1.37456004 1.68013002 -1.37456004 1.67378996 -1.37456004 4 P 0 N;1
A 1.69321998 -1.35033002 1.69321998 -1.35033002 1.6843 -1.35033002 4 P 0 N;1
A 1.7108 -1.31738996 1.7108 -1.31738996 1.69798002 -1.31738996 4 P 0 N;1
A 1.89666998 -1.31511004 1.89666998 -1.31511004 1.88383996 -1.31511004 4 P 0 N;1
A 1.88198996 -1.16876004 1.88198996 -1.16876004 1.85558996 -1.16876004 4 P 0 N;1
A 1.87928002 -1.27801998 1.87928002 -1.27801998 1.86343996 -1.27801998 4 P 0 N;1
A 1.86176998 -1.23075 1.86176998 -1.23075 1.84206004 -1.23075 4 P 0 N;1
A 1.80978996 -1.25916998 1.80978996 -1.25916998 1.78798996 -1.25916998 4 P 0 N;1
A 1.74681004 -1.16876004 1.74681004 -1.16876004 1.72041004 -1.16876004 4 P 0 N;1
A 1.67813002 -1.15513002 1.67813002 -1.15513002 1.65841998 -1.15513002 4 P 0 N;1
A 1.73018002 -1.27816004 1.73018002 -1.27816004 1.71433996 -1.27816004 4 P 0 N;1
A 1.75373002 -1.23081004 1.75373002 -1.23081004 1.73405 -1.23081004 4 P 0 N;1
A 1.65531004 -1.25255 1.65531004 -1.25255 1.63661998 -1.25255 4 P 0 N;1
A 1.69808996 -1.21291998 1.69808996 -1.21291998 1.67628996 -1.21291998 4 P 0 N;1
A 1.81438996 -1.1968 1.81438996 -1.1968 1.78798996 -1.1968 4 P 0 N;1
A 1.6269 -1.1749 1.6269 -1.1749 1.61106004 -1.1749 4 P 0 N;1
A 1.58461004 -1.19126004 1.58461004 -1.19126004 1.57178002 -1.19126004 4 P 0 N;1
A 1.5853 -1.31428002 1.5853 -1.31428002 1.57488996 -1.31428002 4 P 0 N;1
A 1.61735 -1.28638996 1.61735 -1.28638996 1.60276998 -1.28638996 4 P 0 N;1
A 1.88198996 -1.03361004 1.88198996 -1.03361004 1.85558996 -1.03361004 4 P 0 N;1
A 1.71881004 -1.10118002 1.71881004 -1.10118002 1.69238996 -1.10118002 4 P 0 N;1
A 1.65183002 -1.10118002 1.65183002 -1.10118002 1.63003002 -1.10118002 4 P 0 N;1
A 1.67801998 -1.04738996 1.67801998 -1.04738996 1.65831004 -1.04738996 4 P 0 N;1
A 1.74681004 -1.03361004 1.74681004 -1.03361004 1.72041004 -1.03361004 4 P 0 N;1
A 1.69811998 -0.98951004 1.69811998 -0.98951004 1.67631998 -0.98951004 4 P 0 N;1
A 1.81438996 -1.00556004 1.81438996 -1.00556004 1.78798996 -1.00556004 4 P 0 N;1
A 1.59258002 -1.10118002 1.59258002 -1.10118002 1.5739 -1.10118002 4 P 0 N;1
A 1.58451004 -1.01148996 1.58451004 -1.01148996 1.57168002 -1.01148996 4 P 0 N;1
A 1.62681004 -1.02773996 1.62681004 -1.02773996 1.61096998 -1.02773996 4 P 0 N;1
A 1.92148002 -1.21285 1.92148002 -1.21285 1.89968002 -1.21285 4 P 0 N;1
A 1.92148002 -0.98951004 1.92148002 -0.98951004 1.89968002 -0.98951004 4 P 0 N;1
A 1.80978996 -0.9432 1.80978996 -0.9432 1.78798996 -0.9432 4 P 0 N;1
A 1.80668996 -0.88708002 1.80668996 -0.88708002 1.78798996 -0.88708002 4 P 0 N;1
A 1.80255 -0.83923996 1.80255 -0.83923996 1.78798996 -0.83923996 4 P 0 N;1
A 1.8919 -0.88538002 1.8919 -0.88538002 1.87906998 -0.88538002 4 P 0 N;1
A 1.87838996 -0.92456998 1.87838996 -0.92456998 1.86255 -0.92456998 4 P 0 N;1
A 1.65531004 -0.94981004 1.65531004 -0.94981004 1.63661998 -0.94981004 4 P 0 N;1
A 1.73123002 -0.92378002 1.73123002 -0.92378002 1.71538996 -0.92378002 4 P 0 N;1
A 1.71216998 -0.88443996 1.71216998 -0.88443996 1.69935 -0.88443996 4 P 0 N;1
A 1.86225 -0.97178002 1.86225 -0.97178002 1.84253996 -0.97178002 4 P 0 N;1
A 1.75451998 -0.97123996 1.75451998 -0.97123996 1.73483996 -0.97123996 4 P 0 N;1
A 1.61741998 -0.91601004 1.61741998 -0.91601004 1.60283996 -0.91601004 4 P 0 N;1
A 1.5853 -0.88808996 1.5853 -0.88808996 1.57488996 -0.88808996 4 P 0 N;1
A 1.79841004 -0.79975 1.79841004 -0.79975 1.78798996 -0.79975 4 P 0 N;1
A 1.79433002 -0.76648002 1.79433002 -0.76648002 1.78798996 -0.76648002 4 P 0 N;1
A 1.92135 -1.36781004 1.92135 -1.36781004 1.91503996 -1.36781004 4 P 0 N;1
A 1.91096004 -1.34658002 1.91096004 -1.34658002 1.90203996 -1.34658002 4 P 0 N;1
A 2.19078996 -1.1806 2.26591004 -1.16473002 2.21741014 -1.12088169 4 P 0 N;1
A 2.15903002 -1.1402 2.19078996 -1.18061004 2.22093406 -1.12423278 4 P 0 N;1
A 2.05721004 -1.16178996 2.08853002 -1.16658996 2.08281614 -1.09929134 4 P 0 N;1
A 2.00546998 -1.13951998 2.03345 -1.17196004 2.07793927 -1.10530069 4 P 0 N;1
A 2.03346004 -1.17195 2.0847 -1.18461004 2.07891181 -1.09801299 4 P 0 N;1
A 2.0847 -1.18461998 2.14261004 -1.15663002 2.07348435 -1.08751378 4 P 0 N;1
A 2.08853996 -1.16658002 2.13313002 -1.14451998 2.06368967 -1.06025512 4 P 0 N;1
A 1.95808002 -1.25255 1.95808002 -1.25255 1.93938996 -1.25255 4 P 0 N;1
A 1.98775 -1.28635 1.98775 -1.28635 1.97316998 -1.28635 4 P 0 N;1
A 2.27411998 -1.11835 2.15906004 -1.11835 2.21658996 -1.11611998 4 P 0 N;1
L 2.25188002 -1.11418002 2.1807 -1.11418002 4 P 0 ;1
L 2.1807 -1.11418002 2.1807 -1.11398996 4 P 8191 ;1
A 2.25188996 -1.11398996 2.18071004 -1.11398996 2.2163 -1.1124 4 P 0 N;1
A 2.08028996 -1.03428996 2.02048996 -1.08258996 2.0798126 -1.09486801 4 P 0 N;1
A 2.13151998 -1.05146004 2.0803 -1.0343 2.0802999 -1.11932195 4 P 0 N;1
A 2.1315 -1.05146998 2.14175 -1.03951004 2.1356003 -1.04461171 4 P 0 N;1
A 2.14175 -1.03951004 2.08283002 -1.01613002 2.07772461 -1.11492805 4 P 0 N;1
A 2.08283996 -1.01611998 2.00698002 -1.05835 2.08064724 -1.10143169 4 P 0 N;1
L 2.27413002 -1.12868996 2.18073996 -1.12868996 4 P 0 ;1
A 2.18075 -1.12868996 2.19083002 -1.15751998 2.22417795 -1.12968307 4 P 0 N;1
A 2.19083002 -1.15753002 2.25311004 -1.15211004 2.21927195 -1.12381791 4 P 0 N;1
L 2.15903996 -1.1402 2.15903996 -1.11835 4 P 8191 ;1
A 2.02048996 -1.0826 2.05721998 -1.16181004 2.09087933 -1.0980811 4 P 0 N;1
A 2.00698996 -1.05836004 2.00546998 -1.13953002 2.09672953 -1.10063967 4 P 0 N;1
A 2.14258996 -1.15661004 2.13313996 -1.14453002 2.13544892 -1.15246004 4 P 0 N;1
A 1.95808002 -0.94981004 1.95808002 -0.94981004 1.93938996 -0.94981004 4 P 0 N;1
A 1.90183996 -0.8525 1.90183996 -0.8525 1.89291004 -0.8525 4 P 0 N;1
A 1.91108002 -0.82726998 1.91108002 -0.82726998 1.90473996 -0.82726998 4 P 0 N;1
L 2.32081004 -1.02041004 2.32081004 -1.17625 4 P 0 ;1
A 2.49568002 -1.15528996 2.47898002 -1.16443002 2.4882003 -1.1614502 4 P 0 N;1
A 2.47896998 -1.16443996 2.50283002 -1.18086004 2.51649242 -1.13546152 4 P 0 N;1
A 2.50281998 -1.18086998 2.54318002 -1.1834 2.52887392 -1.08843022 4 P 0 N;1
A 2.52306998 -1.16761004 2.52848996 -1.16771998 2.52673258 -1.12070098 4 P 0 N;1
A 2.49566004 -1.15528996 2.52306998 -1.1676 2.5255122 -1.12549094 4 P 0 N;1
A 2.37851998 -1.15753002 2.4408 -1.15211004 2.40696191 -1.12381791 4 P 0 N;1
A 2.45358002 -1.16471998 2.44078996 -1.1521 2.44541191 -1.16020689 4 P 0 N;1
A 2.37848002 -1.1806 2.4536 -1.16473002 2.4051001 -1.12088169 4 P 0 N;1
A 2.34673002 -1.1402 2.37848996 -1.18061004 2.40863406 -1.12423278 4 P 0 N;1
A 2.2659 -1.16471998 2.25311004 -1.1521 2.25773199 -1.16020689 4 P 0 N;1
A 2.3006 -1.17626004 2.3208 -1.17626004 2.3107 -1.17386841 4 P 0 N;1
L 2.30058996 -1.17625 2.30058996 -1.02033996 4 P 0 ;1
A 2.50836998 -1.10106004 2.54306004 -1.11513002 2.56106673 -1.02093386 4 P 0 N;1
A 2.51081004 -1.07948002 2.50836998 -1.10103996 2.51886093 -1.09130915 4 P 0 N;1
A 2.53611004 -1.07688996 2.5108 -1.07948996 2.52742205 -1.11680827 4 P 0 N;1
A 2.56883996 -1.07368002 2.50178002 -1.06358996 2.5273123 -1.12178858 4 P 0 N;1
A 2.50178996 -1.06358996 2.48536998 -1.08248996 2.52926211 -1.10403986 4 P 0 N;1
L 2.48536998 -1.0825 2.48536998 -1.09748002 4 P 8191 ;1
A 2.48536998 -1.09748002 2.49956004 -1.12031004 2.51189104 -1.09682067 4 P 0 N;1
A 2.46181004 -1.11835 2.34675 -1.11835 2.40428002 -1.11611998 4 P 0 N;1
L 2.43956998 -1.11418002 2.36841004 -1.11418002 4 P 0 ;1
L 2.36841004 -1.11418002 2.36841004 -1.11398996 4 P 8191 ;1
A 2.43958002 -1.11398996 2.3684 -1.11398996 2.40398996 -1.1124 4 P 0 N;1
L 2.43956998 -1.11398996 2.43956998 -1.11418002 4 P 8191 ;1
A 2.49955 -1.1203 2.52723002 -1.12985 2.58163209 -0.92727982 4 P 0 N;1
A 2.55001998 -1.14328002 2.52723002 -1.12986004 2.51462185 -1.17733228 4 P 0 N;1
L 2.46181004 -1.12868996 2.36843996 -1.12868996 4 P 0 ;1
A 2.36843996 -1.12868996 2.37851998 -1.15751998 2.41186801 -1.12968307 4 P 0 N;1
L 2.34675 -1.1402 2.34675 -1.11835 4 P 8191 ;1
L 2.46181004 -1.11835 2.46181004 -1.12868996 4 P 8191 ;1
L 2.25188002 -1.11398996 2.25188002 -1.11418002 4 P 8191 ;1
A 2.3208 -1.02041004 2.3006 -1.02033996 2.31069163 -1.02276978 4 P 0 N;1
L 2.27413002 -1.11835 2.27413002 -1.12868996 4 P 8191 ;1
A 2.52848996 -1.16771004 2.54891998 -1.15895 2.52774557 -1.13777087 4 P 0 N;1
A 2.55608002 -1.08618002 2.53611998 -1.07688996 2.5249185 -1.12704419 4 P 0 N;1
L 2.71926004 -1.06796998 2.71926004 -1.17483996 4 P 0 ;1
A 2.78888996 -1.16296998 2.81508002 -1.16676998 2.8083499 -1.12100167 4 P 0 N;1
A 2.8151 -1.16675 2.83966004 -1.15211998 2.80521398 -1.12222392 4 P 0 N;1
A 2.85201004 -1.16508002 2.83966004 -1.15211004 2.84505768 -1.15933514 4 P 0 N;1
L 2.85201004 -1.16508002 2.84523996 -1.17161004 4 P 8191 ;1
A 2.81425 -1.1835 2.84525 -1.17161004 2.81425 -1.13714291 4 P 0 N;1
L 2.81425 -1.1835 2.79571004 -1.1835 4 P 8191 ;1
A 2.75886998 -1.16443002 2.79571998 -1.18351998 2.80278976 -1.12476142 4 P 0 N;1
A 2.74528996 -1.13568002 2.75888002 -1.16443002 2.80246565 -1.12624016 4 P 0 N;1
A 2.54316998 -1.1834 2.56906004 -1.1647 2.5305814 -1.13869892 4 P 0 N;1
A 2.56906004 -1.1647 2.57053996 -1.13728002 2.53763041 -1.14925374 4 P 0 N;1
A 2.65463996 -1.18351998 2.66863996 -1.17373996 2.65440246 -1.16826969 4 P 0 N;1
L 2.65463002 -1.1835 2.64165 -1.1835 4 P 8191 ;1
A 2.60955 -1.16043002 2.64163996 -1.18351004 2.63911063 -1.15317815 4 P 0 N;1
A 2.62978002 -1.15461998 2.66001998 -1.16328996 2.6502374 -1.14033868 4 P 0 N;1
A 2.66863996 -1.17375 2.66001998 -1.16328996 2.66100344 -1.17126132 4 P 0 N;1
A 2.6962 -1.17483996 2.71926004 -1.17483996 2.70773002 -1.17286427 4 P 0 N;1
L 2.69618996 -1.17483996 2.69618996 -1.06796998 4 P 0 ;1
A 2.83833002 -1.09275 2.82661998 -1.08201998 2.74555758 -1.18224094 4 P 0 N;1
A 2.82661998 -1.08198996 2.80036998 -1.07538996 2.80348839 -1.11848878 4 P 0 N;1
A 2.80036004 -1.07541998 2.76848996 -1.09933002 2.80700217 -1.1174685 4 P 0 N;1
A 2.76848996 -1.09931998 2.76446004 -1.12066004 2.82315728 -1.120694 4 P 0 N;1
A 2.74998002 -1.09273996 2.74528996 -1.11838996 2.8498563 -1.12425591 4 P 0 N;1
A 2.7954 -1.05776998 2.74998996 -1.09273996 2.80799961 -1.12109961 4 P 0 N;1
L 2.79541004 -1.05776998 2.80918996 -1.05776998 4 P 8191 ;1
A 2.85401998 -1.08106004 2.80918996 -1.05776998 2.80626024 -1.1181998 4 P 0 N;1
A 2.83833002 -1.09273996 2.85403002 -1.08106004 2.84418386 -1.08421683 4 P 0 N;1
L 2.76445 -1.12066004 2.76445 -1.12943002 4 P 8191 ;1
A 2.76446004 -1.12943002 2.76836998 -1.14305 2.80607844 -1.12485364 4 P 0 N;1
A 2.76836998 -1.14305 2.78891004 -1.16296998 2.80906152 -1.12164144 4 P 0 N;1
L 2.74528996 -1.13566004 2.74528996 -1.11838996 4 P 8191 ;1
A 2.55606004 -1.0862 2.56885 -1.07366998 2.56205354 -1.0795252 4 P 0 N;1
L 2.60953996 -1.07953996 2.59981998 -1.07953996 4 P 8191 ;1
A 2.5993 -1.05931998 2.59981004 -1.07955 2.6022813 -1.06936624 4 P 0 N;1
L 2.5993 -1.05931998 2.60953996 -1.05931998 4 P 8191 ;1
L 2.60953996 -1.05931998 2.60953996 -1.03491998 4 P 8191 ;1
A 2.62971998 -1.03418002 2.60953996 -1.03491004 2.61966791 -1.03559478 4 P 0 N;1
L 2.62971004 -1.03418996 2.62978002 -1.05931998 4 P 8191 ;1
L 2.62978002 -1.05931998 2.66008002 -1.05931998 4 P 8191 ;1
A 2.66003996 -1.07955 2.66008002 -1.05931998 2.65827421 -1.0694314 4 P 0 N;1
L 2.66003002 -1.07953996 2.62978002 -1.07953996 4 P 8191 ;1
A 2.71926004 -1.06796998 2.6962 -1.06796998 2.70773002 -1.0720561 4 P 0 N;1
A 2.71968996 -1.02341998 2.71968996 -1.02341998 2.70775 -1.02341998 4 P 0 N;1
A 2.57053996 -1.13728996 2.54306998 -1.11513002 2.53584449 -1.15219301 4 P 0 N;1
A 2.54891998 -1.15895 2.55001004 -1.14328002 2.54127923 -1.15054557 4 P 0 N;1
L 2.60953996 -1.16041004 2.60953996 -1.07953996 4 P 0 ;1
L 2.62978002 -1.07953996 2.62978002 -1.15463002 4 P 0 ;1
L 2.98495 -1.09393996 2.98495 -1.17625 4 P 0 ;1
A 2.96473996 -1.17626998 2.98493996 -1.17626998 2.97483996 -1.17442303 4 P 0 N;1
L 2.96473002 -1.17625 2.96473002 -1.17226004 4 P 8191 ;1
A 2.94165 -1.1835 2.96471004 -1.17226004 2.93076516 -1.1318935 4 P 0 N;1
L 2.94165 -1.1835 2.90701004 -1.1835 4 P 8191 ;1
A 2.90671004 -1.10841998 2.90703002 -1.18351004 2.9153065 -1.14592904 4 P 0 N;1
A 2.91853002 -1.12288996 2.91853002 -1.16618996 2.92048209 -1.14453996 4 P 0 N;1
L 2.91853002 -1.1662 2.94456004 -1.1662 4 P 8191 ;1
A 2.94456998 -1.16618996 2.94456998 -1.12288996 2.94406004 -1.14453996 4 P 0 N;1
A 2.96473002 -1.09686004 2.94741998 -1.07955 2.94874833 -1.09553169 4 P 0 N;1
L 2.9474 -1.07953996 2.90986998 -1.07953996 4 P 8191 ;1
A 2.90986998 -1.07953996 2.89821004 -1.0852 2.92433445 -1.12417766 4 P 0 N;1
A 2.89111998 -1.07086004 2.8982 -1.0852 2.8969689 -1.07688996 4 P 0 N;1
A 2.91561998 -1.05931998 2.89111998 -1.07085 2.92146033 -1.103525 4 P 0 N;1
L 2.91563002 -1.05931998 2.95031004 -1.05931998 4 P 8191 ;1
A 2.98496004 -1.09393996 2.95031004 -1.05933002 2.9453438 -1.09895197 4 P 0 N;1
A 2.92878996 -1.10535 2.9067 -1.10841998 2.93158484 -1.20646998 4 P 0 N;1
A 2.96471998 -1.10841004 2.92878002 -1.10536004 2.93215738 -1.27883829 4 P 0 N;1
L 2.96473002 -1.10841004 2.96473002 -1.09686004 4 P 8191 ;1
L 2.94456004 -1.12288002 2.91853002 -1.12288002 4 P 8191 ;1
L 3.04731004 -1.06001004 3.04191998 -1.07631998 4 P 8191 ;1
L 3.04191998 -1.07631998 3.03648002 -1.06001004 4 P 8191 ;1
L 3.03648002 -1.06001004 3.03243002 -1.06001004 4 P 8191 ;1
L 3.03243002 -1.06001004 3.02698002 -1.08543996 4 P 8191 ;1
L 3.02698002 -1.08543996 3.03226004 -1.08543996 4 P 8191 ;1
L 3.03226004 -1.08543996 3.03501004 -1.06886998 4 P 8191 ;1
L 3.03501004 -1.06886998 3.04086004 -1.08543996 4 P 8191 ;1
L 3.04086004 -1.08543996 3.04308996 -1.08543996 4 P 8191 ;1
L 3.04308996 -1.08543996 3.04888996 -1.06871004 4 P 8191 ;1
L 3.04888996 -1.06871004 3.05171004 -1.08543996 4 P 8191 ;1
L 3.05171004 -1.08543996 3.05713002 -1.08543996 4 P 8191 ;1
L 3.05713002 -1.08543996 3.05163996 -1.06001004 4 P 8191 ;1
L 3.05163996 -1.06001004 3.04731004 -1.06001004 4 P 8191 ;1
L 3.01066998 -1.06508002 3.00223002 -1.06508002 4 P 8191 ;1
L 3.00223002 -1.06508002 3.00223002 -1.06001004 4 P 8191 ;1
L 3.00223002 -1.06001004 3.02461004 -1.06001004 4 P 8191 ;1
L 3.02461004 -1.06001004 3.02461004 -1.06508002 4 P 8191 ;1
L 3.02461004 -1.06508002 3.01615 -1.06508002 4 P 8191 ;1
L 3.01615 -1.06508002 3.01615 -1.08533996 4 P 8191 ;1
L 3.01615 -1.08533996 3.01066998 -1.08533996 4 P 8191 ;1
L 3.01066998 -1.08533996 3.01066998 -1.06508002 4 P 8191 ;1
L 3.36933297 -0.955 3.36933297 -0.88 2 P 0 ;1,3=102,5=0.000000
L 3.36933297 -0.88 3.39173337 -0.88 2 P 0 ;1,3=102,5=0.000000
L 3.39173337 -0.88 3.3992001 -0.88375157 2 P 0 ;1,3=102,5=0.000000
L 3.3992001 -0.88375157 3.40480059 -0.8924997 2 P 0 ;1,3=102,5=0.000000
L 3.40480059 -0.8924997 3.40666693 -0.9024998 2 P 0 ;1,3=102,5=0.000000
L 3.40666693 -0.9024998 3.40480059 -0.9125 2 P 0 ;1,3=102,5=0.000000
L 3.40480059 -0.9125 3.40013327 -0.92000069 2 P 0 ;1,3=102,5=0.000000
L 3.40013327 -0.92000069 3.39173337 -0.92375217 2 P 0 ;1,3=102,5=0.000000
L 3.39173337 -0.92375217 3.36933297 -0.92375217 2 P 0 ;1,3=102,5=0.000000
L 3.44619931 -0.95749941 3.47980059 -0.88 2 P 0 ;1,3=102,5=0.000000
L 3.51653356 -0.955 3.51653356 -0.88 2 P 0 ;1,3=102,5=0.000000
L 3.51653356 -0.88 3.55946634 -0.955 2 P 0 ;1,3=102,5=0.000000
L 3.55946634 -0.955 3.55946634 -0.88 2 P 0 ;1,3=102,5=0.000000
L 3.68799911 -0.95749941 3.68613287 -0.9562497 2 P 0 ;1,3=102,5=0.000000
L 3.68613287 -0.9562497 3.68613287 -0.9537503 2 P 0 ;1,3=102,5=0.000000
L 3.68613287 -0.9537503 3.68799911 -0.95250059 2 P 0 ;1,3=102,5=0.000000
L 3.68799911 -0.95250059 3.68986703 -0.9537503 2 P 0 ;1,3=102,5=0.000000
L 3.68986703 -0.9537503 3.68986703 -0.9562497 2 P 0 ;1,3=102,5=0.000000
L 3.68986703 -0.9562497 3.68799911 -0.95749941 2 P 0 ;1,3=102,5=0.000000
L 3.68799911 -0.92375217 3.68613287 -0.9225001 2 P 0 ;1,3=102,5=0.000000
L 3.68613287 -0.9225001 3.68613287 -0.92000069 2 P 0 ;1,3=102,5=0.000000
L 3.68613287 -0.92000069 3.68799911 -0.91875089 2 P 0 ;1,3=102,5=0.000000
L 3.68799911 -0.91875089 3.68986703 -0.92000069 2 P 0 ;1,3=102,5=0.000000
L 3.68986703 -0.92000069 3.68986703 -0.9225001 2 P 0 ;1,3=102,5=0.000000
L 3.68986703 -0.9225001 3.68799911 -0.92375217 2 P 0 ;1,3=102,5=0.000000
L 3.81933297 -0.955 3.81933297 -0.88 2 P 0 ;1,3=102,5=0.000000
L 3.81933297 -0.88 3.84266644 -0.88 2 P 0 ;1,3=102,5=0.000000
L 3.84266644 -0.88 3.85013327 -0.88375157 2 P 0 ;1,3=102,5=0.000000
L 3.85013327 -0.88375157 3.85480059 -0.88875049 2 P 0 ;1,3=102,5=0.000000
L 3.85480059 -0.88875049 3.85666693 -0.89875059 2 P 0 ;1,3=102,5=0.000000
L 3.85666693 -0.89875059 3.85480059 -0.90875079 2 P 0 ;1,3=102,5=0.000000
L 3.85480059 -0.90875079 3.8492001 -0.91499941 2 P 0 ;1,3=102,5=0.000000
L 3.8492001 -0.91499941 3.84266644 -0.91875089 2 P 0 ;1,3=102,5=0.000000
L 3.84266644 -0.91875089 3.81933297 -0.91875089 2 P 0 ;1,3=102,5=0.000000
L 3.84266644 -0.91875089 3.85666693 -0.955 2 P 0 ;1,3=102,5=0.000000
L 3.9242001 -0.955 3.9242001 -0.88 2 P 0 ;1,3=102,5=0.000000
L 3.9242001 -0.88 3.88966565 -0.93375 2 P 0 ;1,3=102,5=0.000000
L 3.88966565 -0.93375 3.93633425 -0.93375 2 P 0 ;1,3=102,5=0.000000
L 3.98799911 -0.88 3.98053228 -0.88249951 2 P 0 ;1,3=102,5=0.000000
L 3.98053228 -0.88249951 3.97493346 -0.88875049 2 P 0 ;1,3=102,5=0.000000
L 3.97493346 -0.88875049 3.97119931 -0.89624882 2 P 0 ;1,3=102,5=0.000000
L 3.97119931 -0.89624882 3.9683999 -0.90625128 2 P 0 ;1,3=102,5=0.000000
L 3.9683999 -0.90625128 3.96746673 -0.91750118 2 P 0 ;1,3=102,5=0.000000
L 3.96746673 -0.91750118 3.9683999 -0.92875108 2 P 0 ;1,3=102,5=0.000000
L 3.9683999 -0.92875108 3.97119931 -0.93875128 2 P 0 ;1,3=102,5=0.000000
L 3.97119931 -0.93875128 3.97493346 -0.94625187 2 P 0 ;1,3=102,5=0.000000
L 3.97493346 -0.94625187 3.98053228 -0.95250059 2 P 0 ;1,3=102,5=0.000000
L 3.98053228 -0.95250059 3.98799911 -0.955 2 P 0 ;1,3=102,5=0.000000
L 3.98799911 -0.955 3.99546585 -0.95250059 2 P 0 ;1,3=102,5=0.000000
L 3.99546585 -0.95250059 4.00106644 -0.94625187 2 P 0 ;1,3=102,5=0.000000
L 4.00106644 -0.94625187 4.00480059 -0.93875128 2 P 0 ;1,3=102,5=0.000000
L 4.00480059 -0.93875128 4.0076 -0.92875108 2 P 0 ;1,3=102,5=0.000000
L 4.0076 -0.92875108 4.00853317 -0.91750118 2 P 0 ;1,3=102,5=0.000000
L 4.00853317 -0.91750118 4.0076 -0.90625128 2 P 0 ;1,3=102,5=0.000000
L 4.0076 -0.90625128 4.00480059 -0.89624882 2 P 0 ;1,3=102,5=0.000000
L 4.00480059 -0.89624882 4.00106644 -0.88875049 2 P 0 ;1,3=102,5=0.000000
L 4.00106644 -0.88875049 3.99546585 -0.88249951 2 P 0 ;1,3=102,5=0.000000
L 3.99546585 -0.88249951 3.98799911 -0.88 2 P 0 ;1,3=102,5=0.000000
L 4.06299911 -0.88 4.05553228 -0.88249951 2 P 0 ;1,3=102,5=0.000000
L 4.05553228 -0.88249951 4.04993346 -0.88875049 2 P 0 ;1,3=102,5=0.000000
L 4.04993346 -0.88875049 4.04619931 -0.89624882 2 P 0 ;1,3=102,5=0.000000
L 4.04619931 -0.89624882 4.0433999 -0.90625128 2 P 0 ;1,3=102,5=0.000000
L 4.0433999 -0.90625128 4.04246673 -0.91750118 2 P 0 ;1,3=102,5=0.000000
L 4.04246673 -0.91750118 4.0433999 -0.92875108 2 P 0 ;1,3=102,5=0.000000
L 4.0433999 -0.92875108 4.04619931 -0.93875128 2 P 0 ;1,3=102,5=0.000000
L 4.04619931 -0.93875128 4.04993346 -0.94625187 2 P 0 ;1,3=102,5=0.000000
L 4.04993346 -0.94625187 4.05553228 -0.95250059 2 P 0 ;1,3=102,5=0.000000
L 4.05553228 -0.95250059 4.06299911 -0.955 2 P 0 ;1,3=102,5=0.000000
L 4.06299911 -0.955 4.07046585 -0.95250059 2 P 0 ;1,3=102,5=0.000000
L 4.07046585 -0.95250059 4.07606644 -0.94625187 2 P 0 ;1,3=102,5=0.000000
L 4.07606644 -0.94625187 4.07980059 -0.93875128 2 P 0 ;1,3=102,5=0.000000
L 4.07980059 -0.93875128 4.0826 -0.92875108 2 P 0 ;1,3=102,5=0.000000
L 4.0826 -0.92875108 4.08353317 -0.91750118 2 P 0 ;1,3=102,5=0.000000
L 4.08353317 -0.91750118 4.0826 -0.90625128 2 P 0 ;1,3=102,5=0.000000
L 4.0826 -0.90625128 4.07980059 -0.89624882 2 P 0 ;1,3=102,5=0.000000
L 4.07980059 -0.89624882 4.07606644 -0.88875049 2 P 0 ;1,3=102,5=0.000000
L 4.07606644 -0.88875049 4.07046585 -0.88249951 2 P 0 ;1,3=102,5=0.000000
L 4.07046585 -0.88249951 4.06299911 -0.88 2 P 0 ;1,3=102,5=0.000000
L 4.12026614 -0.92375217 4.1267998 -0.91499941 2 P 0 ;1,3=102,5=0.000000
L 4.1267998 -0.91499941 4.1324003 -0.91000049 2 P 0 ;1,3=102,5=0.000000
L 4.1324003 -0.91000049 4.13986703 -0.90750108 2 P 0 ;1,3=102,5=0.000000
L 4.13986703 -0.90750108 4.14640069 -0.91000049 2 P 0 ;1,3=102,5=0.000000
L 4.14640069 -0.91000049 4.15106644 -0.91499941 2 P 0 ;1,3=102,5=0.000000
L 4.15106644 -0.91499941 4.15480059 -0.9225001 2 P 0 ;1,3=102,5=0.000000
L 4.15480059 -0.9225001 4.15573376 -0.93125059 2 P 0 ;1,3=102,5=0.000000
L 4.15573376 -0.93125059 4.15480059 -0.93875128 2 P 0 ;1,3=102,5=0.000000
L 4.15480059 -0.93875128 4.15106644 -0.94625187 2 P 0 ;1,3=102,5=0.000000
L 4.15106644 -0.94625187 4.14546585 -0.95250059 2 P 0 ;1,3=102,5=0.000000
L 4.14546585 -0.95250059 4.13893396 -0.955 2 P 0 ;1,3=102,5=0.000000
L 4.13893396 -0.955 4.13146713 -0.95250059 2 P 0 ;1,3=102,5=0.000000
L 4.13146713 -0.95250059 4.12493346 -0.94500217 2 P 0 ;1,3=102,5=0.000000
L 4.12493346 -0.94500217 4.12119931 -0.93375 2 P 0 ;1,3=102,5=0.000000
L 4.12119931 -0.93375 4.12026614 -0.92125039 2 P 0 ;1,3=102,5=0.000000
L 4.12026614 -0.92125039 4.12213238 -0.90500157 2 P 0 ;1,3=102,5=0.000000
L 4.12213238 -0.90500157 4.12493346 -0.89624882 2 P 0 ;1,3=102,5=0.000000
L 4.12493346 -0.89624882 4.12959921 -0.88750069 2 P 0 ;1,3=102,5=0.000000
L 4.12959921 -0.88750069 4.13613287 -0.8812498 2 P 0 ;1,3=102,5=0.000000
L 4.13613287 -0.8812498 4.14266644 -0.88 2 P 0 ;1,3=102,5=0.000000
L 4.14266644 -0.88 4.1492001 -0.88249951 2 P 0 ;1,3=102,5=0.000000
L 4.1492001 -0.88249951 4.15386752 -0.88875049 2 P 0 ;1,3=102,5=0.000000
L 4.20086663 -0.93000079 4.22513327 -0.93000079 2 P 0 ;1,3=102,5=0.000000
L 4.29546585 -0.91499941 4.2992001 -0.9112502 2 P 0 ;1,3=102,5=0.000000
L 4.2992001 -0.9112502 4.30199951 -0.90500157 2 P 0 ;1,3=102,5=0.000000
L 4.30199951 -0.90500157 4.30386752 -0.89624882 2 P 0 ;1,3=102,5=0.000000
L 4.30386752 -0.89624882 4.30199951 -0.88875049 2 P 0 ;1,3=102,5=0.000000
L 4.30199951 -0.88875049 4.29826703 -0.88375157 2 P 0 ;1,3=102,5=0.000000
L 4.29826703 -0.88375157 4.29173337 -0.88 2 P 0 ;1,3=102,5=0.000000
L 4.29173337 -0.88 4.26653356 -0.88 2 P 0 ;1,3=102,5=0.000000
L 4.26653356 -0.88 4.26653356 -0.955 2 P 0 ;1,3=102,5=0.000000
L 4.26653356 -0.955 4.29733386 -0.955 2 P 0 ;1,3=102,5=0.000000
L 4.29733386 -0.955 4.30386752 -0.95000108 2 P 0 ;1,3=102,5=0.000000
L 4.30386752 -0.95000108 4.3076 -0.94250039 2 P 0 ;1,3=102,5=0.000000
L 4.3076 -0.94250039 4.30946634 -0.93375 2 P 0 ;1,3=102,5=0.000000
L 4.30946634 -0.93375 4.3076 -0.92500187 2 P 0 ;1,3=102,5=0.000000
L 4.3076 -0.92500187 4.30199951 -0.91750118 2 P 0 ;1,3=102,5=0.000000
L 4.30199951 -0.91750118 4.29546585 -0.91499941 2 P 0 ;1,3=102,5=0.000000
L 4.29546585 -0.91499941 4.26653356 -0.91499941 2 P 0 ;1,3=102,5=0.000000
L 4.36299911 -0.88 4.35553228 -0.88249951 2 P 0 ;1,3=102,5=0.000000
L 4.35553228 -0.88249951 4.34993346 -0.88875049 2 P 0 ;1,3=102,5=0.000000
L 4.34993346 -0.88875049 4.34619931 -0.89624882 2 P 0 ;1,3=102,5=0.000000
L 4.34619931 -0.89624882 4.3433999 -0.90625128 2 P 0 ;1,3=102,5=0.000000
L 4.3433999 -0.90625128 4.34246673 -0.91750118 2 P 0 ;1,3=102,5=0.000000
L 4.34246673 -0.91750118 4.3433999 -0.92875108 2 P 0 ;1,3=102,5=0.000000
L 4.3433999 -0.92875108 4.34619931 -0.93875128 2 P 0 ;1,3=102,5=0.000000
L 4.34619931 -0.93875128 4.34993346 -0.94625187 2 P 0 ;1,3=102,5=0.000000
L 4.34993346 -0.94625187 4.35553228 -0.95250059 2 P 0 ;1,3=102,5=0.000000
L 4.35553228 -0.95250059 4.36299911 -0.955 2 P 0 ;1,3=102,5=0.000000
L 4.36299911 -0.955 4.37046585 -0.95250059 2 P 0 ;1,3=102,5=0.000000
L 4.37046585 -0.95250059 4.37606644 -0.94625187 2 P 0 ;1,3=102,5=0.000000
L 4.37606644 -0.94625187 4.37980059 -0.93875128 2 P 0 ;1,3=102,5=0.000000
L 4.37980059 -0.93875128 4.3826 -0.92875108 2 P 0 ;1,3=102,5=0.000000
L 4.3826 -0.92875108 4.38353317 -0.91750118 2 P 0 ;1,3=102,5=0.000000
L 4.38353317 -0.91750118 4.3826 -0.90625128 2 P 0 ;1,3=102,5=0.000000
L 4.3826 -0.90625128 4.37980059 -0.89624882 2 P 0 ;1,3=102,5=0.000000
L 4.37980059 -0.89624882 4.37606644 -0.88875049 2 P 0 ;1,3=102,5=0.000000
L 4.37606644 -0.88875049 4.37046585 -0.88249951 2 P 0 ;1,3=102,5=0.000000
L 4.37046585 -0.88249951 4.36299911 -0.88 2 P 0 ;1,3=102,5=0.000000
L 4.43799911 -0.88 4.43053228 -0.88249951 2 P 0 ;1,3=102,5=0.000000
L 4.43053228 -0.88249951 4.42493346 -0.88875049 2 P 0 ;1,3=102,5=0.000000
L 4.42493346 -0.88875049 4.42119931 -0.89624882 2 P 0 ;1,3=102,5=0.000000
L 4.42119931 -0.89624882 4.4183999 -0.90625128 2 P 0 ;1,3=102,5=0.000000
L 4.4183999 -0.90625128 4.41746673 -0.91750118 2 P 0 ;1,3=102,5=0.000000
L 4.41746673 -0.91750118 4.4183999 -0.92875108 2 P 0 ;1,3=102,5=0.000000
L 4.4183999 -0.92875108 4.42119931 -0.93875128 2 P 0 ;1,3=102,5=0.000000
L 4.42119931 -0.93875128 4.42493346 -0.94625187 2 P 0 ;1,3=102,5=0.000000
L 4.42493346 -0.94625187 4.43053228 -0.95250059 2 P 0 ;1,3=102,5=0.000000
L 4.43053228 -0.95250059 4.43799911 -0.955 2 P 0 ;1,3=102,5=0.000000
L 4.43799911 -0.955 4.44546585 -0.95250059 2 P 0 ;1,3=102,5=0.000000
L 4.44546585 -0.95250059 4.45106644 -0.94625187 2 P 0 ;1,3=102,5=0.000000
L 4.45106644 -0.94625187 4.45480059 -0.93875128 2 P 0 ;1,3=102,5=0.000000
L 4.45480059 -0.93875128 4.4576 -0.92875108 2 P 0 ;1,3=102,5=0.000000
L 4.4576 -0.92875108 4.45853317 -0.91750118 2 P 0 ;1,3=102,5=0.000000
L 4.45853317 -0.91750118 4.4576 -0.90625128 2 P 0 ;1,3=102,5=0.000000
L 4.4576 -0.90625128 4.45480059 -0.89624882 2 P 0 ;1,3=102,5=0.000000
L 4.45480059 -0.89624882 4.45106644 -0.88875049 2 P 0 ;1,3=102,5=0.000000
L 4.45106644 -0.88875049 4.44546585 -0.88249951 2 P 0 ;1,3=102,5=0.000000
L 4.44546585 -0.88249951 4.43799911 -0.88 2 P 0 ;1,3=102,5=0.000000
L 4.51299911 -0.88 4.50553228 -0.88249951 2 P 0 ;1,3=102,5=0.000000
L 4.50553228 -0.88249951 4.49993346 -0.88875049 2 P 0 ;1,3=102,5=0.000000
L 4.49993346 -0.88875049 4.49619931 -0.89624882 2 P 0 ;1,3=102,5=0.000000
L 4.49619931 -0.89624882 4.4933999 -0.90625128 2 P 0 ;1,3=102,5=0.000000
L 4.4933999 -0.90625128 4.49246673 -0.91750118 2 P 0 ;1,3=102,5=0.000000
L 4.49246673 -0.91750118 4.4933999 -0.92875108 2 P 0 ;1,3=102,5=0.000000
L 4.4933999 -0.92875108 4.49619931 -0.93875128 2 P 0 ;1,3=102,5=0.000000
L 4.49619931 -0.93875128 4.49993346 -0.94625187 2 P 0 ;1,3=102,5=0.000000
L 4.49993346 -0.94625187 4.50553228 -0.95250059 2 P 0 ;1,3=102,5=0.000000
L 4.50553228 -0.95250059 4.51299911 -0.955 2 P 0 ;1,3=102,5=0.000000
L 4.51299911 -0.955 4.52046585 -0.95250059 2 P 0 ;1,3=102,5=0.000000
L 4.52046585 -0.95250059 4.52606644 -0.94625187 2 P 0 ;1,3=102,5=0.000000
L 4.52606644 -0.94625187 4.52980059 -0.93875128 2 P 0 ;1,3=102,5=0.000000
L 4.52980059 -0.93875128 4.5326 -0.92875108 2 P 0 ;1,3=102,5=0.000000
L 4.5326 -0.92875108 4.53353317 -0.91750118 2 P 0 ;1,3=102,5=0.000000
L 4.53353317 -0.91750118 4.5326 -0.90625128 2 P 0 ;1,3=102,5=0.000000
L 4.5326 -0.90625128 4.52980059 -0.89624882 2 P 0 ;1,3=102,5=0.000000
L 4.52980059 -0.89624882 4.52606644 -0.88875049 2 P 0 ;1,3=102,5=0.000000
L 4.52606644 -0.88875049 4.52046585 -0.88249951 2 P 0 ;1,3=102,5=0.000000
L 4.52046585 -0.88249951 4.51299911 -0.88 2 P 0 ;1,3=102,5=0.000000
L 4.58799911 -0.955 4.58799911 -0.88 2 P 0 ;1,3=102,5=0.000000
L 4.58799911 -0.88 4.5767998 -0.89499911 2 P 0 ;1,3=102,5=0.000000
L 4.5767998 -0.955 4.59919843 -0.955 2 P 0 ;1,3=102,5=0.000000
L 4.65086663 -0.93000079 4.67513327 -0.93000079 2 P 0 ;1,3=102,5=0.000000
L 4.73799911 -0.88 4.73053228 -0.88249951 2 P 0 ;1,3=102,5=0.000000
L 4.73053228 -0.88249951 4.72493346 -0.88875049 2 P 0 ;1,3=102,5=0.000000
L 4.72493346 -0.88875049 4.72119931 -0.89624882 2 P 0 ;1,3=102,5=0.000000
L 4.72119931 -0.89624882 4.7183999 -0.90625128 2 P 0 ;1,3=102,5=0.000000
L 4.7183999 -0.90625128 4.71746673 -0.91750118 2 P 0 ;1,3=102,5=0.000000
L 4.71746673 -0.91750118 4.7183999 -0.92875108 2 P 0 ;1,3=102,5=0.000000
L 4.7183999 -0.92875108 4.72119931 -0.93875128 2 P 0 ;1,3=102,5=0.000000
L 4.72119931 -0.93875128 4.72493346 -0.94625187 2 P 0 ;1,3=102,5=0.000000
L 4.72493346 -0.94625187 4.73053228 -0.95250059 2 P 0 ;1,3=102,5=0.000000
L 4.73053228 -0.95250059 4.73799911 -0.955 2 P 0 ;1,3=102,5=0.000000
L 4.73799911 -0.955 4.74546585 -0.95250059 2 P 0 ;1,3=102,5=0.000000
L 4.74546585 -0.95250059 4.75106644 -0.94625187 2 P 0 ;1,3=102,5=0.000000
L 4.75106644 -0.94625187 4.75480059 -0.93875128 2 P 0 ;1,3=102,5=0.000000
L 4.75480059 -0.93875128 4.7576 -0.92875108 2 P 0 ;1,3=102,5=0.000000
L 4.7576 -0.92875108 4.75853317 -0.91750118 2 P 0 ;1,3=102,5=0.000000
L 4.75853317 -0.91750118 4.7576 -0.90625128 2 P 0 ;1,3=102,5=0.000000
L 4.7576 -0.90625128 4.75480059 -0.89624882 2 P 0 ;1,3=102,5=0.000000
L 4.75480059 -0.89624882 4.75106644 -0.88875049 2 P 0 ;1,3=102,5=0.000000
L 4.75106644 -0.88875049 4.74546585 -0.88249951 2 P 0 ;1,3=102,5=0.000000
L 4.74546585 -0.88249951 4.73799911 -0.88 2 P 0 ;1,3=102,5=0.000000
L 4.79526614 -0.8924997 4.80086663 -0.88500128 2 P 0 ;1,3=102,5=0.000000
L 4.80086663 -0.88500128 4.8074003 -0.8812498 2 P 0 ;1,3=102,5=0.000000
L 4.8074003 -0.8812498 4.81486703 -0.88 2 P 0 ;1,3=102,5=0.000000
L 4.81486703 -0.88 4.8242001 -0.88249951 2 P 0 ;1,3=102,5=0.000000
L 4.8242001 -0.88249951 4.83073376 -0.88875049 2 P 0 ;1,3=102,5=0.000000
L 4.83073376 -0.88875049 4.8326 -0.89624882 2 P 0 ;1,3=102,5=0.000000
L 4.8326 -0.89624882 4.83166693 -0.90375187 2 P 0 ;1,3=102,5=0.000000
L 4.83166693 -0.90375187 4.82793268 -0.91000049 2 P 0 ;1,3=102,5=0.000000
L 4.82793268 -0.91000049 4.80926654 -0.9225001 2 P 0 ;1,3=102,5=0.000000
L 4.80926654 -0.9225001 4.80086663 -0.93125059 2 P 0 ;1,3=102,5=0.000000
L 4.80086663 -0.93125059 4.79526614 -0.94375246 2 P 0 ;1,3=102,5=0.000000
L 4.79526614 -0.94375246 4.7933999 -0.955 2 P 0 ;1,3=102,5=0.000000
L 4.7933999 -0.955 4.8326 -0.955 2 P 0 ;1,3=102,5=0.000000
L 3.36746673 -1.205 3.36746673 -1.13 2 P 0 ;1,3=103,5=0.000000
L 3.36746673 -1.13 3.38613287 -1.13 2 P 0 ;1,3=103,5=0.000000
L 3.38613287 -1.13 3.39359961 -1.13375157 2 P 0 ;1,3=103,5=0.000000
L 3.39359961 -1.13375157 3.3992001 -1.13875049 2 P 0 ;1,3=103,5=0.000000
L 3.3992001 -1.13875049 3.40386752 -1.14624882 2 P 0 ;1,3=103,5=0.000000
L 3.40386752 -1.14624882 3.4076 -1.15500157 2 P 0 ;1,3=103,5=0.000000
L 3.4076 -1.15500157 3.40853317 -1.16750118 2 P 0 ;1,3=103,5=0.000000
L 3.40853317 -1.16750118 3.4076 -1.18000079 2 P 0 ;1,3=103,5=0.000000
L 3.4076 -1.18000079 3.40386752 -1.18875128 2 P 0 ;1,3=103,5=0.000000
L 3.40386752 -1.18875128 3.3992001 -1.19625187 2 P 0 ;1,3=103,5=0.000000
L 3.3992001 -1.19625187 3.39359961 -1.20125089 2 P 0 ;1,3=103,5=0.000000
L 3.39359961 -1.20125089 3.38613287 -1.205 2 P 0 ;1,3=103,5=0.000000
L 3.38613287 -1.205 3.36746673 -1.205 2 P 0 ;1,3=103,5=0.000000
L 3.47980059 -1.205 3.47980059 -1.15500157 2 P 0 ;1,3=103,5=0.000000
L 3.47980059 -1.1637497 3.47606644 -1.15875079 2 P 0 ;1,3=103,5=0.000000
L 3.47606644 -1.15875079 3.47046585 -1.15625128 2 P 0 ;1,3=103,5=0.000000
L 3.47046585 -1.15625128 3.46393396 -1.15500157 2 P 0 ;1,3=103,5=0.000000
L 3.46393396 -1.15500157 3.4574003 -1.15750108 2 P 0 ;1,3=103,5=0.000000
L 3.4574003 -1.15750108 3.4517998 -1.1625 2 P 0 ;1,3=103,5=0.000000
L 3.4517998 -1.1625 3.44806555 -1.17000069 2 P 0 ;1,3=103,5=0.000000
L 3.44806555 -1.17000069 3.44619931 -1.18000079 2 P 0 ;1,3=103,5=0.000000
L 3.44619931 -1.18000079 3.44806555 -1.19000098 2 P 0 ;1,3=103,5=0.000000
L 3.44806555 -1.19000098 3.4517998 -1.19750167 2 P 0 ;1,3=103,5=0.000000
L 3.4517998 -1.19750167 3.4574003 -1.20250059 2 P 0 ;1,3=103,5=0.000000
L 3.4574003 -1.20250059 3.46393396 -1.205 2 P 0 ;1,3=103,5=0.000000
L 3.46393396 -1.205 3.47046585 -1.2037503 2 P 0 ;1,3=103,5=0.000000
L 3.47046585 -1.2037503 3.47606644 -1.20000108 2 P 0 ;1,3=103,5=0.000000
L 3.47606644 -1.20000108 3.47980059 -1.19500217 2 P 0 ;1,3=103,5=0.000000
L 3.53799911 -1.13 3.53799911 -1.205 2 P 0 ;1,3=103,5=0.000000
L 3.52493346 -1.15500157 3.55106644 -1.15500157 2 P 0 ;1,3=103,5=0.000000
L 3.59900039 -1.17125039 3.62886752 -1.17125039 2 P 0 ;1,3=103,5=0.000000
L 3.62886752 -1.17125039 3.62606644 -1.1625 2 P 0 ;1,3=103,5=0.000000
L 3.62606644 -1.1625 3.62140069 -1.15750108 2 P 0 ;1,3=103,5=0.000000
L 3.62140069 -1.15750108 3.61486703 -1.15500157 2 P 0 ;1,3=103,5=0.000000
L 3.61486703 -1.15500157 3.60833346 -1.15625128 2 P 0 ;1,3=103,5=0.000000
L 3.60833346 -1.15625128 3.60273287 -1.16000049 2 P 0 ;1,3=103,5=0.000000
L 3.60273287 -1.16000049 3.59900039 -1.16875089 2 P 0 ;1,3=103,5=0.000000
L 3.59900039 -1.16875089 3.59713238 -1.17625157 2 P 0 ;1,3=103,5=0.000000
L 3.59713238 -1.17625157 3.59713238 -1.18375 2 P 0 ;1,3=103,5=0.000000
L 3.59713238 -1.18375 3.59900039 -1.19125069 2 P 0 ;1,3=103,5=0.000000
L 3.59900039 -1.19125069 3.60366604 -1.19875138 2 P 0 ;1,3=103,5=0.000000
L 3.60366604 -1.19875138 3.60926654 -1.2037503 2 P 0 ;1,3=103,5=0.000000
L 3.60926654 -1.2037503 3.6158002 -1.205 2 P 0 ;1,3=103,5=0.000000
L 3.6158002 -1.205 3.62233386 -1.20250059 2 P 0 ;1,3=103,5=0.000000
L 3.62233386 -1.20250059 3.62886752 -1.19500217 2 P 0 ;1,3=103,5=0.000000
L 3.68799911 -1.20749941 3.68613287 -1.2062497 2 P 0 ;1,3=103,5=0.000000
L 3.68613287 -1.2062497 3.68613287 -1.2037503 2 P 0 ;1,3=103,5=0.000000
L 3.68613287 -1.2037503 3.68799911 -1.20250059 2 P 0 ;1,3=103,5=0.000000
L 3.68799911 -1.20250059 3.68986703 -1.2037503 2 P 0 ;1,3=103,5=0.000000
L 3.68986703 -1.2037503 3.68986703 -1.2062497 2 P 0 ;1,3=103,5=0.000000
L 3.68986703 -1.2062497 3.68799911 -1.20749941 2 P 0 ;1,3=103,5=0.000000
L 3.68799911 -1.17375217 3.68613287 -1.1725001 2 P 0 ;1,3=103,5=0.000000
L 3.68613287 -1.1725001 3.68613287 -1.17000069 2 P 0 ;1,3=103,5=0.000000
L 3.68613287 -1.17000069 3.68799911 -1.16875089 2 P 0 ;1,3=103,5=0.000000
L 3.68799911 -1.16875089 3.68986703 -1.17000069 2 P 0 ;1,3=103,5=0.000000
L 3.68986703 -1.17000069 3.68986703 -1.1725001 2 P 0 ;1,3=103,5=0.000000
L 3.68986703 -1.1725001 3.68799911 -1.17375217 2 P 0 ;1,3=103,5=0.000000
L 3.82026614 -1.1424997 3.82586663 -1.13500128 2 P 0 ;1,3=103,5=0.000000
L 3.82586663 -1.13500128 3.8324003 -1.1312498 2 P 0 ;1,3=103,5=0.000000
L 3.8324003 -1.1312498 3.83986703 -1.13 2 P 0 ;1,3=103,5=0.000000
L 3.83986703 -1.13 3.8492001 -1.13249951 2 P 0 ;1,3=103,5=0.000000
L 3.8492001 -1.13249951 3.85573376 -1.13875049 2 P 0 ;1,3=103,5=0.000000
L 3.85573376 -1.13875049 3.8576 -1.14624882 2 P 0 ;1,3=103,5=0.000000
L 3.8576 -1.14624882 3.85666693 -1.15375187 2 P 0 ;1,3=103,5=0.000000
L 3.85666693 -1.15375187 3.85293268 -1.16000049 2 P 0 ;1,3=103,5=0.000000
L 3.85293268 -1.16000049 3.83426654 -1.1725001 2 P 0 ;1,3=103,5=0.000000
L 3.83426654 -1.1725001 3.82586663 -1.18125059 2 P 0 ;1,3=103,5=0.000000
L 3.82586663 -1.18125059 3.82026614 -1.19375246 2 P 0 ;1,3=103,5=0.000000
L 3.82026614 -1.19375246 3.8183999 -1.205 2 P 0 ;1,3=103,5=0.000000
L 3.8183999 -1.205 3.8576 -1.205 2 P 0 ;1,3=103,5=0.000000
L 3.91299911 -1.13 3.90553228 -1.13249951 2 P 0 ;1,3=103,5=0.000000
L 3.90553228 -1.13249951 3.89993346 -1.13875049 2 P 0 ;1,3=103,5=0.000000
L 3.89993346 -1.13875049 3.89619931 -1.14624882 2 P 0 ;1,3=103,5=0.000000
L 3.89619931 -1.14624882 3.8933999 -1.15625128 2 P 0 ;1,3=103,5=0.000000
L 3.8933999 -1.15625128 3.89246673 -1.16750118 2 P 0 ;1,3=103,5=0.000000
L 3.89246673 -1.16750118 3.8933999 -1.17875108 2 P 0 ;1,3=103,5=0.000000
L 3.8933999 -1.17875108 3.89619931 -1.18875128 2 P 0 ;1,3=103,5=0.000000
L 3.89619931 -1.18875128 3.89993346 -1.19625187 2 P 0 ;1,3=103,5=0.000000
L 3.89993346 -1.19625187 3.90553228 -1.20250059 2 P 0 ;1,3=103,5=0.000000
L 3.90553228 -1.20250059 3.91299911 -1.205 2 P 0 ;1,3=103,5=0.000000
L 3.91299911 -1.205 3.92046585 -1.20250059 2 P 0 ;1,3=103,5=0.000000
L 3.92046585 -1.20250059 3.92606644 -1.19625187 2 P 0 ;1,3=103,5=0.000000
L 3.92606644 -1.19625187 3.92980059 -1.18875128 2 P 0 ;1,3=103,5=0.000000
L 3.92980059 -1.18875128 3.9326 -1.17875108 2 P 0 ;1,3=103,5=0.000000
L 3.9326 -1.17875108 3.93353317 -1.16750118 2 P 0 ;1,3=103,5=0.000000
L 3.93353317 -1.16750118 3.9326 -1.15625128 2 P 0 ;1,3=103,5=0.000000
L 3.9326 -1.15625128 3.92980059 -1.14624882 2 P 0 ;1,3=103,5=0.000000
L 3.92980059 -1.14624882 3.92606644 -1.13875049 2 P 0 ;1,3=103,5=0.000000
L 3.92606644 -1.13875049 3.92046585 -1.13249951 2 P 0 ;1,3=103,5=0.000000
L 3.92046585 -1.13249951 3.91299911 -1.13 2 P 0 ;1,3=103,5=0.000000
L 3.97026614 -1.1424997 3.97586663 -1.13500128 2 P 0 ;1,3=103,5=0.000000
L 3.97586663 -1.13500128 3.9824003 -1.1312498 2 P 0 ;1,3=103,5=0.000000
L 3.9824003 -1.1312498 3.98986703 -1.13 2 P 0 ;1,3=103,5=0.000000
L 3.98986703 -1.13 3.9992001 -1.13249951 2 P 0 ;1,3=103,5=0.000000
L 3.9992001 -1.13249951 4.00573376 -1.13875049 2 P 0 ;1,3=103,5=0.000000
L 4.00573376 -1.13875049 4.0076 -1.14624882 2 P 0 ;1,3=103,5=0.000000
L 4.0076 -1.14624882 4.00666693 -1.15375187 2 P 0 ;1,3=103,5=0.000000
L 4.00666693 -1.15375187 4.00293268 -1.16000049 2 P 0 ;1,3=103,5=0.000000
L 4.00293268 -1.16000049 3.98426654 -1.1725001 2 P 0 ;1,3=103,5=0.000000
L 3.98426654 -1.1725001 3.97586663 -1.18125059 2 P 0 ;1,3=103,5=0.000000
L 3.97586663 -1.18125059 3.97026614 -1.19375246 2 P 0 ;1,3=103,5=0.000000
L 3.97026614 -1.19375246 3.9683999 -1.205 2 P 0 ;1,3=103,5=0.000000
L 3.9683999 -1.205 4.0076 -1.205 2 P 0 ;1,3=103,5=0.000000
L 4.04526614 -1.1424997 4.05086663 -1.13500128 2 P 0 ;1,3=103,5=0.000000
L 4.05086663 -1.13500128 4.0574003 -1.1312498 2 P 0 ;1,3=103,5=0.000000
L 4.0574003 -1.1312498 4.06486703 -1.13 2 P 0 ;1,3=103,5=0.000000
L 4.06486703 -1.13 4.0742001 -1.13249951 2 P 0 ;1,3=103,5=0.000000
L 4.0742001 -1.13249951 4.08073376 -1.13875049 2 P 0 ;1,3=103,5=0.000000
L 4.08073376 -1.13875049 4.0826 -1.14624882 2 P 0 ;1,3=103,5=0.000000
L 4.0826 -1.14624882 4.08166693 -1.15375187 2 P 0 ;1,3=103,5=0.000000
L 4.08166693 -1.15375187 4.07793268 -1.16000049 2 P 0 ;1,3=103,5=0.000000
L 4.07793268 -1.16000049 4.05926654 -1.1725001 2 P 0 ;1,3=103,5=0.000000
L 4.05926654 -1.1725001 4.05086663 -1.18125059 2 P 0 ;1,3=103,5=0.000000
L 4.05086663 -1.18125059 4.04526614 -1.19375246 2 P 0 ;1,3=103,5=0.000000
L 4.04526614 -1.19375246 4.0433999 -1.205 2 P 0 ;1,3=103,5=0.000000
L 4.0433999 -1.205 4.0826 -1.205 2 P 0 ;1,3=103,5=0.000000
L 4.12586663 -1.18000079 4.15013327 -1.18000079 2 P 0 ;1,3=103,5=0.000000
L 4.21299911 -1.13 4.20553228 -1.13249951 2 P 0 ;1,3=103,5=0.000000
L 4.20553228 -1.13249951 4.19993346 -1.13875049 2 P 0 ;1,3=103,5=0.000000
L 4.19993346 -1.13875049 4.19619931 -1.14624882 2 P 0 ;1,3=103,5=0.000000
L 4.19619931 -1.14624882 4.1933999 -1.15625128 2 P 0 ;1,3=103,5=0.000000
L 4.1933999 -1.15625128 4.19246673 -1.16750118 2 P 0 ;1,3=103,5=0.000000
L 4.19246673 -1.16750118 4.1933999 -1.17875108 2 P 0 ;1,3=103,5=0.000000
L 4.1933999 -1.17875108 4.19619931 -1.18875128 2 P 0 ;1,3=103,5=0.000000
L 4.19619931 -1.18875128 4.19993346 -1.19625187 2 P 0 ;1,3=103,5=0.000000
L 4.19993346 -1.19625187 4.20553228 -1.20250059 2 P 0 ;1,3=103,5=0.000000
L 4.20553228 -1.20250059 4.21299911 -1.205 2 P 0 ;1,3=103,5=0.000000
L 4.21299911 -1.205 4.22046585 -1.20250059 2 P 0 ;1,3=103,5=0.000000
L 4.22046585 -1.20250059 4.22606644 -1.19625187 2 P 0 ;1,3=103,5=0.000000
L 4.22606644 -1.19625187 4.22980059 -1.18875128 2 P 0 ;1,3=103,5=0.000000
L 4.22980059 -1.18875128 4.2326 -1.17875108 2 P 0 ;1,3=103,5=0.000000
L 4.2326 -1.17875108 4.23353317 -1.16750118 2 P 0 ;1,3=103,5=0.000000
L 4.23353317 -1.16750118 4.2326 -1.15625128 2 P 0 ;1,3=103,5=0.000000
L 4.2326 -1.15625128 4.22980059 -1.14624882 2 P 0 ;1,3=103,5=0.000000
L 4.22980059 -1.14624882 4.22606644 -1.13875049 2 P 0 ;1,3=103,5=0.000000
L 4.22606644 -1.13875049 4.22046585 -1.13249951 2 P 0 ;1,3=103,5=0.000000
L 4.22046585 -1.13249951 4.21299911 -1.13 2 P 0 ;1,3=103,5=0.000000
L 4.27026614 -1.1424997 4.27586663 -1.13500128 2 P 0 ;1,3=103,5=0.000000
L 4.27586663 -1.13500128 4.2824003 -1.1312498 2 P 0 ;1,3=103,5=0.000000
L 4.2824003 -1.1312498 4.28986703 -1.13 2 P 0 ;1,3=103,5=0.000000
L 4.28986703 -1.13 4.2992001 -1.13249951 2 P 0 ;1,3=103,5=0.000000
L 4.2992001 -1.13249951 4.30573376 -1.13875049 2 P 0 ;1,3=103,5=0.000000
L 4.30573376 -1.13875049 4.3076 -1.14624882 2 P 0 ;1,3=103,5=0.000000
L 4.3076 -1.14624882 4.30666693 -1.15375187 2 P 0 ;1,3=103,5=0.000000
L 4.30666693 -1.15375187 4.30293268 -1.16000049 2 P 0 ;1,3=103,5=0.000000
L 4.30293268 -1.16000049 4.28426654 -1.1725001 2 P 0 ;1,3=103,5=0.000000
L 4.28426654 -1.1725001 4.27586663 -1.18125059 2 P 0 ;1,3=103,5=0.000000
L 4.27586663 -1.18125059 4.27026614 -1.19375246 2 P 0 ;1,3=103,5=0.000000
L 4.27026614 -1.19375246 4.2683999 -1.205 2 P 0 ;1,3=103,5=0.000000
L 4.2683999 -1.205 4.3076 -1.205 2 P 0 ;1,3=103,5=0.000000
L 4.35086663 -1.18000079 4.37513327 -1.18000079 2 P 0 ;1,3=103,5=0.000000
L 4.42026614 -1.1424997 4.42586663 -1.13500128 2 P 0 ;1,3=103,5=0.000000
L 4.42586663 -1.13500128 4.4324003 -1.1312498 2 P 0 ;1,3=103,5=0.000000
L 4.4324003 -1.1312498 4.43986703 -1.13 2 P 0 ;1,3=103,5=0.000000
L 4.43986703 -1.13 4.4492001 -1.13249951 2 P 0 ;1,3=103,5=0.000000
L 4.4492001 -1.13249951 4.45573376 -1.13875049 2 P 0 ;1,3=103,5=0.000000
L 4.45573376 -1.13875049 4.4576 -1.14624882 2 P 0 ;1,3=103,5=0.000000
L 4.4576 -1.14624882 4.45666693 -1.15375187 2 P 0 ;1,3=103,5=0.000000
L 4.45666693 -1.15375187 4.45293268 -1.16000049 2 P 0 ;1,3=103,5=0.000000
L 4.45293268 -1.16000049 4.43426654 -1.1725001 2 P 0 ;1,3=103,5=0.000000
L 4.43426654 -1.1725001 4.42586663 -1.18125059 2 P 0 ;1,3=103,5=0.000000
L 4.42586663 -1.18125059 4.42026614 -1.19375246 2 P 0 ;1,3=103,5=0.000000
L 4.42026614 -1.19375246 4.4183999 -1.205 2 P 0 ;1,3=103,5=0.000000
L 4.4183999 -1.205 4.4576 -1.205 2 P 0 ;1,3=103,5=0.000000
L 4.49246673 -1.19375246 4.49806555 -1.20000108 2 P 0 ;1,3=103,5=0.000000
L 4.49806555 -1.20000108 4.50459921 -1.2037503 2 P 0 ;1,3=103,5=0.000000
L 4.50459921 -1.2037503 4.51299911 -1.205 2 P 0 ;1,3=103,5=0.000000
L 4.51299911 -1.205 4.52140069 -1.20250059 2 P 0 ;1,3=103,5=0.000000
L 4.52140069 -1.20250059 4.52793268 -1.19750167 2 P 0 ;1,3=103,5=0.000000
L 4.52793268 -1.19750167 4.5326 -1.18875128 2 P 0 ;1,3=103,5=0.000000
L 4.5326 -1.18875128 4.53353317 -1.17875108 2 P 0 ;1,3=103,5=0.000000
L 4.53353317 -1.17875108 4.53166693 -1.16875089 2 P 0 ;1,3=103,5=0.000000
L 4.53166693 -1.16875089 4.52699951 -1.1625 2 P 0 ;1,3=103,5=0.000000
L 4.52699951 -1.1625 4.52046585 -1.15750108 2 P 0 ;1,3=103,5=0.000000
L 4.52046585 -1.15750108 4.51393396 -1.15625128 2 P 0 ;1,3=103,5=0.000000
L 4.51393396 -1.15625128 4.5074003 -1.15750108 2 P 0 ;1,3=103,5=0.000000
L 4.5074003 -1.15750108 4.49900039 -1.1625 2 P 0 ;1,3=103,5=0.000000
L 4.49900039 -1.1625 4.5017998 -1.13 2 P 0 ;1,3=103,5=0.000000
L 4.5017998 -1.13 4.52699951 -1.13 2 P 0 ;1,3=103,5=0.000000
L 3.29433297 -1.255 3.29433297 -1.33 2 P 0 ;1,3=104,5=0.000000
L 3.29433297 -1.33 3.33166693 -1.33 2 P 0 ;1,3=104,5=0.000000
L 3.40480059 -1.33 3.40480059 -1.28000157 2 P 0 ;1,3=104,5=0.000000
L 3.40480059 -1.2887497 3.40106644 -1.28375079 2 P 0 ;1,3=104,5=0.000000
L 3.40106644 -1.28375079 3.39546585 -1.28125128 2 P 0 ;1,3=104,5=0.000000
L 3.39546585 -1.28125128 3.38893396 -1.28000157 2 P 0 ;1,3=104,5=0.000000
L 3.38893396 -1.28000157 3.3824003 -1.28250108 2 P 0 ;1,3=104,5=0.000000
L 3.3824003 -1.28250108 3.3767998 -1.2875 2 P 0 ;1,3=104,5=0.000000
L 3.3767998 -1.2875 3.37306555 -1.29500069 2 P 0 ;1,3=104,5=0.000000
L 3.37306555 -1.29500069 3.37119931 -1.30500079 2 P 0 ;1,3=104,5=0.000000
L 3.37119931 -1.30500079 3.37306555 -1.31500098 2 P 0 ;1,3=104,5=0.000000
L 3.37306555 -1.31500098 3.3767998 -1.32250167 2 P 0 ;1,3=104,5=0.000000
L 3.3767998 -1.32250167 3.3824003 -1.32750059 2 P 0 ;1,3=104,5=0.000000
L 3.3824003 -1.32750059 3.38893396 -1.33 2 P 0 ;1,3=104,5=0.000000
L 3.38893396 -1.33 3.39546585 -1.3287503 2 P 0 ;1,3=104,5=0.000000
L 3.39546585 -1.3287503 3.40106644 -1.32500108 2 P 0 ;1,3=104,5=0.000000
L 3.40106644 -1.32500108 3.40480059 -1.32000217 2 P 0 ;1,3=104,5=0.000000
L 3.4433999 -1.3524997 3.44900039 -1.35499921 2 P 0 ;1,3=104,5=0.000000
L 3.44900039 -1.35499921 3.45646713 -1.3524997 2 P 0 ;1,3=104,5=0.000000
L 3.45646713 -1.3524997 3.46113287 -1.34750079 2 P 0 ;1,3=104,5=0.000000
L 3.46113287 -1.34750079 3.46486703 -1.3412498 2 P 0 ;1,3=104,5=0.000000
L 3.46486703 -1.3412498 3.47046585 -1.32125187 2 P 0 ;1,3=104,5=0.000000
L 3.47046585 -1.32125187 3.4826 -1.28000157 2 P 0 ;1,3=104,5=0.000000
L 3.45273287 -1.28000157 3.47046585 -1.32125187 2 P 0 ;1,3=104,5=0.000000
L 3.52400039 -1.29625039 3.55386752 -1.29625039 2 P 0 ;1,3=104,5=0.000000
L 3.55386752 -1.29625039 3.55106644 -1.2875 2 P 0 ;1,3=104,5=0.000000
L 3.55106644 -1.2875 3.54640069 -1.28250108 2 P 0 ;1,3=104,5=0.000000
L 3.54640069 -1.28250108 3.53986703 -1.28000157 2 P 0 ;1,3=104,5=0.000000
L 3.53986703 -1.28000157 3.53333346 -1.28125128 2 P 0 ;1,3=104,5=0.000000
L 3.53333346 -1.28125128 3.52773287 -1.28500049 2 P 0 ;1,3=104,5=0.000000
L 3.52773287 -1.28500049 3.52400039 -1.29375089 2 P 0 ;1,3=104,5=0.000000
L 3.52400039 -1.29375089 3.52213238 -1.30125157 2 P 0 ;1,3=104,5=0.000000
L 3.52213238 -1.30125157 3.52213238 -1.30875 2 P 0 ;1,3=104,5=0.000000
L 3.52213238 -1.30875 3.52400039 -1.31625069 2 P 0 ;1,3=104,5=0.000000
L 3.52400039 -1.31625069 3.52866604 -1.32375138 2 P 0 ;1,3=104,5=0.000000
L 3.52866604 -1.32375138 3.53426654 -1.3287503 2 P 0 ;1,3=104,5=0.000000
L 3.53426654 -1.3287503 3.5408002 -1.33 2 P 0 ;1,3=104,5=0.000000
L 3.5408002 -1.33 3.54733386 -1.32750059 2 P 0 ;1,3=104,5=0.000000
L 3.54733386 -1.32750059 3.55386752 -1.32000217 2 P 0 ;1,3=104,5=0.000000
L 3.59993346 -1.33 3.59993346 -1.28000157 2 P 0 ;1,3=104,5=0.000000
L 3.59993346 -1.28999941 3.60459921 -1.28500049 2 P 0 ;1,3=104,5=0.000000
L 3.60459921 -1.28500049 3.60926654 -1.28125128 2 P 0 ;1,3=104,5=0.000000
L 3.60926654 -1.28125128 3.6158002 -1.28000157 2 P 0 ;1,3=104,5=0.000000
L 3.6158002 -1.28000157 3.62046585 -1.28125128 2 P 0 ;1,3=104,5=0.000000
L 3.62046585 -1.28125128 3.62606644 -1.28500049 2 P 0 ;1,3=104,5=0.000000
L 3.68799911 -1.33249941 3.68613287 -1.3312497 2 P 0 ;1,3=104,5=0.000000
L 3.68613287 -1.3312497 3.68613287 -1.3287503 2 P 0 ;1,3=104,5=0.000000
L 3.68613287 -1.3287503 3.68799911 -1.32750059 2 P 0 ;1,3=104,5=0.000000
L 3.68799911 -1.32750059 3.68986703 -1.3287503 2 P 0 ;1,3=104,5=0.000000
L 3.68986703 -1.3287503 3.68986703 -1.3312497 2 P 0 ;1,3=104,5=0.000000
L 3.68986703 -1.3312497 3.68799911 -1.33249941 2 P 0 ;1,3=104,5=0.000000
L 3.68799911 -1.29875217 3.68613287 -1.2975001 2 P 0 ;1,3=104,5=0.000000
L 3.68613287 -1.2975001 3.68613287 -1.29500069 2 P 0 ;1,3=104,5=0.000000
L 3.68613287 -1.29500069 3.68799911 -1.29375089 2 P 0 ;1,3=104,5=0.000000
L 3.68799911 -1.29375089 3.68986703 -1.29500069 2 P 0 ;1,3=104,5=0.000000
L 3.68986703 -1.29500069 3.68986703 -1.2975001 2 P 0 ;1,3=104,5=0.000000
L 3.68986703 -1.2975001 3.68799911 -1.29875217 2 P 0 ;1,3=104,5=0.000000
L 3.36933297 -1.08 3.36933297 -1.005 2 P 0 ;1,3=105,5=0.000000
L 3.36933297 -1.005 3.39266644 -1.005 2 P 0 ;1,3=105,5=0.000000
L 3.39266644 -1.005 3.40013327 -1.00875157 2 P 0 ;1,3=105,5=0.000000
L 3.40013327 -1.00875157 3.40480059 -1.01375049 2 P 0 ;1,3=105,5=0.000000
L 3.40480059 -1.01375049 3.40666693 -1.02375059 2 P 0 ;1,3=105,5=0.000000
L 3.40666693 -1.02375059 3.40480059 -1.03375079 2 P 0 ;1,3=105,5=0.000000
L 3.40480059 -1.03375079 3.3992001 -1.03999941 2 P 0 ;1,3=105,5=0.000000
L 3.3992001 -1.03999941 3.39266644 -1.04375089 2 P 0 ;1,3=105,5=0.000000
L 3.39266644 -1.04375089 3.36933297 -1.04375089 2 P 0 ;1,3=105,5=0.000000
L 3.39266644 -1.04375089 3.40666693 -1.08 2 P 0 ;1,3=105,5=0.000000
L 3.44900039 -1.04625039 3.47886752 -1.04625039 2 P 0 ;1,3=105,5=0.000000
L 3.47886752 -1.04625039 3.47606644 -1.0375 2 P 0 ;1,3=105,5=0.000000
L 3.47606644 -1.0375 3.47140069 -1.03250108 2 P 0 ;1,3=105,5=0.000000
L 3.47140069 -1.03250108 3.46486703 -1.03000157 2 P 0 ;1,3=105,5=0.000000
L 3.46486703 -1.03000157 3.45833346 -1.03125128 2 P 0 ;1,3=105,5=0.000000
L 3.45833346 -1.03125128 3.45273287 -1.03500049 2 P 0 ;1,3=105,5=0.000000
L 3.45273287 -1.03500049 3.44900039 -1.04375089 2 P 0 ;1,3=105,5=0.000000
L 3.44900039 -1.04375089 3.44713238 -1.05125157 2 P 0 ;1,3=105,5=0.000000
L 3.44713238 -1.05125157 3.44713238 -1.05875 2 P 0 ;1,3=105,5=0.000000
L 3.44713238 -1.05875 3.44900039 -1.06625069 2 P 0 ;1,3=105,5=0.000000
L 3.44900039 -1.06625069 3.45366604 -1.07375138 2 P 0 ;1,3=105,5=0.000000
L 3.45366604 -1.07375138 3.45926654 -1.0787503 2 P 0 ;1,3=105,5=0.000000
L 3.45926654 -1.0787503 3.4658002 -1.08 2 P 0 ;1,3=105,5=0.000000
L 3.4658002 -1.08 3.47233386 -1.07750059 2 P 0 ;1,3=105,5=0.000000
L 3.47233386 -1.07750059 3.47886752 -1.07000217 2 P 0 ;1,3=105,5=0.000000
L 3.52119931 -1.03000157 3.53799911 -1.08 2 P 0 ;1,3=105,5=0.000000
L 3.53799911 -1.08 3.55480059 -1.03000157 2 P 0 ;1,3=105,5=0.000000
L 3.68799911 -1.08249941 3.68613287 -1.0812497 2 P 0 ;1,3=105,5=0.000000
L 3.68613287 -1.0812497 3.68613287 -1.0787503 2 P 0 ;1,3=105,5=0.000000
L 3.68613287 -1.0787503 3.68799911 -1.07750059 2 P 0 ;1,3=105,5=0.000000
L 3.68799911 -1.07750059 3.68986703 -1.0787503 2 P 0 ;1,3=105,5=0.000000
L 3.68986703 -1.0787503 3.68986703 -1.0812497 2 P 0 ;1,3=105,5=0.000000
L 3.68986703 -1.0812497 3.68799911 -1.08249941 2 P 0 ;1,3=105,5=0.000000
L 3.68799911 -1.04875217 3.68613287 -1.0475001 2 P 0 ;1,3=105,5=0.000000
L 3.68613287 -1.0475001 3.68613287 -1.04500069 2 P 0 ;1,3=105,5=0.000000
L 3.68613287 -1.04500069 3.68799911 -1.04375089 2 P 0 ;1,3=105,5=0.000000
L 3.68799911 -1.04375089 3.68986703 -1.04500069 2 P 0 ;1,3=105,5=0.000000
L 3.68986703 -1.04500069 3.68986703 -1.0475001 2 P 0 ;1,3=105,5=0.000000
L 3.68986703 -1.0475001 3.68799911 -1.04875217 2 P 0 ;1,3=105,5=0.000000
L 3.83799911 -1.005 3.83053228 -1.00749951 2 P 0 ;1,3=105,5=0.000000
L 3.83053228 -1.00749951 3.82493346 -1.01375049 2 P 0 ;1,3=105,5=0.000000
L 3.82493346 -1.01375049 3.82119931 -1.02124882 2 P 0 ;1,3=105,5=0.000000
L 3.82119931 -1.02124882 3.8183999 -1.03125128 2 P 0 ;1,3=105,5=0.000000
L 3.8183999 -1.03125128 3.81746673 -1.04250118 2 P 0 ;1,3=105,5=0.000000
L 3.81746673 -1.04250118 3.8183999 -1.05375108 2 P 0 ;1,3=105,5=0.000000
L 3.8183999 -1.05375108 3.82119931 -1.06375128 2 P 0 ;1,3=105,5=0.000000
L 3.82119931 -1.06375128 3.82493346 -1.07125187 2 P 0 ;1,3=105,5=0.000000
L 3.82493346 -1.07125187 3.83053228 -1.07750059 2 P 0 ;1,3=105,5=0.000000
L 3.83053228 -1.07750059 3.83799911 -1.08 2 P 0 ;1,3=105,5=0.000000
L 3.83799911 -1.08 3.84546585 -1.07750059 2 P 0 ;1,3=105,5=0.000000
L 3.84546585 -1.07750059 3.85106644 -1.07125187 2 P 0 ;1,3=105,5=0.000000
L 3.85106644 -1.07125187 3.85480059 -1.06375128 2 P 0 ;1,3=105,5=0.000000
L 3.85480059 -1.06375128 3.8576 -1.05375108 2 P 0 ;1,3=105,5=0.000000
L 3.8576 -1.05375108 3.85853317 -1.04250118 2 P 0 ;1,3=105,5=0.000000
L 3.85853317 -1.04250118 3.8576 -1.03125128 2 P 0 ;1,3=105,5=0.000000
L 3.8576 -1.03125128 3.85480059 -1.02124882 2 P 0 ;1,3=105,5=0.000000
L 3.85480059 -1.02124882 3.85106644 -1.01375049 2 P 0 ;1,3=105,5=0.000000
L 3.85106644 -1.01375049 3.84546585 -1.00749951 2 P 0 ;1,3=105,5=0.000000
L 3.84546585 -1.00749951 3.83799911 -1.005 2 P 0 ;1,3=105,5=0.000000
L 3.91299911 -1.08 3.91299911 -1.005 2 P 0 ;1,3=105,5=0.000000
L 3.91299911 -1.005 3.9017998 -1.01999911 2 P 0 ;1,3=105,5=0.000000
L 3.9017998 -1.08 3.92419843 -1.08 2 P 0 ;1,3=105,5=0.000000

### steps/pcb/layers/comp_+_bot/components
#
#Component attribute names
#
@0 .comp_mount_type
@1 .comp_height

# CMP 0
CMP 6 3.77 0.89 90.0 N L10 ??? ;0=1,1=0.037000
PRP ALT_SYMBOLS '(SMC_0603R_H037)' 
PRP PARENT_PART_TYPE 'FERRITEBEAD' 
PRP PARENT_PPT 'FERRITEBEAD' 
PRP PARENT_PPT_PART 'FERRITEBEAD-G191-10097-01,600OHM,25%' 
PRP PART_NAME 'FERRITEBEAD' 
TOP 0 3.77 0.917 90.0 N 42 4 1
TOP 1 3.77 0.863 90.0 N 19 25 2
#
# CMP 1
CMP 6 1.32 3.575 90.0 N L22 ??? ;0=1,1=0.037000
PRP ALT_SYMBOLS '(SMC_0603R_H037)' 
PRP PARENT_PART_TYPE 'FERRITEBEAD' 
PRP PARENT_PPT 'FERRITEBEAD' 
PRP PARENT_PPT_PART 'FERRITEBEAD-G191-10097-01,600OHM,25%' 
PRP PART_NAME 'FERRITEBEAD' 
TOP 0 1.32 3.602 90.0 N 88 14 1
TOP 1 1.32 3.548 90.0 N 5 1 2
#
# CMP 2
CMP 6 1.09 3.485 270.0 N L4 ??? ;0=1,1=0.037000
PRP ALT_SYMBOLS '(SMC_0603R_H037)' 
PRP PARENT_PART_TYPE 'FERRITEBEAD' 
PRP PARENT_PPT 'FERRITEBEAD' 
PRP PARENT_PPT_PART 'FERRITEBEAD-G191-10097-01,600OHM,25%' 
PRP PART_NAME 'FERRITEBEAD' 
TOP 0 1.09 3.458 270.0 N 88 15 1
TOP 1 1.09 3.512 270.0 N 4 1 2
#
# CMP 3
CMP 6 4.27 0.805 90.0 N L14 ??? ;0=1,1=0.037000
PRP ALT_SYMBOLS '(SMC_0603R_H037)' 
PRP PARENT_PART_TYPE 'FERRITEBEAD' 
PRP PARENT_PPT 'FERRITEBEAD' 
PRP PARENT_PPT_PART 'FERRITEBEAD-G191-10097-01,600OHM,25%' 
PRP PART_NAME 'FERRITEBEAD' 
TOP 0 4.27 0.832 90.0 N 41 2 1
TOP 1 4.27 0.778 90.0 N 19 26 2
#
# CMP 4
CMP 9 3.01 2.18 90.0 N Q2 ??? ;0=1,1=0.043700
PRP ALT_SYMBOLS '(SOT23_V1_H044)' 
PRP PARENT_PART_TYPE 'POWERMOS_3P_NCH_V1' 
PRP PARENT_PPT 'POWERMOS_3P_NCH_V1' 
PRP PARENT_PPT_PART 'POWERMOS_3P_NCH_V1-G121-10200-01' 
PRP PART_NAME 'POWERMOS_3P_NCH_V1' 
TOP 0 3.0535 2.217 90.0 N 123 0 1
TOP 1 3.0535 2.143 90.0 N 2 470 2
TOP 2 2.9665 2.18 90.0 N 247 0 3
#
# CMP 5
CMP 10 3.015 2.315 270.0 N Q3 ??? ;0=1,1=0.045280
PRP ALT_SYMBOLS '(SOT23_V1_H045)' 
PRP PARENT_PART_TYPE 'POWERMOS_3P_PCH' 
PRP PARENT_PPT 'POWERMOS_3P_PCH' 
PRP PARENT_PPT_PART 'POWERMOS_3P_PCH-G121-10216-01' 
PRP PART_NAME 'POWERMOS_3P_PCH' 
TOP 0 2.9715 2.278 270.0 N 247 1 1
TOP 1 2.9715 2.352 270.0 N 76 1 2
TOP 2 3.0585 2.315 270.0 N 178 0 3
#
# CMP 6
CMP 11 3.705 0.84 0.0 N TP50 ??? ;0=2
PRP SCH_MODIFIED_PART 'TRUE' 
PRP PARENT_PART_TYPE 'TP_PIONT' 
PRP PARENT_PPT 'TP_PIONT' 
PRP PARENT_PPT_PART 'TP_PIONT-TP010CT020B030_PTH' 
PRP PART_NAME 'TP_PIONT' 
TOP 0 3.705 0.84 0.0 N 343 2 1
#
# CMP 7
CMP 11 3.065 1.695 0.0 N TP51 ??? ;0=2
PRP SCH_MODIFIED_PART 'TRUE' 
PRP PARENT_PART_TYPE 'TP_PIONT' 
PRP PARENT_PPT 'TP_PIONT' 
PRP PARENT_PPT_PART 'TP_PIONT-TP010CT020B030_PTH' 
PRP PART_NAME 'TP_PIONT' 
TOP 0 3.065 1.695 0.0 N 239 2 1
#
# CMP 8
CMP 11 2.29582 0.48918 0.0 N TP48 ??? ;0=2
PRP SCH_MODIFIED_PART 'TRUE' 
PRP PARENT_PART_TYPE 'TP_PIONT' 
PRP PARENT_PPT 'TP_PIONT' 
PRP PARENT_PPT_PART 'TP_PIONT-TP010CT020B030_PTH' 
PRP PART_NAME 'TP_PIONT' 
TOP 0 2.29582 0.48918 0.0 N 184 4 1
#
# CMP 9
CMP 11 3.746 1.782 0.0 N TP47 ??? ;0=2
PRP SCH_MODIFIED_PART 'TRUE' 
PRP PARENT_PART_TYPE 'TP_PIONT' 
PRP PARENT_PPT 'TP_PIONT' 
PRP PARENT_PPT_PART 'TP_PIONT-TP010CT020B030_PTH' 
PRP PART_NAME 'TP_PIONT' 
TOP 0 3.746 1.782 0.0 N 317 1 1
#
# CMP 10
CMP 13 4.06878 1.4891 0.0 N R197 ??? ;0=1,1=0.016000
PRP SIGNAL_MODEL 'RESISTOR-G155-11000-01_100OHM_A' 
PRP ALT_SYMBOLS '(SMC_0402R_C_H016)' 
PRP PARENT_PART_TYPE 'RESISTOR' 
PRP PARENT_PPT 'RESISTOR' 
PRP PARENT_PPT_PART 'RESISTOR-G155-11000-01,100OHM,1%' 
PRP PART_NAME 'RESISTOR' 
TOP 0 4.08847 1.4891 0.0 N 51 2 1
TOP 1 4.04909 1.4891 0.0 N 53 2 2
#
# CMP 11
CMP 13 4.06878 1.68595 0.0 N R198 ??? ;0=1,1=0.016000
PRP SIGNAL_MODEL 'RESISTOR-G155-11000-01_100OHM_A' 
PRP ALT_SYMBOLS '(SMC_0402R_C_H016)' 
PRP PARENT_PART_TYPE 'RESISTOR' 
PRP PARENT_PPT 'RESISTOR' 
PRP PARENT_PPT_PART 'RESISTOR-G155-11000-01,100OHM,1%' 
PRP PART_NAME 'RESISTOR' 
TOP 0 4.08847 1.68595 0.0 N 25 1 1
TOP 1 4.04909 1.68595 0.0 N 35 1 2
#
# CMP 12
CMP 13 4.69871 2.07965 180.0 N R503 ??? ;0=1,1=0.016000
PRP SIGNAL_MODEL 'RESISTOR-G155-100R0-J0_0OHM_-' 
PRP ALT_SYMBOLS '(SMC_0402R_C_H016)' 
PRP PARENT_PART_TYPE 'RESISTOR' 
PRP PARENT_PPT 'RESISTOR' 
PRP PARENT_PPT_PART 'RESISTOR-G155-14701-01,4.7KOHM,1%' 
PRP PART_NAME 'RESISTOR' 
TOP 0 4.67902 2.07965 180.0 N 438 2 1
TOP 1 4.7184 2.07965 180.0 N 2 471 2
#
# CMP 13
CMP 13 4.71839 2.13871 270.0 N R504 ??? ;0=1,1=0.016000
PRP SIGNAL_MODEL 'RESISTOR-G155-100R0-J0_0OHM_-' 
PRP ALT_SYMBOLS '(SMC_0402R_C_H016)' 
PRP PARENT_PART_TYPE 'RESISTOR' 
PRP PARENT_PPT 'RESISTOR' 
PRP PARENT_PPT_PART 'RESISTOR-G155-14701-01,4.7KOHM,1%' 
PRP PART_NAME 'RESISTOR' 
TOP 0 4.71839 2.11902 270.0 N 436 2 1
TOP 1 4.71839 2.1584 270.0 N 2 472 2
#
# CMP 14
CMP 13 4.6987 1.68595 0.0 N R500 ??? ;0=1,1=0.016000
PRP SIGNAL_MODEL 'RESISTOR-G155-100R0-J0_0OHM_-' 
PRP ALT_SYMBOLS '(SMC_0402R_C_H016)' 
PRP PARENT_PART_TYPE 'RESISTOR' 
PRP PARENT_PPT 'RESISTOR' 
PRP PARENT_PPT_PART 'RESISTOR-G155-14701-01,4.7KOHM,1%' 
PRP PART_NAME 'RESISTOR' 
TOP 0 4.71839 1.68595 0.0 N 2 473 1
TOP 1 4.67901 1.68595 0.0 N 430 2 2
#
# CMP 15
CMP 13 4.67902 1.86312 270.0 N R271 ??? ;0=1,1=0.016000
PRP HARD_LOCATION 'YES' 
PRP SIGNAL_MODEL 'RESISTOR-G155-100R0-J0_0OHM_-' 
PRP ALT_SYMBOLS '(SMC_0402R_C_H016)' 
PRP PARENT_PART_TYPE 'RESISTOR' 
PRP PARENT_PPT 'RESISTOR' 
PRP PARENT_PPT_PART 'RESISTOR-G155-14701-01,4.7KOHM,1%' 
PRP PART_NAME 'RESISTOR' 
TOP 0 4.67902 1.84343 270.0 N 2 474 1
TOP 1 4.67902 1.88281 270.0 N 261 1 2
#
# CMP 16
CMP 13 4.5806 1.8828 180.0 N R270 ??? ;0=1,1=0.016000
PRP SIGNAL_MODEL 'RESISTOR-G155-100R0-J0_0OHM_-' 
PRP ALT_SYMBOLS '(SMC_0402R_C_H016)' 
PRP PARENT_PART_TYPE 'RESISTOR' 
PRP PARENT_PPT 'RESISTOR' 
PRP PARENT_PPT_PART 'RESISTOR-G155-14701-01,4.7KOHM,1%' 
PRP PART_NAME 'RESISTOR' 
TOP 0 4.56091 1.8828 180.0 N 2 475 1
TOP 1 4.60029 1.8828 180.0 N 263 2 2
#
# CMP 17
CMP 13 4.58059 1.84343 0.0 N R502 ??? ;0=1,1=0.016000
PRP ALT_SYMBOLS '(SMC_0402R_C_H016)' 
PRP PARENT_PART_TYPE 'RESISTOR' 
PRP PARENT_PPT 'RESISTOR' 
PRP PARENT_PPT_PART 'RESISTOR-G155-12201-01,2.2KOHM,1%' 
PRP PART_NAME 'RESISTOR' 
TOP 0 4.60028 1.84343 0.0 N 1 136 1
TOP 1 4.5609 1.84343 0.0 N 517 1 2
#
# CMP 18
CMP 13 4.50186 1.44973 180.0 N R278 ??? ;0=1,1=0.016000
PRP SIGNAL_MODEL 'RESISTOR-G155-11000-01_100OHM_A' 
PRP ALT_SYMBOLS '(SMC_0402R_C_H016)' 
PRP PARENT_PART_TYPE 'RESISTOR' 
PRP PARENT_PPT 'RESISTOR' 
PRP PARENT_PPT_PART 'RESISTOR-G155-11000-01,100OHM,1%' 
PRP PART_NAME 'RESISTOR' 
TOP 0 4.48217 1.44973 180.0 N 47 3 1
TOP 1 4.52155 1.44973 180.0 N 49 3 2
#
# CMP 19
CMP 13 4.61996 1.29224 180.0 N R275 ??? ;0=1,1=0.016000
PRP SIGNAL_MODEL 'RESISTOR-G155-11000-01_100OHM_A' 
PRP ALT_SYMBOLS '(SMC_0402R_C_H016)' 
PRP PARENT_PART_TYPE 'RESISTOR' 
PRP PARENT_PPT 'RESISTOR' 
PRP PARENT_PPT_PART 'RESISTOR-G155-11000-01,100OHM,1%' 
PRP PART_NAME 'RESISTOR' 
TOP 0 4.60027 1.29224 180.0 N 357 3 1
TOP 1 4.63965 1.29224 180.0 N 358 3 2
#
# CMP 20
CMP 13 4.48217 1.82374 270.0 N R437 ??? ;0=1,1=0.016000
PRP ALT_SYMBOLS '(SMC_0402R_C_H016)' 
PRP PARENT_PART_TYPE 'RESISTOR' 
PRP PARENT_PPT 'RESISTOR' 
PRP PARENT_PPT_PART 'RESISTOR-G155-11502-01,15KOHM,1%' 
PRP PART_NAME 'RESISTOR' 
TOP 0 4.48217 1.80405 270.0 N 2 476 1
TOP 1 4.48217 1.84343 270.0 N 254 2 2
#
# CMP 21
CMP 13 4.4428 1.82374 270.0 N R436 ??? ;0=1,1=0.016000
PRP ALT_SYMBOLS '(SMC_0402R_C_H016)' 
PRP PARENT_PART_TYPE 'RESISTOR' 
PRP PARENT_PPT 'RESISTOR' 
PRP PARENT_PPT_PART 'RESISTOR-G155-11502-01,15KOHM,1%' 
PRP PART_NAME 'RESISTOR' 
TOP 0 4.4428 1.80405 270.0 N 2 477 1
TOP 1 4.4428 1.84343 270.0 N 256 2 2
#
# CMP 22
CMP 19 4.00973 1.54816 270.0 N C218 ??? ;0=1,1=0.022000
PRP SIGNAL_MODEL 'DEFAULT_CAPACITOR_100000pF_1_2' 
PRP ALT_SYMBOLS '(SMC_0402R_C_H022,C0402_BGA,C0402-0P8MM-45DG,C0402-1MM-TRIANGLE-S0)' 
PRP PARENT_PART_TYPE 'CAPACITOR' 
PRP PARENT_PPT 'CAPACITOR' 
PRP PARENT_PPT_PART 'CAPACITOR-G105-0B104-CK,0.1UF,10%' 
PRP PART_NAME 'CAPACITOR' 
TOP 0 4.00973 1.52847 270.0 N 7 7 1
TOP 1 4.00973 1.56785 270.0 N 2 478 2
#
# CMP 23
CMP 19 4.10816 1.56784 180.0 N C118 ??? ;0=1,1=0.022000
PRP SIGNAL_MODEL 'DEFAULT_CAPACITOR_100000pF_1_2' 
PRP ALT_SYMBOLS '(SMC_0402R_C_H022,C0402_BGA,C0402-0P8MM-45DG,C0402-1MM-TRIANGLE-S0)' 
PRP PARENT_PART_TYPE 'CAPACITOR' 
PRP PARENT_PPT 'CAPACITOR' 
PRP PARENT_PPT_PART 'CAPACITOR-G105-0B104-CK,0.1UF,10%' 
PRP PART_NAME 'CAPACITOR' 
TOP 0 4.08847 1.56784 180.0 N 7 8 1
TOP 1 4.12785 1.56784 180.0 N 2 479 2
#
# CMP 24
CMP 19 4.0491 1.6269 270.0 N C105 ??? ;0=1,1=0.022000
PRP SIGNAL_MODEL 'DEFAULT_CAPACITOR_100000pF_1_2' 
PRP ALT_SYMBOLS '(SMC_0402R_C_H022,C0402_BGA,C0402-0P8MM-45DG,C0402-1MM-TRIANGLE-S0)' 
PRP PARENT_PART_TYPE 'CAPACITOR' 
PRP PARENT_PPT 'CAPACITOR' 
PRP PARENT_PPT_PART 'CAPACITOR-G105-0B104-CK,0.1UF,10%' 
PRP PART_NAME 'CAPACITOR' 
TOP 0 4.0491 1.60721 270.0 N 7 9 1
TOP 1 4.0491 1.64659 270.0 N 2 480 2
#
# CMP 25
CMP 19 4.10816 1.60721 180.0 N C111 ??? ;0=1,1=0.022000
PRP SIGNAL_MODEL 'DEFAULT_CAPACITOR_100000pF_1_2' 
PRP ALT_SYMBOLS '(SMC_0402R_C_H022,C0402_BGA,C0402-0P8MM-45DG,C0402-1MM-TRIANGLE-S0)' 
PRP PARENT_PART_TYPE 'CAPACITOR' 
PRP PARENT_PPT 'CAPACITOR' 
PRP PARENT_PPT_PART 'CAPACITOR-G105-0B104-CK,0.1UF,10%' 
PRP PART_NAME 'CAPACITOR' 
TOP 0 4.08847 1.60721 180.0 N 7 10 1
TOP 1 4.12785 1.60721 180.0 N 2 481 2
#
# CMP 26
CMP 19 4.00973 1.46941 90.0 N C124 ??? ;0=1,1=0.022000
PRP SIGNAL_MODEL 'DEFAULT_CAPACITOR_100000pF_1_2' 
PRP ALT_SYMBOLS '(SMC_0402R_C_H022,C0402_BGA,C0402-0P8MM-45DG,C0402-1MM-TRIANGLE-S0)' 
PRP PARENT_PART_TYPE 'CAPACITOR' 
PRP PARENT_PPT 'CAPACITOR' 
PRP PARENT_PPT_PART 'CAPACITOR-G105-0B104-CK,0.1UF,10%' 
PRP PART_NAME 'CAPACITOR' 
TOP 0 4.00973 1.4891 90.0 N 7 11 1
TOP 1 4.00973 1.44972 90.0 N 2 482 2
#
# CMP 27
CMP 19 4.0491 1.39067 270.0 N C213 ??? ;0=1,1=0.022000
PRP SIGNAL_MODEL 'DEFAULT_CAPACITOR_100000pF_1_2' 
PRP ALT_SYMBOLS '(SMC_0402R_C_H022,C0402_BGA,C0402-0P8MM-45DG,C0402-1MM-TRIANGLE-S0)' 
PRP PARENT_PART_TYPE 'CAPACITOR' 
PRP PARENT_PPT 'CAPACITOR' 
PRP PARENT_PPT_PART 'CAPACITOR-G105-0B104-CK,0.1UF,10%' 
PRP PART_NAME 'CAPACITOR' 
TOP 0 4.0491 1.37098 270.0 N 9 22 1
TOP 1 4.0491 1.41036 270.0 N 2 483 2
#
# CMP 28
CMP 19 3.95067 1.84343 180.0 N C203 ??? ;0=1,1=0.022000
PRP SIGNAL_MODEL 'DEFAULT_CAPACITOR_100000pF_1_2' 
PRP ALT_SYMBOLS '(SMC_0402R_C_H022,C0402_BGA,C0402-0P8MM-45DG,C0402-1MM-TRIANGLE-S0)' 
PRP PARENT_PART_TYPE 'CAPACITOR' 
PRP PARENT_PPT 'CAPACITOR' 
PRP PARENT_PPT_PART 'CAPACITOR-G105-0B104-CK,0.1UF,10%' 
PRP PART_NAME 'CAPACITOR' 
TOP 0 3.93098 1.84343 180.0 N 1 137 1
TOP 1 3.97036 1.84343 180.0 N 2 484 2
#
# CMP 29
CMP 19 4.12784 1.66626 90.0 N C222 ??? ;0=1,1=0.022000
PRP SIGNAL_MODEL 'DEFAULT_CAPACITOR_100000pF_1_2' 
PRP REUSE_ID '1' 
PRP ALT_SYMBOLS '(SMC_0402R_C_H022,C0402_BGA,C0402-0P8MM-45DG,C0402-1MM-TRIANGLE-S0)' 
PRP PARENT_PART_TYPE 'CAPACITOR' 
PRP PARENT_PPT 'CAPACITOR' 
PRP PARENT_PPT_PART 'CAPACITOR-G105-0B104-CK,0.1UF,10%' 
PRP PART_NAME 'CAPACITOR' 
TOP 0 4.12784 1.68595 90.0 N 10 22 1
TOP 1 4.12784 1.64657 90.0 N 2 485 2
#
# CMP 30
CMP 19 4.02941 1.80406 0.0 N C106 ??? ;0=1,1=0.022000
PRP SIGNAL_MODEL 'DEFAULT_CAPACITOR_100000pF_1_2' 
PRP ALT_SYMBOLS '(SMC_0402R_C_H022,C0402_BGA,C0402-0P8MM-45DG,C0402-1MM-TRIANGLE-S0)' 
PRP PARENT_PART_TYPE 'CAPACITOR' 
PRP PARENT_PPT 'CAPACITOR' 
PRP PARENT_PPT_PART 'CAPACITOR-G105-0B104-CK,0.1UF,10%' 
PRP PART_NAME 'CAPACITOR' 
TOP 0 4.0491 1.80406 0.0 N 8 8 1
TOP 1 4.00972 1.80406 0.0 N 2 486 2
#
# CMP 31
CMP 19 3.95067 1.64658 180.0 N C209 ??? ;0=1,1=0.022000
PRP SIGNAL_MODEL 'DEFAULT_CAPACITOR_100000pF_1_2' 
PRP ALT_SYMBOLS '(SMC_0402R_C_H022,C0402_BGA,C0402-0P8MM-45DG,C0402-1MM-TRIANGLE-S0)' 
PRP PARENT_PART_TYPE 'CAPACITOR' 
PRP PARENT_PPT 'CAPACITOR' 
PRP PARENT_PPT_PART 'CAPACITOR-G105-0B104-CK,0.1UF,10%' 
PRP PART_NAME 'CAPACITOR' 
TOP 0 3.93098 1.64658 180.0 N 6 6 1
TOP 1 3.97036 1.64658 180.0 N 2 487 2
#
# CMP 32
CMP 19 3.93098 1.74501 270.0 N C205 ??? ;0=1,1=0.022000
PRP SIGNAL_MODEL 'DEFAULT_CAPACITOR_100000pF_1_2' 
PRP ALT_SYMBOLS '(SMC_0402R_C_H022,C0402_BGA,C0402-0P8MM-45DG,C0402-1MM-TRIANGLE-S0)' 
PRP PARENT_PART_TYPE 'CAPACITOR' 
PRP PARENT_PPT 'CAPACITOR' 
PRP PARENT_PPT_PART 'CAPACITOR-G105-0B104-CK,0.1UF,10%' 
PRP PART_NAME 'CAPACITOR' 
TOP 0 3.93098 1.72532 270.0 N 6 7 1
TOP 1 3.93098 1.7647 270.0 N 2 488 2
#
# CMP 33
CMP 19 3.91129 1.4891 0.0 N C110 ??? ;0=1,1=0.022000
PRP SIGNAL_MODEL 'DEFAULT_CAPACITOR_100000pF_1_2' 
PRP ALT_SYMBOLS '(SMC_0402R_C_H022,C0402_BGA,C0402-0P8MM-45DG,C0402-1MM-TRIANGLE-S0)' 
PRP PARENT_PART_TYPE 'CAPACITOR' 
PRP PARENT_PPT 'CAPACITOR' 
PRP PARENT_PPT_PART 'CAPACITOR-G105-0B104-CK,0.1UF,10%' 
PRP PART_NAME 'CAPACITOR' 
TOP 0 3.93098 1.4891 0.0 N 6 8 1
TOP 1 3.8916 1.4891 0.0 N 2 489 2
#
# CMP 34
CMP 19 3.97035 1.46942 270.0 N C217 ??? ;0=1,1=0.022000
PRP SIGNAL_MODEL 'DEFAULT_CAPACITOR_100000pF_1_2' 
PRP ALT_SYMBOLS '(SMC_0402R_C_H022,C0402_BGA,C0402-0P8MM-45DG,C0402-1MM-TRIANGLE-S0)' 
PRP PARENT_PART_TYPE 'CAPACITOR' 
PRP PARENT_PPT 'CAPACITOR' 
PRP PARENT_PPT_PART 'CAPACITOR-G105-0B104-CK,0.1UF,10%' 
PRP PART_NAME 'CAPACITOR' 
TOP 0 3.97035 1.44973 270.0 N 6 9 1
TOP 1 3.97035 1.48911 270.0 N 2 490 2
#
# CMP 35
CMP 19 4.73808 2.00091 180.0 N C103 ??? ;0=1,1=0.022000
PRP SIGNAL_MODEL 'DEFAULT_CAPACITOR_100000pF_1_2' 
PRP ALT_SYMBOLS '(SMC_0402R_C_H022,C0402_BGA,C0402-0P8MM-45DG,C0402-1MM-TRIANGLE-S0)' 
PRP PARENT_PART_TYPE 'CAPACITOR' 
PRP PARENT_PPT 'CAPACITOR' 
PRP PARENT_PPT_PART 'CAPACITOR-G105-0B104-CK,0.1UF,10%' 
PRP PART_NAME 'CAPACITOR' 
TOP 0 4.71839 2.00091 180.0 N 1 138 1
TOP 1 4.75777 2.00091 180.0 N 2 491 2
#
# CMP 36
CMP 19 4.16721 1.58752 90.0 N C121 ??? ;0=1,1=0.022000
PRP SIGNAL_MODEL 'DEFAULT_CAPACITOR_100000pF_1_2' 
PRP REUSE_ID '11' 
PRP ALT_SYMBOLS '(SMC_0402R_C_H022,C0402_BGA,C0402-0P8MM-45DG,C0402-1MM-TRIANGLE-S0)' 
PRP PARENT_PART_TYPE 'CAPACITOR' 
PRP PARENT_PPT 'CAPACITOR' 
PRP PARENT_PPT_PART 'CAPACITOR-G105-0B104-CK,0.1UF,10%' 
PRP PART_NAME 'CAPACITOR' 
TOP 0 4.16721 1.60721 90.0 N 10 23 1
TOP 1 4.16721 1.56783 90.0 N 2 492 2
#
# CMP 37
CMP 19 4.22627 1.56784 180.0 N C141 ??? ;0=1,1=0.022000
PRP SIGNAL_MODEL 'DEFAULT_CAPACITOR_100000pF_1_2' 
PRP REUSE_ID '7' 
PRP ALT_SYMBOLS '(SMC_0402R_C_H022,C0402_BGA,C0402-0P8MM-45DG,C0402-1MM-TRIANGLE-S0)' 
PRP PARENT_PART_TYPE 'CAPACITOR' 
PRP PARENT_PPT 'CAPACITOR' 
PRP PARENT_PPT_PART 'CAPACITOR-G105-0B104-CK,0.1UF,10%' 
PRP PART_NAME 'CAPACITOR' 
TOP 0 4.20658 1.56784 180.0 N 10 24 1
TOP 1 4.24596 1.56784 180.0 N 2 493 2
#
# CMP 38
CMP 19 4.22626 1.68595 0.0 N C109 ??? ;0=1,1=0.022000
PRP SIGNAL_MODEL 'DEFAULT_CAPACITOR_100000pF_1_2' 
PRP REUSE_ID '2' 
PRP ALT_SYMBOLS '(SMC_0402R_C_H022,C0402_BGA,C0402-0P8MM-45DG,C0402-1MM-TRIANGLE-S0)' 
PRP PARENT_PART_TYPE 'CAPACITOR' 
PRP PARENT_PPT 'CAPACITOR' 
PRP PARENT_PPT_PART 'CAPACITOR-G105-0B104-CK,0.1UF,10%' 
PRP PART_NAME 'CAPACITOR' 
TOP 0 4.24595 1.68595 0.0 N 10 25 1
TOP 1 4.20657 1.68595 0.0 N 2 494 2
#
# CMP 39
CMP 19 4.16721 1.66627 270.0 N C156 ??? ;0=1,1=0.022000
PRP SIGNAL_MODEL 'DEFAULT_CAPACITOR_100000pF_1_2' 
PRP REUSE_ID '10' 
PRP ALT_SYMBOLS '(SMC_0402R_C_H022,C0402_BGA,C0402-0P8MM-45DG,C0402-1MM-TRIANGLE-S0)' 
PRP PARENT_PART_TYPE 'CAPACITOR' 
PRP PARENT_PPT 'CAPACITOR' 
PRP PARENT_PPT_PART 'CAPACITOR-G105-0B104-CK,0.1UF,10%' 
PRP PART_NAME 'CAPACITOR' 
TOP 0 4.16721 1.64658 270.0 N 10 26 1
TOP 1 4.16721 1.68596 270.0 N 2 495 2
#
# CMP 40
CMP 19 4.24595 1.6269 270.0 N C166 ??? ;0=1,1=0.022000
PRP SIGNAL_MODEL 'DEFAULT_CAPACITOR_100000pF_1_2' 
PRP REUSE_ID '9' 
PRP ALT_SYMBOLS '(SMC_0402R_C_H022,C0402_BGA,C0402-0P8MM-45DG,C0402-1MM-TRIANGLE-S0)' 
PRP PARENT_PART_TYPE 'CAPACITOR' 
PRP PARENT_PPT 'CAPACITOR' 
PRP PARENT_PPT_PART 'CAPACITOR-G105-0B104-CK,0.1UF,10%' 
PRP PART_NAME 'CAPACITOR' 
TOP 0 4.24595 1.60721 270.0 N 10 27 1
TOP 1 4.24595 1.64659 270.0 N 2 496 2
#
# CMP 41
CMP 19 4.20658 1.50878 90.0 N C169 ??? ;0=1,1=0.022000
PRP SIGNAL_MODEL 'DEFAULT_CAPACITOR_100000pF_1_2' 
PRP REUSE_ID '8' 
PRP ALT_SYMBOLS '(SMC_0402R_C_H022,C0402_BGA,C0402-0P8MM-45DG,C0402-1MM-TRIANGLE-S0)' 
PRP PARENT_PART_TYPE 'CAPACITOR' 
PRP PARENT_PPT 'CAPACITOR' 
PRP PARENT_PPT_PART 'CAPACITOR-G105-0B104-CK,0.1UF,10%' 
PRP PART_NAME 'CAPACITOR' 
TOP 0 4.20658 1.52847 90.0 N 10 28 1
TOP 1 4.20658 1.48909 90.0 N 2 497 2
#
# CMP 42
CMP 19 4.20658 1.43004 270.0 N C208 ??? ;0=1,1=0.022000
PRP SIGNAL_MODEL 'DEFAULT_CAPACITOR_100000pF_1_2' 
PRP ALT_SYMBOLS '(SMC_0402R_C_H022,C0402_BGA,C0402-0P8MM-45DG,C0402-1MM-TRIANGLE-S0)' 
PRP PARENT_PART_TYPE 'CAPACITOR' 
PRP PARENT_PPT 'CAPACITOR' 
PRP PARENT_PPT_PART 'CAPACITOR-G105-0B104-CK,0.1UF,10%' 
PRP PART_NAME 'CAPACITOR' 
TOP 0 4.20658 1.41035 270.0 N 9 23 1
TOP 1 4.20658 1.44973 270.0 N 2 498 2
#
# CMP 43
CMP 19 4.14752 1.52847 0.0 N C204 ??? ;0=1,1=0.022000
PRP SIGNAL_MODEL 'DEFAULT_CAPACITOR_100000pF_1_2' 
PRP ALT_SYMBOLS '(SMC_0402R_C_H022,C0402_BGA,C0402-0P8MM-45DG,C0402-1MM-TRIANGLE-S0)' 
PRP PARENT_PART_TYPE 'CAPACITOR' 
PRP PARENT_PPT 'CAPACITOR' 
PRP PARENT_PPT_PART 'CAPACITOR-G105-0B104-CK,0.1UF,10%' 
PRP PART_NAME 'CAPACITOR' 
TOP 0 4.16721 1.52847 0.0 N 9 24 1
TOP 1 4.12783 1.52847 0.0 N 2 499 2
#
# CMP 44
CMP 19 4.14752 1.4891 0.0 N C146 ??? ;0=1,1=0.022000
PRP SIGNAL_MODEL 'DEFAULT_CAPACITOR_100000pF_1_2' 
PRP ALT_SYMBOLS '(SMC_0402R_C_H022,C0402_BGA,C0402-0P8MM-45DG,C0402-1MM-TRIANGLE-S0)' 
PRP PARENT_PART_TYPE 'CAPACITOR' 
PRP PARENT_PPT 'CAPACITOR' 
PRP PARENT_PPT_PART 'CAPACITOR-G105-0B104-CK,0.1UF,10%' 
PRP PART_NAME 'CAPACITOR' 
TOP 0 4.16721 1.4891 0.0 N 9 25 1
TOP 1 4.12783 1.4891 0.0 N 2 500 2
#
# CMP 45
CMP 19 4.309 1.465 270.0 N C142 ??? ;0=1,1=0.022000
PRP SIGNAL_MODEL 'DEFAULT_CAPACITOR_100000pF_1_2' 
PRP ALT_SYMBOLS '(SMC_0402R_C_H022,C0402_BGA,C0402-0P8MM-45DG,C0402-1MM-TRIANGLE-S0)' 
PRP PARENT_PART_TYPE 'CAPACITOR' 
PRP PARENT_PPT 'CAPACITOR' 
PRP PARENT_PPT_PART 'CAPACITOR-G105-0B104-CK,0.1UF,10%' 
PRP PART_NAME 'CAPACITOR' 
TOP 0 4.309 1.44531 270.0 N 9 26 1
TOP 1 4.309 1.48469 270.0 N 2 501 2
#
# CMP 46
CMP 19 4.36406 1.54815 90.0 N C214 ??? ;0=1,1=0.022000
PRP SIGNAL_MODEL 'DEFAULT_CAPACITOR_100000pF_1_2' 
PRP REUSE_ID '3' 
PRP ALT_SYMBOLS '(SMC_0402R_C_H022,C0402_BGA,C0402-0P8MM-45DG,C0402-1MM-TRIANGLE-S0)' 
PRP PARENT_PART_TYPE 'CAPACITOR' 
PRP PARENT_PPT 'CAPACITOR' 
PRP PARENT_PPT_PART 'CAPACITOR-G105-0B104-CK,0.1UF,10%' 
PRP PART_NAME 'CAPACITOR' 
TOP 0 4.36406 1.56784 90.0 N 10 29 1
TOP 1 4.36406 1.52846 90.0 N 2 502 2
#
# CMP 47
CMP 19 4.36406 1.46942 270.0 N C220 ??? ;0=1,1=0.022000
PRP SIGNAL_MODEL 'DEFAULT_CAPACITOR_100000pF_1_2' 
PRP ALT_SYMBOLS '(SMC_0402R_C_H022,C0402_BGA,C0402-0P8MM-45DG,C0402-1MM-TRIANGLE-S0)' 
PRP PARENT_PART_TYPE 'CAPACITOR' 
PRP PARENT_PPT 'CAPACITOR' 
PRP PARENT_PPT_PART 'CAPACITOR-G105-0B104-CK,0.1UF,10%' 
PRP PART_NAME 'CAPACITOR' 
TOP 0 4.36406 1.44973 270.0 N 9 27 1
TOP 1 4.36406 1.48911 270.0 N 2 503 2
#
# CMP 48
CMP 19 3.91129 2.15839 0.0 N C216 ??? ;0=1,1=0.022000
PRP SIGNAL_MODEL 'DEFAULT_CAPACITOR_100000pF_1_2' 
PRP ALT_SYMBOLS '(SMC_0402R_C_H022,C0402_BGA,C0402-0P8MM-45DG,C0402-1MM-TRIANGLE-S0)' 
PRP PARENT_PART_TYPE 'CAPACITOR' 
PRP PARENT_PPT 'CAPACITOR' 
PRP PARENT_PPT_PART 'CAPACITOR-G105-0B104-CK,0.1UF,10%' 
PRP PART_NAME 'CAPACITOR' 
TOP 0 3.93098 2.15839 0.0 N 1 139 1
TOP 1 3.8916 2.15839 0.0 N 2 504 2
#
# CMP 49
CMP 19 3.93098 2.09933 90.0 N C140 ??? ;0=1,1=0.022000
PRP SIGNAL_MODEL 'DEFAULT_CAPACITOR_100000pF_1_2' 
PRP ALT_SYMBOLS '(SMC_0402R_C_H022,C0402_BGA,C0402-0P8MM-45DG,C0402-1MM-TRIANGLE-S0)' 
PRP PARENT_PART_TYPE 'CAPACITOR' 
PRP PARENT_PPT 'CAPACITOR' 
PRP PARENT_PPT_PART 'CAPACITOR-G105-0B104-CK,0.1UF,10%' 
PRP PART_NAME 'CAPACITOR' 
TOP 0 3.93098 2.11902 90.0 N 1 140 1
TOP 1 3.93098 2.07964 90.0 N 2 505 2
#
# CMP 50
CMP 19 3.95066 2.04028 0.0 N C157 ??? ;0=1,1=0.022000
PRP SIGNAL_MODEL 'DEFAULT_CAPACITOR_100000pF_1_2' 
PRP ALT_SYMBOLS '(SMC_0402R_C_H022,C0402_BGA,C0402-0P8MM-45DG,C0402-1MM-TRIANGLE-S0)' 
PRP PARENT_PART_TYPE 'CAPACITOR' 
PRP PARENT_PPT 'CAPACITOR' 
PRP PARENT_PPT_PART 'CAPACITOR-G105-0B104-CK,0.1UF,10%' 
PRP PART_NAME 'CAPACITOR' 
TOP 0 3.97035 2.04028 0.0 N 1 141 1
TOP 1 3.93097 2.04028 0.0 N 2 506 2
#
# CMP 51
CMP 19 3.95067 2.00091 0.0 N C211 ??? ;0=1,1=0.022000
PRP SIGNAL_MODEL 'DEFAULT_CAPACITOR_100000pF_1_2' 
PRP ALT_SYMBOLS '(SMC_0402R_C_H022,C0402_BGA,C0402-0P8MM-45DG,C0402-1MM-TRIANGLE-S0)' 
PRP PARENT_PART_TYPE 'CAPACITOR' 
PRP PARENT_PPT 'CAPACITOR' 
PRP PARENT_PPT_PART 'CAPACITOR-G105-0B104-CK,0.1UF,10%' 
PRP PART_NAME 'CAPACITOR' 
TOP 0 3.97036 2.00091 0.0 N 1 142 1
TOP 1 3.93098 2.00091 0.0 N 2 507 2
#
# CMP 52
CMP 19 4.4428 1.43004 90.0 N C135 ??? ;0=1,1=0.022000
PRP SIGNAL_MODEL 'DEFAULT_CAPACITOR_100000pF_1_2' 
PRP ALT_SYMBOLS '(SMC_0402R_C_H022,C0402_BGA,C0402-0P8MM-45DG,C0402-1MM-TRIANGLE-S0)' 
PRP PARENT_PART_TYPE 'CAPACITOR' 
PRP PARENT_PPT 'CAPACITOR' 
PRP PARENT_PPT_PART 'CAPACITOR-G105-0B104-CK,0.1UF,10%' 
PRP PART_NAME 'CAPACITOR' 
TOP 0 4.4428 1.44973 90.0 N 9 28 1
TOP 1 4.4428 1.41035 90.0 N 2 508 2
#
# CMP 53
CMP 19 4.40343 1.3513 270.0 N C108 ??? ;0=1,1=0.022000
PRP SIGNAL_MODEL 'DEFAULT_CAPACITOR_100000pF_1_2' 
PRP ALT_SYMBOLS '(SMC_0402R_C_H022,C0402_BGA,C0402-0P8MM-45DG,C0402-1MM-TRIANGLE-S0)' 
PRP PARENT_PART_TYPE 'CAPACITOR' 
PRP PARENT_PPT 'CAPACITOR' 
PRP PARENT_PPT_PART 'CAPACITOR-G105-0B104-CK,0.1UF,10%' 
PRP PART_NAME 'CAPACITOR' 
TOP 0 4.40343 1.33161 270.0 N 9 29 1
TOP 1 4.40343 1.37099 270.0 N 2 509 2
#
# CMP 54
CMP 19 4.14753 2.04028 180.0 N C112 ??? ;0=1,1=0.022000
PRP SIGNAL_MODEL 'DEFAULT_CAPACITOR_100000pF_1_2' 
PRP ALT_SYMBOLS '(SMC_0402R_C_H022,C0402_BGA,C0402-0P8MM-45DG,C0402-1MM-TRIANGLE-S0)' 
PRP PARENT_PART_TYPE 'CAPACITOR' 
PRP PARENT_PPT 'CAPACITOR' 
PRP PARENT_PPT_PART 'CAPACITOR-G105-0B104-CK,0.1UF,10%' 
PRP PART_NAME 'CAPACITOR' 
TOP 0 4.12784 2.04028 180.0 N 1 143 1
TOP 1 4.16722 2.04028 180.0 N 2 510 2
#
# CMP 55
CMP 19 4.10815 1.96154 0.0 N C153 ??? ;0=1,1=0.022000
PRP SIGNAL_MODEL 'DEFAULT_CAPACITOR_100000pF_1_2' 
PRP ALT_SYMBOLS '(SMC_0402R_C_H022,C0402_BGA,C0402-0P8MM-45DG,C0402-1MM-TRIANGLE-S0)' 
PRP PARENT_PART_TYPE 'CAPACITOR' 
PRP PARENT_PPT 'CAPACITOR' 
PRP PARENT_PPT_PART 'CAPACITOR-G105-0B104-CK,0.1UF,10%' 
PRP PART_NAME 'CAPACITOR' 
TOP 0 4.12784 1.96154 0.0 N 1 144 1
TOP 1 4.08846 1.96154 0.0 N 2 511 2
#
# CMP 56
CMP 19 4.16721 1.98123 270.0 N C119 ??? ;0=1,1=0.022000
PRP SIGNAL_MODEL 'DEFAULT_CAPACITOR_100000pF_1_2' 
PRP ALT_SYMBOLS '(SMC_0402R_C_H022,C0402_BGA,C0402-0P8MM-45DG,C0402-1MM-TRIANGLE-S0)' 
PRP PARENT_PART_TYPE 'CAPACITOR' 
PRP PARENT_PPT 'CAPACITOR' 
PRP PARENT_PPT_PART 'CAPACITOR-G105-0B104-CK,0.1UF,10%' 
PRP PART_NAME 'CAPACITOR' 
TOP 0 4.16721 1.96154 270.0 N 1 145 1
TOP 1 4.16721 2.00092 270.0 N 2 512 2
#
# CMP 57
CMP 19 4.24595 2.13871 270.0 N C162 ??? ;0=1,1=0.022000
PRP SIGNAL_MODEL 'DEFAULT_CAPACITOR_100000pF_1_2' 
PRP ALT_SYMBOLS '(SMC_0402R_C_H022,C0402_BGA,C0402-0P8MM-45DG,C0402-1MM-TRIANGLE-S0)' 
PRP PARENT_PART_TYPE 'CAPACITOR' 
PRP PARENT_PPT 'CAPACITOR' 
PRP PARENT_PPT_PART 'CAPACITOR-G105-0B104-CK,0.1UF,10%' 
PRP PART_NAME 'CAPACITOR' 
TOP 0 4.24595 2.11902 270.0 N 1 146 1
TOP 1 4.24595 2.1584 270.0 N 2 513 2
#
# CMP 58
CMP 19 4.31006 1.91749 270.0 N C144 ??? ;0=1,1=0.022000
PRP SIGNAL_MODEL 'DEFAULT_CAPACITOR_100000pF_1_2' 
PRP ALT_SYMBOLS '(SMC_0402R_C_H022,C0402_BGA,C0402-0P8MM-45DG,C0402-1MM-TRIANGLE-S0)' 
PRP PARENT_PART_TYPE 'CAPACITOR' 
PRP PARENT_PPT 'CAPACITOR' 
PRP PARENT_PPT_PART 'CAPACITOR-G105-0B104-CK,0.1UF,10%' 
PRP PART_NAME 'CAPACITOR' 
TOP 0 4.31006 1.8978 270.0 N 1 147 1
TOP 1 4.31006 1.93718 270.0 N 2 514 2
#
# CMP 59
CMP 19 4.20658 1.86312 270.0 N C221 ??? ;0=1,1=0.022000
PRP SIGNAL_MODEL 'DEFAULT_CAPACITOR_100000pF_1_2' 
PRP ALT_SYMBOLS '(SMC_0402R_C_H022,C0402_BGA,C0402-0P8MM-45DG,C0402-1MM-TRIANGLE-S0)' 
PRP PARENT_PART_TYPE 'CAPACITOR' 
PRP PARENT_PPT 'CAPACITOR' 
PRP PARENT_PPT_PART 'CAPACITOR-G105-0B104-CK,0.1UF,10%' 
PRP PART_NAME 'CAPACITOR' 
TOP 0 4.20658 1.84343 270.0 N 1 148 1
TOP 1 4.20658 1.88281 270.0 N 2 515 2
#
# CMP 60
CMP 19 4.22626 1.80406 0.0 N C200 ??? ;0=1,1=0.022000
PRP SIGNAL_MODEL 'DEFAULT_CAPACITOR_100000pF_1_2' 
PRP ALT_SYMBOLS '(SMC_0402R_C_H022,C0402_BGA,C0402-0P8MM-45DG,C0402-1MM-TRIANGLE-S0)' 
PRP PARENT_PART_TYPE 'CAPACITOR' 
PRP PARENT_PPT 'CAPACITOR' 
PRP PARENT_PPT_PART 'CAPACITOR-G105-0B104-CK,0.1UF,10%' 
PRP PART_NAME 'CAPACITOR' 
TOP 0 4.24595 1.80406 0.0 N 8 9 1
TOP 1 4.20657 1.80406 0.0 N 2 516 2
#
# CMP 61
CMP 19 4.36406 1.6269 270.0 N C129 ??? ;0=1,1=0.022000
PRP SIGNAL_MODEL 'DEFAULT_CAPACITOR_100000pF_1_2' 
PRP REUSE_ID '14' 
PRP ALT_SYMBOLS '(SMC_0402R_C_H022,C0402_BGA,C0402-0P8MM-45DG,C0402-1MM-TRIANGLE-S0)' 
PRP PARENT_PART_TYPE 'CAPACITOR' 
PRP PARENT_PPT 'CAPACITOR' 
PRP PARENT_PPT_PART 'CAPACITOR-G105-0B104-CK,0.1UF,10%' 
PRP PART_NAME 'CAPACITOR' 
TOP 0 4.36406 1.60721 270.0 N 10 30 1
TOP 1 4.36406 1.64659 270.0 N 2 517 2
#
# CMP 62
CMP 19 4.38375 1.80406 180.0 N C206 ??? ;0=1,1=0.022000
PRP SIGNAL_MODEL 'DEFAULT_CAPACITOR_100000pF_1_2' 
PRP ALT_SYMBOLS '(SMC_0402R_C_H022,C0402_BGA,C0402-0P8MM-45DG,C0402-1MM-TRIANGLE-S0)' 
PRP PARENT_PART_TYPE 'CAPACITOR' 
PRP PARENT_PPT 'CAPACITOR' 
PRP PARENT_PPT_PART 'CAPACITOR-G105-0B104-CK,0.1UF,10%' 
PRP PART_NAME 'CAPACITOR' 
TOP 0 4.36406 1.80406 180.0 N 8 10 1
TOP 1 4.40344 1.80406 180.0 N 2 518 2
#
# CMP 63
CMP 19 4.52154 1.82375 270.0 N C107 ??? ;0=1,1=0.022000
PRP SIGNAL_MODEL 'DEFAULT_CAPACITOR_100000pF_1_2' 
PRP ALT_SYMBOLS '(SMC_0402R_C_H022,C0402_BGA,C0402-0P8MM-45DG,C0402-1MM-TRIANGLE-S0)' 
PRP PARENT_PART_TYPE 'CAPACITOR' 
PRP PARENT_PPT 'CAPACITOR' 
PRP PARENT_PPT_PART 'CAPACITOR-G105-0B104-CK,0.1UF,10%' 
PRP PART_NAME 'CAPACITOR' 
TOP 0 4.52154 1.80406 270.0 N 1 149 1
TOP 1 4.52154 1.84344 270.0 N 2 519 2
#
# CMP 64
CMP 19 4.65934 1.80406 180.0 N C139 ??? ;0=1,1=0.022000
PRP SIGNAL_MODEL 'DEFAULT_CAPACITOR_100000pF_1_2' 
PRP ALT_SYMBOLS '(SMC_0402R_C_H022,C0402_BGA,C0402-0P8MM-45DG,C0402-1MM-TRIANGLE-S0)' 
PRP PARENT_PART_TYPE 'CAPACITOR' 
PRP PARENT_PPT 'CAPACITOR' 
PRP PARENT_PPT_PART 'CAPACITOR-G105-0B104-CK,0.1UF,10%' 
PRP PART_NAME 'CAPACITOR' 
TOP 0 4.63965 1.80406 180.0 N 1 150 1
TOP 1 4.67903 1.80406 180.0 N 2 520 2
#
# CMP 65
CMP 19 4.61996 1.68595 0.0 N C210 ??? ;0=1,1=0.022000
PRP SIGNAL_MODEL 'DEFAULT_CAPACITOR_100000pF_1_2' 
PRP ALT_SYMBOLS '(SMC_0402R_C_H022,C0402_BGA,C0402-0P8MM-45DG,C0402-1MM-TRIANGLE-S0)' 
PRP PARENT_PART_TYPE 'CAPACITOR' 
PRP PARENT_PPT 'CAPACITOR' 
PRP PARENT_PPT_PART 'CAPACITOR-G105-0B104-CK,0.1UF,10%' 
PRP PART_NAME 'CAPACITOR' 
TOP 0 4.63965 1.68595 0.0 N 1 151 1
TOP 1 4.60027 1.68595 0.0 N 2 521 2
#
# CMP 66
CMP 19 4.65933 1.56784 0.0 N C151 ??? ;0=1,1=0.022000
PRP SIGNAL_MODEL 'DEFAULT_CAPACITOR_100000pF_1_2' 
PRP ALT_SYMBOLS '(SMC_0402R_C_H022,C0402_BGA,C0402-0P8MM-45DG,C0402-1MM-TRIANGLE-S0)' 
PRP PARENT_PART_TYPE 'CAPACITOR' 
PRP PARENT_PPT 'CAPACITOR' 
PRP PARENT_PPT_PART 'CAPACITOR-G105-0B104-CK,0.1UF,10%' 
PRP PART_NAME 'CAPACITOR' 
TOP 0 4.67902 1.56784 0.0 N 9 30 1
TOP 1 4.63964 1.56784 0.0 N 2 522 2
#
# CMP 67
CMP 19 4.40343 1.66626 90.0 N C201 ??? ;0=1,1=0.022000
PRP SIGNAL_MODEL 'DEFAULT_CAPACITOR_100000pF_1_2' 
PRP REUSE_ID '5' 
PRP ALT_SYMBOLS '(SMC_0402R_C_H022,C0402_BGA,C0402-0P8MM-45DG,C0402-1MM-TRIANGLE-S0)' 
PRP PARENT_PART_TYPE 'CAPACITOR' 
PRP PARENT_PPT 'CAPACITOR' 
PRP PARENT_PPT_PART 'CAPACITOR-G105-0B104-CK,0.1UF,10%' 
PRP PART_NAME 'CAPACITOR' 
TOP 0 4.40343 1.68595 90.0 N 10 31 1
TOP 1 4.40343 1.64657 90.0 N 2 523 2
#
# CMP 68
CMP 19 4.4428 1.58753 270.0 N C161 ??? ;0=1,1=0.022000
PRP SIGNAL_MODEL 'DEFAULT_CAPACITOR_100000pF_1_2' 
PRP REUSE_ID '17' 
PRP ALT_SYMBOLS '(SMC_0402R_C_H022,C0402_BGA,C0402-0P8MM-45DG,C0402-1MM-TRIANGLE-S0)' 
PRP PARENT_PART_TYPE 'CAPACITOR' 
PRP PARENT_PPT 'CAPACITOR' 
PRP PARENT_PPT_PART 'CAPACITOR-G105-0B104-CK,0.1UF,10%' 
PRP PART_NAME 'CAPACITOR' 
TOP 0 4.4428 1.56784 270.0 N 10 32 1
TOP 1 4.4428 1.60722 270.0 N 2 524 2
#
# CMP 69
CMP 19 4.46249 1.64658 180.0 N C147 ??? ;0=1,1=0.022000
PRP SIGNAL_MODEL 'DEFAULT_CAPACITOR_100000pF_1_2' 
PRP REUSE_ID '15' 
PRP ALT_SYMBOLS '(SMC_0402R_C_H022,C0402_BGA,C0402-0P8MM-45DG,C0402-1MM-TRIANGLE-S0)' 
PRP PARENT_PART_TYPE 'CAPACITOR' 
PRP PARENT_PPT 'CAPACITOR' 
PRP PARENT_PPT_PART 'CAPACITOR-G105-0B104-CK,0.1UF,10%' 
PRP PART_NAME 'CAPACITOR' 
TOP 0 4.4428 1.64658 180.0 N 10 33 1
TOP 1 4.48218 1.64658 180.0 N 2 525 2
#
# CMP 70
CMP 19 4.48217 1.58752 90.0 N C152 ??? ;0=1,1=0.022000
PRP SIGNAL_MODEL 'DEFAULT_CAPACITOR_100000pF_1_2' 
PRP REUSE_ID '6' 
PRP ALT_SYMBOLS '(SMC_0402R_C_H022,C0402_BGA,C0402-0P8MM-45DG,C0402-1MM-TRIANGLE-S0)' 
PRP PARENT_PART_TYPE 'CAPACITOR' 
PRP PARENT_PPT 'CAPACITOR' 
PRP PARENT_PPT_PART 'CAPACITOR-G105-0B104-CK,0.1UF,10%' 
PRP PART_NAME 'CAPACITOR' 
TOP 0 4.48217 1.60721 90.0 N 10 34 1
TOP 1 4.48217 1.56783 90.0 N 2 526 2
#
# CMP 71
CMP 19 4.52154 1.66626 90.0 N C207 ??? ;0=1,1=0.022000
PRP SIGNAL_MODEL 'DEFAULT_CAPACITOR_100000pF_1_2' 
PRP REUSE_ID '4' 
PRP ALT_SYMBOLS '(SMC_0402R_C_H022,C0402_BGA,C0402-0P8MM-45DG,C0402-1MM-TRIANGLE-S0)' 
PRP PARENT_PART_TYPE 'CAPACITOR' 
PRP PARENT_PPT 'CAPACITOR' 
PRP PARENT_PPT_PART 'CAPACITOR-G105-0B104-CK,0.1UF,10%' 
PRP PART_NAME 'CAPACITOR' 
TOP 0 4.52154 1.68595 90.0 N 10 35 1
TOP 1 4.52154 1.64657 90.0 N 2 527 2
#
# CMP 72
CMP 19 4.42311 1.92217 0.0 N C132 ??? ;0=1,1=0.022000
PRP SIGNAL_MODEL 'DEFAULT_CAPACITOR_100000pF_1_2' 
PRP ALT_SYMBOLS '(SMC_0402R_C_H022,C0402_BGA,C0402-0P8MM-45DG,C0402-1MM-TRIANGLE-S0)' 
PRP PARENT_PART_TYPE 'CAPACITOR' 
PRP PARENT_PPT 'CAPACITOR' 
PRP PARENT_PPT_PART 'CAPACITOR-G105-0B104-CK,0.1UF,10%' 
PRP PART_NAME 'CAPACITOR' 
TOP 0 4.4428 1.92217 0.0 N 1 152 1
TOP 1 4.40342 1.92217 0.0 N 2 528 2
#
# CMP 73
CMP 19 4.48216 1.94185 270.0 N C126 ??? ;0=1,1=0.022000
PRP SIGNAL_MODEL 'DEFAULT_CAPACITOR_100000pF_1_2' 
PRP ALT_SYMBOLS '(SMC_0402R_C_H022,C0402_BGA,C0402-0P8MM-45DG,C0402-1MM-TRIANGLE-S0)' 
PRP PARENT_PART_TYPE 'CAPACITOR' 
PRP PARENT_PPT 'CAPACITOR' 
PRP PARENT_PPT_PART 'CAPACITOR-G105-0B104-CK,0.1UF,10%' 
PRP PART_NAME 'CAPACITOR' 
TOP 0 4.48216 1.92216 270.0 N 1 153 1
TOP 1 4.48216 1.96154 270.0 N 2 529 2
#
# CMP 74
CMP 19 4.63965 1.86312 270.0 N C202 ??? ;0=1,1=0.022000
PRP SIGNAL_MODEL 'DEFAULT_CAPACITOR_100000pF_1_2' 
PRP ALT_SYMBOLS '(SMC_0402R_C_H022,C0402_BGA,C0402-0P8MM-45DG,C0402-1MM-TRIANGLE-S0)' 
PRP PARENT_PART_TYPE 'CAPACITOR' 
PRP PARENT_PPT 'CAPACITOR' 
PRP PARENT_PPT_PART 'CAPACITOR-G105-0B104-CK,0.1UF,10%' 
PRP PART_NAME 'CAPACITOR' 
TOP 0 4.63965 1.84343 270.0 N 1 154 1
TOP 1 4.63965 1.88281 270.0 N 2 530 2
#
# CMP 75
CMP 19 4.61997 1.92217 180.0 N C215 ??? ;0=1,1=0.022000
PRP SIGNAL_MODEL 'DEFAULT_CAPACITOR_100000pF_1_2' 
PRP ALT_SYMBOLS '(SMC_0402R_C_H022,C0402_BGA,C0402-0P8MM-45DG,C0402-1MM-TRIANGLE-S0)' 
PRP PARENT_PART_TYPE 'CAPACITOR' 
PRP PARENT_PPT 'CAPACITOR' 
PRP PARENT_PPT_PART 'CAPACITOR-G105-0B104-CK,0.1UF,10%' 
PRP PART_NAME 'CAPACITOR' 
TOP 0 4.60028 1.92217 180.0 N 1 155 1
TOP 1 4.63966 1.92217 180.0 N 2 531 2
#
# CMP 76
CMP 19 4.40343 1.58752 90.0 N C171 ??? ;0=1,1=0.022000
PRP SIGNAL_MODEL 'DEFAULT_CAPACITOR_100000pF_1_2' 
PRP REUSE_ID '16' 
PRP ALT_SYMBOLS '(SMC_0402R_C_H022,C0402_BGA,C0402-0P8MM-45DG,C0402-1MM-TRIANGLE-S0)' 
PRP PARENT_PART_TYPE 'CAPACITOR' 
PRP PARENT_PPT 'CAPACITOR' 
PRP PARENT_PPT_PART 'CAPACITOR-G105-0B104-CK,0.1UF,10%' 
PRP PART_NAME 'CAPACITOR' 
TOP 0 4.40343 1.60721 90.0 N 10 36 1
TOP 1 4.40343 1.56783 90.0 N 2 532 2
#
# CMP 77
CMP 19 4.58059 1.41035 0.0 N C127 ??? ;0=1,1=0.022000
PRP SIGNAL_MODEL 'DEFAULT_CAPACITOR_100000pF_1_2' 
PRP ALT_SYMBOLS '(SMC_0402R_C_H022,C0402_BGA,C0402-0P8MM-45DG,C0402-1MM-TRIANGLE-S0)' 
PRP PARENT_PART_TYPE 'CAPACITOR' 
PRP PARENT_PPT 'CAPACITOR' 
PRP PARENT_PPT_PART 'CAPACITOR-G105-0B104-CK,0.1UF,10%' 
PRP PART_NAME 'CAPACITOR' 
TOP 0 4.60028 1.41035 0.0 N 9 31 1
TOP 1 4.5609 1.41035 0.0 N 2 533 2
#
# CMP 78
CMP 19 4.76666 1.40836 90.0 N C122 ??? ;0=1,1=0.022000
PRP SIGNAL_MODEL 'DEFAULT_CAPACITOR_100000pF_1_2' 
PRP ALT_SYMBOLS '(SMC_0402R_C_H022,C0402_BGA,C0402-0P8MM-45DG,C0402-1MM-TRIANGLE-S0)' 
PRP PARENT_PART_TYPE 'CAPACITOR' 
PRP PARENT_PPT 'CAPACITOR' 
PRP PARENT_PPT_PART 'CAPACITOR-G105-0B104-CK,0.1UF,10%' 
PRP PART_NAME 'CAPACITOR' 
TOP 0 4.76666 1.42805 90.0 N 9 32 1
TOP 1 4.76666 1.38867 90.0 N 2 534 2
#
# CMP 79
CMP 19 4.50185 2.07965 0.0 N C134 ??? ;0=1,1=0.022000
PRP SIGNAL_MODEL 'DEFAULT_CAPACITOR_100000pF_1_2' 
PRP ALT_SYMBOLS '(SMC_0402R_C_H022,C0402_BGA,C0402-0P8MM-45DG,C0402-1MM-TRIANGLE-S0)' 
PRP PARENT_PART_TYPE 'CAPACITOR' 
PRP PARENT_PPT 'CAPACITOR' 
PRP PARENT_PPT_PART 'CAPACITOR-G105-0B104-CK,0.1UF,10%' 
PRP PART_NAME 'CAPACITOR' 
TOP 0 4.52154 2.07965 0.0 N 1 156 1
TOP 1 4.48216 2.07965 0.0 N 2 535 2
#
# CMP 80
CMP 19 4.40343 2.17808 270.0 N C223 ??? ;0=1,1=0.022000
PRP SIGNAL_MODEL 'DEFAULT_CAPACITOR_100000pF_1_2' 
PRP ALT_SYMBOLS '(SMC_0402R_C_H022,C0402_BGA,C0402-0P8MM-45DG,C0402-1MM-TRIANGLE-S0)' 
PRP PARENT_PART_TYPE 'CAPACITOR' 
PRP PARENT_PPT 'CAPACITOR' 
PRP PARENT_PPT_PART 'CAPACITOR-G105-0B104-CK,0.1UF,10%' 
PRP PART_NAME 'CAPACITOR' 
TOP 0 4.40343 2.15839 270.0 N 1 157 1
TOP 1 4.40343 2.19777 270.0 N 2 536 2
#
# CMP 81
CMP 19 4.61997 1.96154 180.0 N C130 ??? ;0=1,1=0.022000
PRP SIGNAL_MODEL 'DEFAULT_CAPACITOR_100000pF_1_2' 
PRP ALT_SYMBOLS '(SMC_0402R_C_H022,C0402_BGA,C0402-0P8MM-45DG,C0402-1MM-TRIANGLE-S0)' 
PRP PARENT_PART_TYPE 'CAPACITOR' 
PRP PARENT_PPT 'CAPACITOR' 
PRP PARENT_PPT_PART 'CAPACITOR-G105-0B104-CK,0.1UF,10%' 
PRP PART_NAME 'CAPACITOR' 
TOP 0 4.60028 1.96154 180.0 N 1 158 1
TOP 1 4.63966 1.96154 180.0 N 2 537 2
#
# CMP 82
CMP 20 4.00973 1.62689 90.0 N C131 ??? ;0=1,1=0.026000
PRP ALT_SYMBOLS '(SMC_0402R_C_H026,C0402_BGA,C0402-0P8MM-45DG,C0402-1MM-TRIANGLE-S0)' 
PRP PARENT_PART_TYPE 'CAPACITOR' 
PRP PARENT_PPT 'CAPACITOR' 
PRP PARENT_PPT_PART 'CAPACITOR-G105-0F475-BM,4.7UF,20%' 
PRP PART_NAME 'CAPACITOR' 
TOP 0 4.00973 1.64658 90.0 N 7 12 1
TOP 1 4.00973 1.6072 90.0 N 2 538 2
#
# CMP 83
CMP 20 3.95067 1.52847 180.0 N C117 ??? ;0=1,1=0.026000
PRP ALT_SYMBOLS '(SMC_0402R_C_H026,C0402_BGA,C0402-0P8MM-45DG,C0402-1MM-TRIANGLE-S0)' 
PRP PARENT_PART_TYPE 'CAPACITOR' 
PRP PARENT_PPT 'CAPACITOR' 
PRP PARENT_PPT_PART 'CAPACITOR-G105-0F475-BM,4.7UF,20%' 
PRP PART_NAME 'CAPACITOR' 
TOP 0 3.93098 1.52847 180.0 N 6 10 1
TOP 1 3.97036 1.52847 180.0 N 2 539 2
#
# CMP 84
CMP 20 3.99004 1.92217 0.0 N C167 ??? ;0=1,1=0.026000
PRP ALT_SYMBOLS '(SMC_0402R_C_H026,C0402_BGA,C0402-0P8MM-45DG,C0402-1MM-TRIANGLE-S0)' 
PRP PARENT_PART_TYPE 'CAPACITOR' 
PRP PARENT_PPT 'CAPACITOR' 
PRP PARENT_PPT_PART 'CAPACITOR-G105-0F475-BM,4.7UF,20%' 
PRP PART_NAME 'CAPACITOR' 
TOP 0 4.00973 1.92217 0.0 N 1 159 1
TOP 1 3.97035 1.92217 0.0 N 2 540 2
#
# CMP 85
CMP 20 4.20658 1.62689 90.0 N C120 ??? ;0=1,1=0.026000
PRP ALT_SYMBOLS '(SMC_0402R_C_H026,C0402_BGA,C0402-0P8MM-45DG,C0402-1MM-TRIANGLE-S0)' 
PRP PARENT_PART_TYPE 'CAPACITOR' 
PRP PARENT_PPT 'CAPACITOR' 
PRP PARENT_PPT_PART 'CAPACITOR-G105-0F475-BM,4.7UF,20%' 
PRP PART_NAME 'CAPACITOR' 
TOP 0 4.20658 1.64658 90.0 N 8 11 1
TOP 1 4.20658 1.6072 90.0 N 2 541 2
#
# CMP 86
CMP 20 4.0491 1.94186 270.0 N C170 ??? ;0=1,1=0.026000
PRP ALT_SYMBOLS '(SMC_0402R_C_H026,C0402_BGA,C0402-0P8MM-45DG,C0402-1MM-TRIANGLE-S0)' 
PRP PARENT_PART_TYPE 'CAPACITOR' 
PRP PARENT_PPT 'CAPACITOR' 
PRP PARENT_PPT_PART 'CAPACITOR-G105-0F475-BM,4.7UF,20%' 
PRP PART_NAME 'CAPACITOR' 
TOP 0 4.0491 1.92217 270.0 N 1 160 1
TOP 1 4.0491 1.96155 270.0 N 2 542 2
#
# CMP 87
CMP 20 4.46249 1.68595 180.0 N C138 ??? ;0=1,1=0.026000
PRP ALT_SYMBOLS '(SMC_0402R_C_H026,C0402_BGA,C0402-0P8MM-45DG,C0402-1MM-TRIANGLE-S0)' 
PRP PARENT_PART_TYPE 'CAPACITOR' 
PRP PARENT_PPT 'CAPACITOR' 
PRP PARENT_PPT_PART 'CAPACITOR-G105-0F475-BM,4.7UF,20%' 
PRP PART_NAME 'CAPACITOR' 
TOP 0 4.4428 1.68595 180.0 N 8 12 1
TOP 1 4.48218 1.68595 180.0 N 2 543 2
#
# CMP 88
CMP 20 4.52154 1.39066 270.0 N C160 ??? ;0=1,1=0.026000
PRP ALT_SYMBOLS '(SMC_0402R_C_H026,C0402_BGA,C0402-0P8MM-45DG,C0402-1MM-TRIANGLE-S0)' 
PRP PARENT_PART_TYPE 'CAPACITOR' 
PRP PARENT_PPT 'CAPACITOR' 
PRP PARENT_PPT_PART 'CAPACITOR-G105-0F475-BM,4.7UF,20%' 
PRP PART_NAME 'CAPACITOR' 
TOP 0 4.52154 1.37097 270.0 N 9 33 1
TOP 1 4.52154 1.41035 270.0 N 2 544 2
#
# CMP 89
CMP 20 4.60028 1.54816 270.0 N C93 ??? ;0=1,1=0.026000
PRP REUSE_ID '33' 
PRP ALT_SYMBOLS '(SMC_0402R_C_H026,C0402_BGA,C0402-0P8MM-45DG,C0402-1MM-TRIANGLE-S0)' 
PRP PARENT_PART_TYPE 'CAPACITOR' 
PRP PARENT_PPT 'CAPACITOR' 
PRP PARENT_PPT_PART 'CAPACITOR-G105-0F475-BM,4.7UF,20%' 
PRP PART_NAME 'CAPACITOR' 
TOP 0 4.60028 1.52847 270.0 N 9 34 1
TOP 1 4.60028 1.56785 270.0 N 2 545 2
#
# CMP 90
CMP 20 4.67902 2.13871 270.0 N C154 ??? ;0=1,1=0.026000
PRP ALT_SYMBOLS '(SMC_0402R_C_H026,C0402_BGA,C0402-0P8MM-45DG,C0402-1MM-TRIANGLE-S0)' 
PRP PARENT_PART_TYPE 'CAPACITOR' 
PRP PARENT_PPT 'CAPACITOR' 
PRP PARENT_PPT_PART 'CAPACITOR-G105-0F475-BM,4.7UF,20%' 
PRP PART_NAME 'CAPACITOR' 
TOP 0 4.67902 2.11902 270.0 N 1 161 1
TOP 1 4.67902 2.1584 270.0 N 2 546 2
#
# CMP 91
CMP 31 3.645 1.395 0.0 N L35 ??? ;0=1,1=0.029530
PRP ALT_SYMBOLS '(SMC_0603R_H030)' 
PRP PARENT_PART_TYPE 'FERRITEBEAD' 
PRP PARENT_PPT 'FERRITEBEAD' 
PRP PARENT_PPT_PART 'FERRITEBEAD-G191-10100-01,120OHM,25%' 
PRP PART_NAME 'FERRITEBEAD' 
TOP 0 3.672 1.395 0.0 N 6 11 1
TOP 1 3.618 1.395 0.0 N 14 6 2
#
# CMP 92
CMP 31 2.26 0.65 270.0 N L21 ??? ;0=1,1=0.029530
PRP ALT_SYMBOLS '(SMC_0603R_H030)' 
PRP PARENT_PART_TYPE 'FERRITEBEAD' 
PRP PARENT_PPT 'FERRITEBEAD' 
PRP PARENT_PPT_PART 'FERRITEBEAD-G191-10101-01,26OHM,25%' 
PRP PART_NAME 'FERRITEBEAD' 
TOP 0 2.26 0.623 270.0 N 81 3 1
TOP 1 2.26 0.677 270.0 N 19 27 2
#
# CMP 93
CMP 31 3.185 2.88 270.0 N L3 ??? ;0=1,1=0.029530
PRP ALT_SYMBOLS '(SMC_0603R_H030)' 
PRP PARENT_PART_TYPE 'FERRITEBEAD' 
PRP PARENT_PPT 'FERRITEBEAD' 
PRP PARENT_PPT_PART 'FERRITEBEAD-G191-10101-01,26OHM,25%' 
PRP PART_NAME 'FERRITEBEAD' 
TOP 0 3.185 2.853 270.0 N 76 2 1
TOP 1 3.185 2.907 270.0 N 13 10 2
#
# CMP 94
CMP 39 4.035 2.325 0.0 N C172 ??? ;0=1,1=0.110000
PRP ALT_SYMBOLS '(SMC_1210R_H110)' 
PRP PARENT_PART_TYPE 'CAPACITOR' 
PRP PARENT_PPT 'CAPACITOR' 
PRP PARENT_PPT_PART 'CAPACITOR-G109-0G107-BM,100UF,20%' 
PRP PART_NAME 'CAPACITOR' 
TOP 0 4.0875 2.325 0.0 N 1 162 1
TOP 1 3.9825 2.325 0.0 N 2 547 2
#
# CMP 95
CMP 40 1.035 3.115 90.0 N C90 ??? ;0=1,1=0.025590
PRP ALT_SYMBOLS '(SMC_0402R_C_H026,C0402_BGA,C0402-0P8MM-45DG,C0402-1MM-TRIANGLE-S0)' 
PRP PARENT_PART_TYPE 'CAPACITOR' 
PRP PARENT_PPT 'CAPACITOR' 
PRP PARENT_PPT_PART 'CAPACITOR-G105-0F475-BM,4.7UF,20%' 
PRP PART_NAME 'CAPACITOR' 
TOP 0 1.035 3.136 90.0 N 131 4 1
TOP 1 1.035 3.094 90.0 N 2 548 2
#
# CMP 96
CMP 40 1.375 3.58 90.0 N C91 ??? ;0=1,1=0.025590
PRP ALT_SYMBOLS '(SMC_0402R_C_H026,C0402_BGA,C0402-0P8MM-45DG,C0402-1MM-TRIANGLE-S0)' 
PRP PARENT_PART_TYPE 'CAPACITOR' 
PRP PARENT_PPT 'CAPACITOR' 
PRP PARENT_PPT_PART 'CAPACITOR-G105-0F475-BM,4.7UF,20%' 
PRP PART_NAME 'CAPACITOR' 
TOP 0 1.375 3.601 90.0 N 88 16 1
TOP 1 1.375 3.559 90.0 N 2 549 2
#
# CMP 97
CMP 40 1.085 3.585 270.0 N C98 ??? ;0=1,1=0.025590
PRP REUSE_ID '13' 
PRP ALT_SYMBOLS '(SMC_0402R_C_H026,C0402_BGA,C0402-0P8MM-45DG,C0402-1MM-TRIANGLE-S0)' 
PRP PARENT_PART_TYPE 'CAPACITOR' 
PRP PARENT_PPT 'CAPACITOR' 
PRP PARENT_PPT_PART 'CAPACITOR-G105-0F475-BM,4.7UF,20%' 
PRP PART_NAME 'CAPACITOR' 
TOP 0 1.085 3.564 270.0 N 4 2 1
TOP 1 1.085 3.606 270.0 N 2 550 2
#
# CMP 98
CMP 40 1.22 3.585 270.0 N C99 ??? ;0=1,1=0.025590
PRP REUSE_ID '9' 
PRP ALT_SYMBOLS '(SMC_0402R_C_H026,C0402_BGA,C0402-0P8MM-45DG,C0402-1MM-TRIANGLE-S0)' 
PRP PARENT_PART_TYPE 'CAPACITOR' 
PRP PARENT_PPT 'CAPACITOR' 
PRP PARENT_PPT_PART 'CAPACITOR-G105-0F475-BM,4.7UF,20%' 
PRP PART_NAME 'CAPACITOR' 
TOP 0 1.22 3.564 270.0 N 5 2 1
TOP 1 1.22 3.606 270.0 N 2 551 2
#
# CMP 99
CMP 40 4.045 2.215 0.0 N C159 ??? ;0=1,1=0.025590
PRP ALT_SYMBOLS '(SMC_0402R_C_H026,C0402_BGA,C0402-0P8MM-45DG,C0402-1MM-TRIANGLE-S0)' 
PRP PARENT_PART_TYPE 'CAPACITOR' 
PRP PARENT_PPT 'CAPACITOR' 
PRP PARENT_PPT_PART 'CAPACITOR-G105-0F475-BM,4.7UF,20%' 
PRP PART_NAME 'CAPACITOR' 
TOP 0 4.066 2.215 0.0 N 1 163 1
TOP 1 4.024 2.215 0.0 N 2 552 2
#
# CMP 100
CMP 40 4.44411 1.755 180.0 N C128 ??? ;0=1,1=0.025590
PRP ALT_SYMBOLS '(SMC_0402R_C_H026,C0402_BGA,C0402-0P8MM-45DG,C0402-1MM-TRIANGLE-S0)' 
PRP PARENT_PART_TYPE 'CAPACITOR' 
PRP PARENT_PPT 'CAPACITOR' 
PRP PARENT_PPT_PART 'CAPACITOR-G105-0F475-BM,4.7UF,20%' 
PRP PART_NAME 'CAPACITOR' 
TOP 0 4.42311 1.755 180.0 N 8 13 1
TOP 1 4.46511 1.755 180.0 N 2 553 2
#
# CMP 101
CMP 40 4.47585 2.22 0.0 N C163 ??? ;0=1,1=0.025590
PRP ALT_SYMBOLS '(SMC_0402R_C_H026,C0402_BGA,C0402-0P8MM-45DG,C0402-1MM-TRIANGLE-S0)' 
PRP PARENT_PART_TYPE 'CAPACITOR' 
PRP PARENT_PPT 'CAPACITOR' 
PRP PARENT_PPT_PART 'CAPACITOR-G105-0F475-BM,4.7UF,20%' 
PRP PART_NAME 'CAPACITOR' 
TOP 0 4.49685 2.22 0.0 N 1 164 1
TOP 1 4.45485 2.22 0.0 N 2 554 2
#
# CMP 102
CMP 41 1.631 4.031 0.0 N SP1 ??? ;0=1,1=0.000010
PRP REUSE_ID '12' 
PRP ALT_SYMBOLS '(0201_SOLDER_PREFORM_5MIL)' 
PRP PARENT_PART_TYPE 'SOLDER_PREFORM' 
PRP PARENT_PPT 'SOLDER_PREFORM' 
PRP PARENT_PPT_PART 'SOLDER_PREFORM-G380-10015-01' 
PRP PART_NAME 'SOLDER_PREFORM' 
TOP 0 1.6355 4.031 0.0 N 2 555 1
TOP 1 1.6265 4.031 0.0 N 90 4 2
#
# CMP 103
CMP 41 3.368 3.947 180.0 N SP2 ??? ;0=1,1=0.000010
PRP REUSE_ID '24' 
PRP ALT_SYMBOLS '(0201_SOLDER_PREFORM_5MIL)' 
PRP PARENT_PART_TYPE 'SOLDER_PREFORM' 
PRP PARENT_PPT 'SOLDER_PREFORM' 
PRP PARENT_PPT_PART 'SOLDER_PREFORM-G380-10015-01' 
PRP PART_NAME 'SOLDER_PREFORM' 
TOP 0 3.3635 3.947 180.0 N 2 556 1
TOP 1 3.3725 3.947 180.0 N 112 5 2
#
# CMP 104
CMP 41 5.64 2.17 270.0 N SP3 ??? ;0=1,1=0.000010
PRP ALT_SYMBOLS '(0201_SOLDER_PREFORM_5MIL)' 
PRP PARENT_PART_TYPE 'SOLDER_PREFORM' 
PRP PARENT_PPT 'SOLDER_PREFORM' 
PRP PARENT_PPT_PART 'SOLDER_PREFORM-G380-10015-01' 
PRP PART_NAME 'SOLDER_PREFORM' 
TOP 0 5.64 2.1655 270.0 N 2 557 1
TOP 1 5.64 2.1745 270.0 N 58 4 2
#
# CMP 105
CMP 44 5.316 3.607 270.0 N CR3 ??? ;0=1,1=0.097240
PRP REUSE_ID '18' 
PRP ALT_SYMBOLS '(SMC_CR_170X143_V2)' 
PRP PARENT_PART_TYPE 'DIODE_2' 
PRP PARENT_PPT 'DIODE_2' 
PRP PARENT_PPT_PART 'DIODE_2-G122-00005-01' 
PRP PART_NAME 'DIODE_2' 
TOP 0 5.316 3.51999 270.0 N 2 558 A
TOP 1 5.316 3.69401 270.0 N 3 20 C
#
# CMP 106
CMP 45 2.69 2.25 270.0 N U12 ??? ;0=1,1=0.057000
PRP ALT_SYMBOLS '(SOT23_5)' 
PRP PARENT_PART_TYPE 'TPS2051BDBVT_SOT23_5' 
PRP PARENT_PPT 'TPS2051BDBVT_SOT23_5' 
PRP PARENT_PPT_PART 'TPS2051BDBVT_SOT23_5-G220-10338-01' 
PRP PART_NAME 'TPS2051BDBVT_SOT23_5' 
TOP 0 2.7274 2.1935 270.0 N 122 1 1
TOP 1 2.69 2.1935 270.0 N 2 559 2
TOP 2 2.6526 2.1935 270.0 N 353 0 3
TOP 3 2.6526 2.3065 270.0 N 123 1 4
TOP 4 2.7274 2.3065 270.0 N 76 3 5
#
# CMP 107
CMP 48 1.859 3.463 0.0 N U31 ??? ;0=1,1=0.068900
PRP ALT_SYMBOLS '(SOP8_154_P050_V1)' 
PRP PARENT_PART_TYPE 'CAT93C46VI_GT3_SOIC8' 
PRP PARENT_PPT 'CAT93C46VI_GT3_SOIC8' 
PRP PARENT_PPT_PART 'CAT93C46VI_GT3_SOIC8-G221-10075-01' 
PRP PART_NAME 'CAT93C46VI_GT3_SOIC8' 
TOP 0 1.9695 3.538 0.0 N 480 1 1
TOP 1 1.9695 3.488 0.0 N 481 1 2
TOP 2 1.9695 3.438 0.0 N 486 1 3
TOP 3 1.9695 3.388 0.0 N 479 0 4
TOP 4 1.7485 3.388 0.0 N 2 560 5
TOP 5 1.7485 3.438 0.0 N 88 17 6
TOP 6 1.7485 3.488 0.0 N 0 226 7
TOP 7 1.7485 3.538 0.0 N 88 18 8
#
# CMP 108
CMP 50 0.46 2.99 0.0 N U8 ??? ;0=1,1=0.043700
PRP ALT_SYMBOLS '(SOP8_118_P0256_V2)' 
PRP PARENT_PART_TYPE 'LM75BDP_TSSOP8' 
PRP PARENT_PPT 'LM75BDP_TSSOP8' 
PRP PARENT_PPT_PART 'LM75BDP_TSSOP8-G220-10215-01' 
PRP PART_NAME 'LM75BDP_TSSOP8' 
TOP 0 0.5505 3.0284 0.0 N 401 0 1
TOP 1 0.5505 3.0028 0.0 N 331 4 2
TOP 2 0.5505 2.9772 0.0 N 407 2 3
TOP 3 0.5505 2.9516 0.0 N 2 561 4
TOP 4 0.3695 2.9516 0.0 N 402 0 5
TOP 5 0.3695 2.9772 0.0 N 403 0 6
TOP 6 0.3695 3.0028 0.0 N 404 0 7
TOP 7 0.3695 3.0284 0.0 N 1 165 8
#
# CMP 109
CMP 52 1.5 3 0.0 N R491 ??? ;0=1,1=0.013780
PRP ALT_SYMBOLS '(SMC_0402R_C_H014)' 
PRP PARENT_PART_TYPE 'RESISTOR' 
PRP PARENT_PPT 'RESISTOR' 
PRP PARENT_PPT_PART 'RESISTOR-G155-03241-01,3.24KOHM,1%' 
PRP PART_NAME 'RESISTOR' 
TOP 0 1.521 3 0.0 N 516 3 1
TOP 1 1.479 3 0.0 N 2 562 2
#
# CMP 110
CMP 52 1.456 4.142 0.0 N R32 ??? ;0=1,1=0.013780
PRP REUSE_ID '3' 
PRP ALT_SYMBOLS '(SMC_0402R_C_H014)' 
PRP PARENT_PART_TYPE 'RESISTOR' 
PRP PARENT_PPT 'RESISTOR' 
PRP PARENT_PPT_PART 'RESISTOR-G155-03241-01,3.24KOHM,1%' 
PRP PART_NAME 'RESISTOR' 
TOP 0 1.477 4.142 0.0 N 12 3 1
TOP 1 1.435 4.142 0.0 N 90 5 2
#
# CMP 111
CMP 52 5.278 2.632 270.0 N R188 ??? ;0=1,1=0.013780
PRP ALT_SYMBOLS '(SMC_0402R_C_H014)' 
PRP PARENT_PART_TYPE 'RESISTOR' 
PRP PARENT_PPT 'RESISTOR' 
PRP PARENT_PPT_PART 'RESISTOR-G155-03241-01,3.24KOHM,1%' 
PRP PART_NAME 'RESISTOR' 
TOP 0 5.278 2.611 270.0 N 2 563 1
TOP 1 5.278 2.653 270.0 N 311 3 2
#
# CMP 112
CMP 53 1.445 4.09 180.0 N R50 ??? ;0=1,1=0.023620
PRP REUSE_ID '18' 
PRP ALT_SYMBOLS '(SMC_0603R_H024)' 
PRP PARENT_PART_TYPE 'RESISTOR' 
PRP PARENT_PPT 'RESISTOR' 
PRP PARENT_PPT_PART 'RESISTOR-G156-100R0-J0,0OHM,-' 
PRP PART_NAME 'RESISTOR' 
TOP 0 1.418 4.09 180.0 N 90 6 1
TOP 1 1.472 4.09 180.0 N 12 4 2
#
# CMP 113
CMP 53 2.845 2.195 90.0 N FU3 ??? ;0=1,1=0.023620
PRP ALT_SYMBOLS '(SMC_0603R_H024)' 
PRP PARENT_PART_TYPE 'FUSE' 
PRP PARENT_PPT 'FUSE' 
PRP PARENT_PPT_PART 'FUSE-G280-10049-01,1A' 
PRP PART_NAME 'FUSE' 
TOP 0 2.845 2.222 90.0 N 178 1 1
TOP 1 2.845 2.168 90.0 N 122 2 2
#
# CMP 114
CMP 53 3.543 3.887 0.0 N R54 ??? ;0=1,1=0.023620
PRP REUSE_ID '26' 
PRP ALT_SYMBOLS '(SMC_0603R_H024)' 
PRP PARENT_PART_TYPE 'RESISTOR' 
PRP PARENT_PPT 'RESISTOR' 
PRP PARENT_PPT_PART 'RESISTOR-G156-100R0-J0,0OHM,-' 
PRP PART_NAME 'RESISTOR' 
TOP 0 3.57 3.887 0.0 N 112 6 1
TOP 1 3.516 3.887 0.0 N 18 4 2
#
# CMP 115
CMP 53 5.7 2.345 90.0 N R252 ??? ;0=1,1=0.023620
PRP ALT_SYMBOLS '(SMC_0603R_H024)' 
PRP PARENT_PART_TYPE 'RESISTOR' 
PRP PARENT_PPT 'RESISTOR' 
PRP PARENT_PPT_PART 'RESISTOR-G156-100R0-J0,0OHM,-' 
PRP PART_NAME 'RESISTOR' 
TOP 0 5.7 2.372 90.0 N 58 5 1
TOP 1 5.7 2.318 90.0 N 67 3 2
#
# CMP 116
CMP 54 1.84 4.13 180.0 N R33 ??? ;0=1,1=0.026000
PRP REUSE_ID '6' 
PRP ALT_SYMBOLS '(SMC_0805R_H026)' 
PRP PARENT_PART_TYPE 'RESISTOR' 
PRP PARENT_PPT 'RESISTOR' 
PRP PARENT_PPT_PART 'RESISTOR-G157-12R20-01,2.2OHM,1%' 
PRP PART_NAME 'RESISTOR' 
TOP 0 1.807 4.13 180.0 N 108 0 1
TOP 1 1.873 4.13 180.0 N 2 564 2
#
# CMP 117
CMP 54 2.85 2.31 90.0 N R357 ??? ;0=1,1=0.026000
PRP ALT_SYMBOLS '(SMC_0805R_H026)' 
PRP PARENT_PART_TYPE 'RESISTOR' 
PRP PARENT_PPT 'RESISTOR' 
PRP PARENT_PPT_PART 'RESISTOR-G157-100R0-J0,0OHM,-' 
PRP PART_NAME 'RESISTOR' 
TOP 0 2.85 2.343 90.0 N 76 4 1
TOP 1 2.85 2.277 90.0 N 178 2 2
#
# CMP 118
CMP 54 3.185 3.79 90.0 N R39 ??? ;0=1,1=0.026000
PRP REUSE_ID '22' 
PRP ALT_SYMBOLS '(SMC_0805R_H026)' 
PRP PARENT_PART_TYPE 'RESISTOR' 
PRP PARENT_PPT 'RESISTOR' 
PRP PARENT_PPT_PART 'RESISTOR-G157-12R20-01,2.2OHM,1%' 
PRP PART_NAME 'RESISTOR' 
TOP 0 3.185 3.823 90.0 N 119 0 1
TOP 1 3.185 3.757 90.0 N 2 565 2
#
# CMP 119
CMP 54 5.72 1.99 180.0 N R253 ??? ;0=1,1=0.026000
PRP ALT_SYMBOLS '(SMC_0805R_H026)' 
PRP PARENT_PART_TYPE 'RESISTOR' 
PRP PARENT_PPT 'RESISTOR' 
PRP PARENT_PPT_PART 'RESISTOR-G157-12R20-01,2.2OHM,1%' 
PRP PART_NAME 'RESISTOR' 
TOP 0 5.687 1.99 180.0 N 65 0 1
TOP 1 5.753 1.99 180.0 N 2 566 2
#
# CMP 120
CMP 56 1.8646 0.6232 270.0 N R23 ??? ;0=1,1=0.016000
PRP SIGNAL_MODEL 'RESISTOR-G155-100R0-J0_0OHM_-' 
PRP ALT_SYMBOLS '(SMC_0402R_C_H016,C0402-0P8MM-45DG)' 
PRP PARENT_PART_TYPE 'RESISTOR' 
PRP PARENT_PPT 'RESISTOR' 
PRP PARENT_PPT_PART 'RESISTOR-G155-100R0-J0,0OHM,-' 
PRP PART_NAME 'RESISTOR' 
TOP 0 1.8646 0.6022 270.0 N 179 2 1
TOP 1 1.8646 0.6442 270.0 N 196 1 2
#
# CMP 121
CMP 56 3.554 1.88649 180.0 N R106 ??? ;0=1,1=0.016000
PRP SIGNAL_MODEL 'RESISTOR-G155-100R0-J0_0OHM_-' 
PRP ALT_SYMBOLS '(SMC_0402R_C_H016,C0402-0P8MM-45DG)' 
PRP PARENT_PART_TYPE 'RESISTOR' 
PRP PARENT_PPT 'RESISTOR' 
PRP PARENT_PPT_PART 'RESISTOR-G155-100R0-J0,0OHM,-' 
PRP PART_NAME 'RESISTOR' 
TOP 0 3.533 1.88649 180.0 N 255 2 1
TOP 1 3.575 1.88649 180.0 N 256 3 2
#
# CMP 122
CMP 56 2.795 1.859 270.0 N R90 ??? ;0=1,1=0.016000
PRP SIGNAL_MODEL 'RESISTOR-G155-11000-01_100OHM_A' 
PRP ALT_SYMBOLS '(SMC_0402R_C_H016)' 
PRP PARENT_PART_TYPE 'RESISTOR' 
PRP PARENT_PPT 'RESISTOR' 
PRP PARENT_PPT_PART 'RESISTOR-G155-11000-01,100OHM,1%' 
PRP PART_NAME 'RESISTOR' 
TOP 0 2.795 1.838 270.0 N 236 2 1
TOP 1 2.795 1.88 270.0 N 235 2 2
#
# CMP 123
CMP 56 3.725 1.72 180.0 N R196 ??? ;0=1,1=0.016000
PRP SIGNAL_MODEL 'RESISTOR-G155-11000-01_100OHM_A' 
PRP ALT_SYMBOLS '(SMC_0402R_C_H016)' 
PRP PARENT_PART_TYPE 'RESISTOR' 
PRP PARENT_PPT 'RESISTOR' 
PRP PARENT_PPT_PART 'RESISTOR-G155-11000-01,100OHM,1%' 
PRP PART_NAME 'RESISTOR' 
TOP 0 3.704 1.72 180.0 N 6 12 1
TOP 1 3.746 1.72 180.0 N 317 2 2
#
# CMP 124
CMP 56 0.53 1.465 90.0 N R492 ??? ;0=1,1=0.016000
PRP SIGNAL_MODEL 'RESISTOR-G155-100R0-J0_0OHM_-' 
PRP ALT_SYMBOLS '(SMC_0402R_C_H016,C0402-0P8MM-45DG)' 
PRP PARENT_PART_TYPE 'RESISTOR' 
PRP PARENT_PPT 'RESISTOR' 
PRP PARENT_PPT_PART 'RESISTOR-G155-100R0-J0,0OHM,-' 
PRP PART_NAME 'RESISTOR' 
TOP 0 0.53 1.486 90.0 N 91 1 1
TOP 1 0.53 1.444 90.0 N 297 2 2
#
# CMP 125
CMP 56 0.535 0.905 90.0 N R493 ??? ;0=1,1=0.016000
PRP SIGNAL_MODEL 'RESISTOR-G155-100R0-J0_0OHM_-' 
PRP ALT_SYMBOLS '(SMC_0402R_C_H016,C0402-0P8MM-45DG)' 
PRP PARENT_PART_TYPE 'RESISTOR' 
PRP PARENT_PPT 'RESISTOR' 
PRP PARENT_PPT_PART 'RESISTOR-G155-100R0-J0,0OHM,-' 
PRP PART_NAME 'RESISTOR' 
TOP 0 0.535 0.926 90.0 N 92 1 1
TOP 1 0.535 0.884 90.0 N 299 2 2
#
# CMP 126
CMP 56 0.53 2.605 90.0 N R494 ??? ;0=1,1=0.016000
PRP SIGNAL_MODEL 'RESISTOR-G155-100R0-J0_0OHM_-' 
PRP ALT_SYMBOLS '(SMC_0402R_C_H016,C0402-0P8MM-45DG)' 
PRP PARENT_PART_TYPE 'RESISTOR' 
PRP PARENT_PPT 'RESISTOR' 
PRP PARENT_PPT_PART 'RESISTOR-G155-100R0-J0,0OHM,-' 
PRP PART_NAME 'RESISTOR' 
TOP 0 0.53 2.626 90.0 N 94 1 1
TOP 1 0.53 2.584 90.0 N 265 2 2
#
# CMP 127
CMP 56 0.53 2.07 90.0 N R495 ??? ;0=1,1=0.016000
PRP SIGNAL_MODEL 'RESISTOR-G155-100R0-J0_0OHM_-' 
PRP ALT_SYMBOLS '(SMC_0402R_C_H016,C0402-0P8MM-45DG)' 
PRP PARENT_PART_TYPE 'RESISTOR' 
PRP PARENT_PPT 'RESISTOR' 
PRP PARENT_PPT_PART 'RESISTOR-G155-100R0-J0,0OHM,-' 
PRP PART_NAME 'RESISTOR' 
TOP 0 0.53 2.091 90.0 N 95 1 1
TOP 1 0.53 2.049 90.0 N 267 2 2
#
# CMP 128
CMP 56 4.66 1.755 0.0 N R501 ??? ;0=1,1=0.016000
PRP SIGNAL_MODEL 'RESISTOR-G155-100R0-J0_0OHM_-' 
PRP ALT_SYMBOLS '(SMC_0402R_C_H016)' 
PRP PARENT_PART_TYPE 'RESISTOR' 
PRP PARENT_PPT 'RESISTOR' 
PRP PARENT_PPT_PART 'RESISTOR-G155-14701-01,4.7KOHM,1%' 
PRP PART_NAME 'RESISTOR' 
TOP 0 4.681 1.755 0.0 N 2 567 1
TOP 1 4.639 1.755 0.0 N 434 2 2
#
# CMP 129
CMP 56 4.715 0.965 180.0 N R482 ??? ;0=1,1=0.016000
PRP SIGNAL_MODEL 'RESISTOR-G155-100R0-J0_0OHM_-' 
PRP ALT_SYMBOLS '(SMC_0402R_C_H016)' 
PRP PARENT_PART_TYPE 'RESISTOR' 
PRP PARENT_PPT 'RESISTOR' 
PRP PARENT_PPT_PART 'RESISTOR-G155-14701-01,4.7KOHM,1%' 
PRP PART_NAME 'RESISTOR' 
TOP 0 4.694 0.965 180.0 N 1 166 1
TOP 1 4.736 0.965 180.0 N 512 4 2
#
# CMP 130
CMP 56 3.994 3.291 180.0 N R457 ??? ;0=1,1=0.016000
PRP SIGNAL_MODEL 'RESISTOR-G155-100R0-J0_0OHM_-' 
PRP ALT_SYMBOLS '(SMC_0402R_C_H016)' 
PRP PARENT_PART_TYPE 'RESISTOR' 
PRP PARENT_PPT 'RESISTOR' 
PRP PARENT_PPT_PART 'RESISTOR-G155-14701-01,4.7KOHM,1%' 
PRP PART_NAME 'RESISTOR' 
TOP 0 3.973 3.291 180.0 N 1 167 1
TOP 1 4.015 3.291 180.0 N 488 6 2
#
# CMP 131
CMP 56 3.86 3.81 0.0 N R450 ??? ;0=1,1=0.016000
PRP SIGNAL_MODEL 'RESISTOR-G155-100R0-J0_0OHM_-' 
PRP ALT_SYMBOLS '(SMC_0402R_C_H016)' 
PRP PARENT_PART_TYPE 'RESISTOR' 
PRP PARENT_PPT 'RESISTOR' 
PRP PARENT_PPT_PART 'RESISTOR-G155-14701-01,4.7KOHM,1%' 
PRP PART_NAME 'RESISTOR' 
TOP 0 3.881 3.81 0.0 N 482 4 1
TOP 1 3.839 3.81 0.0 N 1 168 2
#
# CMP 132
CMP 56 4.15 2.531 90.0 N R328 ??? ;0=1,1=0.016000
PRP SIGNAL_MODEL 'RESISTOR-G155-100R0-J0_0OHM_-' 
PRP ALT_SYMBOLS '(SMC_0402R_C_H016)' 
PRP PARENT_PART_TYPE 'RESISTOR' 
PRP PARENT_PPT 'RESISTOR' 
PRP PARENT_PPT_PART 'RESISTOR-G155-14701-01,4.7KOHM,1%' 
PRP PART_NAME 'RESISTOR' 
TOP 0 4.15 2.552 90.0 N 2 568 1
TOP 1 4.15 2.51 90.0 N 397 2 2
#
# CMP 133
CMP 56 4.209 2.531 90.0 N R326 ??? ;0=1,1=0.016000
PRP SIGNAL_MODEL 'RESISTOR-G155-100R0-J0_0OHM_-' 
PRP ALT_SYMBOLS '(SMC_0402R_C_H016)' 
PRP PARENT_PART_TYPE 'RESISTOR' 
PRP PARENT_PPT 'RESISTOR' 
PRP PARENT_PPT_PART 'RESISTOR-G155-14701-01,4.7KOHM,1%' 
PRP PART_NAME 'RESISTOR' 
TOP 0 4.209 2.552 90.0 N 2 569 1
TOP 1 4.209 2.51 90.0 N 396 2 2
#
# CMP 134
CMP 56 4.093 2.531 90.0 N R309 ??? ;0=1,1=0.016000
PRP SIGNAL_MODEL 'RESISTOR-G155-100R0-J0_0OHM_-' 
PRP ALT_SYMBOLS '(SMC_0402R_C_H016)' 
PRP PARENT_PART_TYPE 'RESISTOR' 
PRP PARENT_PPT 'RESISTOR' 
PRP PARENT_PPT_PART 'RESISTOR-G155-14701-01,4.7KOHM,1%' 
PRP PART_NAME 'RESISTOR' 
TOP 0 4.093 2.552 90.0 N 2 570 1
TOP 1 4.093 2.51 90.0 N 382 2 2
#
# CMP 135
CMP 56 3.801 2.531 90.0 N R286 ??? ;0=1,1=0.016000
PRP SIGNAL_MODEL 'RESISTOR-G155-100R0-J0_0OHM_-' 
PRP ALT_SYMBOLS '(SMC_0402R_C_H016)' 
PRP PARENT_PART_TYPE 'RESISTOR' 
PRP PARENT_PPT 'RESISTOR' 
PRP PARENT_PPT_PART 'RESISTOR-G155-14701-01,4.7KOHM,1%' 
PRP PART_NAME 'RESISTOR' 
TOP 0 3.801 2.552 90.0 N 2 571 1
TOP 1 3.801 2.51 90.0 N 366 2 2
#
# CMP 136
CMP 56 3.86 2.531 90.0 N R284 ??? ;0=1,1=0.016000
PRP SIGNAL_MODEL 'RESISTOR-G155-100R0-J0_0OHM_-' 
PRP ALT_SYMBOLS '(SMC_0402R_C_H016)' 
PRP PARENT_PART_TYPE 'RESISTOR' 
PRP PARENT_PPT 'RESISTOR' 
PRP PARENT_PPT_PART 'RESISTOR-G155-14701-01,4.7KOHM,1%' 
PRP PART_NAME 'RESISTOR' 
TOP 0 3.86 2.552 90.0 N 2 572 1
TOP 1 3.86 2.51 90.0 N 365 2 2
#
# CMP 137
CMP 56 0.725 3.155 0.0 N R473 ??? ;0=1,1=0.016000
PRP SIGNAL_MODEL 'RESISTOR-G155-100R0-J0_0OHM_-' 
PRP ALT_SYMBOLS '(SMC_0402R_C_H016,C0402-0P8MM-45DG)' 
PRP PARENT_PART_TYPE 'RESISTOR' 
PRP PARENT_PPT 'RESISTOR' 
PRP PARENT_PPT_PART 'RESISTOR-G155-100R0-J0,0OHM,-' 
PRP PART_NAME 'RESISTOR' 
TOP 0 0.746 3.155 0.0 N 507 1 1
TOP 1 0.704 3.155 0.0 N 506 3 2
#
# CMP 138
CMP 56 0.89 3.41 180.0 N R470 ??? ;0=1,1=0.016000
PRP SIGNAL_MODEL 'DEFAULT_RESISTOR_33OHM_2_1' 
PRP ALT_SYMBOLS '(SMC_0402R_C_H016)' 
PRP PARENT_PART_TYPE 'RESISTOR' 
PRP PARENT_PPT 'RESISTOR' 
PRP PARENT_PPT_PART 'RESISTOR-G155-133R0-01,33OHM,1%' 
PRP PART_NAME 'RESISTOR' 
TOP 0 0.869 3.41 180.0 N 501 1 1
TOP 1 0.911 3.41 180.0 N 502 1 2
#
# CMP 139
CMP 56 0.89 3.5 180.0 N R469 ??? ;0=1,1=0.016000
PRP SIGNAL_MODEL 'DEFAULT_RESISTOR_33OHM_2_1' 
PRP ALT_SYMBOLS '(SMC_0402R_C_H016)' 
PRP PARENT_PART_TYPE 'RESISTOR' 
PRP PARENT_PPT 'RESISTOR' 
PRP PARENT_PPT_PART 'RESISTOR-G155-133R0-01,33OHM,1%' 
PRP PART_NAME 'RESISTOR' 
TOP 0 0.869 3.5 180.0 N 495 1 1
TOP 1 0.911 3.5 180.0 N 500 1 2
#
# CMP 140
CMP 56 0.882 3.574 270.0 N R468 ??? ;0=1,1=0.016000
PRP SIGNAL_MODEL 'DEFAULT_RESISTOR_33OHM_2_1' 
PRP ALT_SYMBOLS '(SMC_0402R_C_H016)' 
PRP PARENT_PART_TYPE 'RESISTOR' 
PRP PARENT_PPT 'RESISTOR' 
PRP PARENT_PPT_PART 'RESISTOR-G155-133R0-01,33OHM,1%' 
PRP PART_NAME 'RESISTOR' 
TOP 0 0.882 3.553 270.0 N 498 1 1
TOP 1 0.882 3.595 270.0 N 499 1 2
#
# CMP 141
CMP 56 0.95 3.585 270.0 N R467 ??? ;0=1,1=0.016000
PRP SIGNAL_MODEL 'DEFAULT_RESISTOR_33OHM_2_1' 
PRP ALT_SYMBOLS '(SMC_0402R_C_H016)' 
PRP PARENT_PART_TYPE 'RESISTOR' 
PRP PARENT_PPT 'RESISTOR' 
PRP PARENT_PPT_PART 'RESISTOR-G155-133R0-01,33OHM,1%' 
PRP PART_NAME 'RESISTOR' 
TOP 0 0.95 3.564 270.0 N 496 1 1
TOP 1 0.95 3.606 270.0 N 497 1 2
#
# CMP 142
CMP 56 5.98 1.76 90.0 N R434 ??? ;0=1,1=0.016000
PRP SIGNAL_MODEL 'DEFAULT_RESISTOR_33OHM_2_1' 
PRP ALT_SYMBOLS '(SMC_0402R_C_H016)' 
PRP PARENT_PART_TYPE 'RESISTOR' 
PRP PARENT_PPT 'RESISTOR' 
PRP PARENT_PPT_PART 'RESISTOR-G155-133R0-01,33OHM,1%' 
PRP PART_NAME 'RESISTOR' 
TOP 0 5.98 1.781 90.0 N 215 1 1
TOP 1 5.98 1.739 90.0 N 304 2 2
#
# CMP 143
CMP 56 5.98 1.655 90.0 N R433 ??? ;0=1,1=0.016000
PRP SIGNAL_MODEL 'DEFAULT_RESISTOR_33OHM_2_1' 
PRP ALT_SYMBOLS '(SMC_0402R_C_H016)' 
PRP PARENT_PART_TYPE 'RESISTOR' 
PRP PARENT_PPT 'RESISTOR' 
PRP PARENT_PPT_PART 'RESISTOR-G155-133R0-01,33OHM,1%' 
PRP PART_NAME 'RESISTOR' 
TOP 0 5.98 1.676 90.0 N 217 1 1
TOP 1 5.98 1.634 90.0 N 305 2 2
#
# CMP 144
CMP 56 5.98 1.56 90.0 N R432 ??? ;0=1,1=0.016000
PRP SIGNAL_MODEL 'DEFAULT_RESISTOR_33OHM_2_1' 
PRP ALT_SYMBOLS '(SMC_0402R_C_H016)' 
PRP PARENT_PART_TYPE 'RESISTOR' 
PRP PARENT_PPT 'RESISTOR' 
PRP PARENT_PPT_PART 'RESISTOR-G155-133R0-01,33OHM,1%' 
PRP PART_NAME 'RESISTOR' 
TOP 0 5.98 1.581 90.0 N 219 1 1
TOP 1 5.98 1.539 90.0 N 365 3 2
#
# CMP 145
CMP 56 5.98 1.44 90.0 N R431 ??? ;0=1,1=0.016000
PRP SIGNAL_MODEL 'DEFAULT_RESISTOR_33OHM_2_1' 
PRP ALT_SYMBOLS '(SMC_0402R_C_H016)' 
PRP PARENT_PART_TYPE 'RESISTOR' 
PRP PARENT_PPT 'RESISTOR' 
PRP PARENT_PPT_PART 'RESISTOR-G155-133R0-01,33OHM,1%' 
PRP PART_NAME 'RESISTOR' 
TOP 0 5.98 1.461 90.0 N 221 1 1
TOP 1 5.98 1.419 90.0 N 366 3 2
#
# CMP 146
CMP 56 6.155 1.79 90.0 N R430 ??? ;0=1,1=0.016000
PRP SIGNAL_MODEL 'DEFAULT_RESISTOR_33OHM_2_1' 
PRP ALT_SYMBOLS '(SMC_0402R_C_H016)' 
PRP PARENT_PART_TYPE 'RESISTOR' 
PRP PARENT_PPT 'RESISTOR' 
PRP PARENT_PPT_PART 'RESISTOR-G155-133R0-01,33OHM,1%' 
PRP PART_NAME 'RESISTOR' 
TOP 0 6.155 1.811 90.0 N 373 2 1
TOP 1 6.155 1.769 90.0 N 214 1 2
#
# CMP 147
CMP 56 6.17 1.655 270.0 N R429 ??? ;0=1,1=0.016000
PRP SIGNAL_MODEL 'DEFAULT_RESISTOR_33OHM_2_1' 
PRP ALT_SYMBOLS '(SMC_0402R_C_H016)' 
PRP PARENT_PART_TYPE 'RESISTOR' 
PRP PARENT_PPT 'RESISTOR' 
PRP PARENT_PPT_PART 'RESISTOR-G155-133R0-01,33OHM,1%' 
PRP PART_NAME 'RESISTOR' 
TOP 0 6.17 1.634 270.0 N 382 3 1
TOP 1 6.17 1.676 270.0 N 216 1 2
#
# CMP 148
CMP 56 6.17 1.555 270.0 N R428 ??? ;0=1,1=0.016000
PRP SIGNAL_MODEL 'DEFAULT_RESISTOR_33OHM_2_1' 
PRP ALT_SYMBOLS '(SMC_0402R_C_H016)' 
PRP PARENT_PART_TYPE 'RESISTOR' 
PRP PARENT_PPT 'RESISTOR' 
PRP PARENT_PPT_PART 'RESISTOR-G155-133R0-01,33OHM,1%' 
PRP PART_NAME 'RESISTOR' 
TOP 0 6.17 1.534 270.0 N 396 3 1
TOP 1 6.17 1.576 270.0 N 218 1 2
#
# CMP 149
CMP 56 6.17 1.455 270.0 N R329 ??? ;0=1,1=0.016000
PRP SIGNAL_MODEL 'DEFAULT_RESISTOR_33OHM_2_1' 
PRP ALT_SYMBOLS '(SMC_0402R_C_H016)' 
PRP PARENT_PART_TYPE 'RESISTOR' 
PRP PARENT_PPT 'RESISTOR' 
PRP PARENT_PPT_PART 'RESISTOR-G155-133R0-01,33OHM,1%' 
PRP PART_NAME 'RESISTOR' 
TOP 0 6.17 1.434 270.0 N 397 3 1
TOP 1 6.17 1.476 270.0 N 220 1 2
#
# CMP 150
CMP 56 4.715 0.915 180.0 N R483 ??? ;0=1,1=0.016000
PRP ALT_SYMBOLS '(SMC_0402R_C_H016)' 
PRP PARENT_PART_TYPE 'RESISTOR' 
PRP PARENT_PPT 'RESISTOR' 
PRP PARENT_PPT_PART 'RESISTOR-G155-11001-01,1KOHM,1%' 
PRP PART_NAME 'RESISTOR' 
TOP 0 4.694 0.915 180.0 N 2 573 1
TOP 1 4.736 0.915 180.0 N 512 5 2
#
# CMP 151
CMP 56 1.04 3.585 90.0 N R460 ??? ;0=1,1=0.016000
PRP ALT_SYMBOLS '(SMC_0402R_C_H016)' 
PRP PARENT_PART_TYPE 'RESISTOR' 
PRP PARENT_PPT 'RESISTOR' 
PRP PARENT_PPT_PART 'RESISTOR-G155-11001-01,1KOHM,1%' 
PRP PART_NAME 'RESISTOR' 
TOP 0 1.04 3.606 90.0 N 245 4 1
TOP 1 1.04 3.564 90.0 N 491 1 2
#
# CMP 152
CMP 56 3.994 3.239 180.0 N R458 ??? ;0=1,1=0.016000
PRP ALT_SYMBOLS '(SMC_0402R_C_H016)' 
PRP PARENT_PART_TYPE 'RESISTOR' 
PRP PARENT_PPT 'RESISTOR' 
PRP PARENT_PPT_PART 'RESISTOR-G155-11001-01,1KOHM,1%' 
PRP PART_NAME 'RESISTOR' 
TOP 0 3.973 3.239 180.0 N 2 574 1
TOP 1 4.015 3.239 180.0 N 488 7 2
#
# CMP 153
CMP 56 3.86 3.758 0.0 N R451 ??? ;0=1,1=0.016000
PRP ALT_SYMBOLS '(SMC_0402R_C_H016)' 
PRP PARENT_PART_TYPE 'RESISTOR' 
PRP PARENT_PPT 'RESISTOR' 
PRP PARENT_PPT_PART 'RESISTOR-G155-11001-01,1KOHM,1%' 
PRP PART_NAME 'RESISTOR' 
TOP 0 3.881 3.758 0.0 N 482 5 1
TOP 1 3.839 3.758 0.0 N 2 575 2
#
# CMP 154
CMP 56 0.725 3.2 180.0 N R479 ??? ;0=1,1=0.016000
PRP ALT_SYMBOLS '(SMC_0402R_C_H016)' 
PRP PARENT_PART_TYPE 'RESISTOR' 
PRP PARENT_PPT 'RESISTOR' 
PRP PARENT_PPT_PART 'RESISTOR-G155-11003-01,100KOHM,1%' 
PRP PART_NAME 'RESISTOR' 
TOP 0 0.704 3.2 180.0 N 506 4 1
TOP 1 0.746 3.2 180.0 N 88 19 2
#
# CMP 155
CMP 56 0.725 3.245 180.0 N R478 ??? ;0=1,1=0.016000
PRP ALT_SYMBOLS '(SMC_0402R_C_H016)' 
PRP PARENT_PART_TYPE 'RESISTOR' 
PRP PARENT_PPT 'RESISTOR' 
PRP PARENT_PPT_PART 'RESISTOR-G155-11003-01,100KOHM,1%' 
PRP PART_NAME 'RESISTOR' 
TOP 0 0.704 3.245 180.0 N 504 3 1
TOP 1 0.746 3.245 180.0 N 88 20 2
#
# CMP 156
CMP 56 0.89 3.455 180.0 N R466 ??? ;0=1,1=0.016000
PRP ALT_SYMBOLS '(SMC_0402R_C_H016)' 
PRP PARENT_PART_TYPE 'RESISTOR' 
PRP PARENT_PPT 'RESISTOR' 
PRP PARENT_PPT_PART 'RESISTOR-G155-11003-01,100KOHM,1%' 
PRP PART_NAME 'RESISTOR' 
TOP 0 0.869 3.455 180.0 N 495 2 1
TOP 1 0.911 3.455 180.0 N 88 21 2
#
# CMP 157
CMP 56 1.885 2.96 270.0 N R488 ??? ;0=1,1=0.016000
PRP SIGNAL_MODEL 'RESISTOR-G155-100R0-J0_0OHM_-' 
PRP ALT_SYMBOLS '(SMC_0402R_C_H016)' 
PRP PARENT_PART_TYPE 'RESISTOR' 
PRP PARENT_PPT 'RESISTOR' 
PRP PARENT_PPT_PART 'RESISTOR-G155-11002-01,10KOHM,1%' 
PRP PART_NAME 'RESISTOR' 
TOP 0 1.885 2.939 270.0 N 86 3 1
TOP 1 1.885 2.981 270.0 N 2 576 2
#
# CMP 158
CMP 56 2.125 3.5 0.0 N R447 ??? ;0=1,1=0.016000
PRP SIGNAL_MODEL 'RESISTOR-G155-100R0-J0_0OHM_-' 
PRP ALT_SYMBOLS '(SMC_0402R_C_H016)' 
PRP PARENT_PART_TYPE 'RESISTOR' 
PRP PARENT_PPT 'RESISTOR' 
PRP PARENT_PPT_PART 'RESISTOR-G155-11002-01,10KOHM,1%' 
PRP PART_NAME 'RESISTOR' 
TOP 0 2.146 3.5 0.0 N 88 22 1
TOP 1 2.104 3.5 0.0 N 481 2 2
#
# CMP 159
CMP 56 2.125 3.55 0.0 N R446 ??? ;0=1,1=0.016000
PRP SIGNAL_MODEL 'RESISTOR-G155-100R0-J0_0OHM_-' 
PRP ALT_SYMBOLS '(SMC_0402R_C_H016)' 
PRP PARENT_PART_TYPE 'RESISTOR' 
PRP PARENT_PPT 'RESISTOR' 
PRP PARENT_PPT_PART 'RESISTOR-G155-11002-01,10KOHM,1%' 
PRP PART_NAME 'RESISTOR' 
TOP 0 2.146 3.55 0.0 N 88 23 1
TOP 1 2.104 3.55 0.0 N 480 2 2
#
# CMP 160
CMP 56 2.125 3.36 0.0 N R444 ??? ;0=1,1=0.016000
PRP SIGNAL_MODEL 'RESISTOR-G155-100R0-J0_0OHM_-' 
PRP ALT_SYMBOLS '(SMC_0402R_C_H016)' 
PRP PARENT_PART_TYPE 'RESISTOR' 
PRP PARENT_PPT 'RESISTOR' 
PRP PARENT_PPT_PART 'RESISTOR-G155-11002-01,10KOHM,1%' 
PRP PART_NAME 'RESISTOR' 
TOP 0 2.146 3.36 0.0 N 88 24 1
TOP 1 2.104 3.36 0.0 N 479 1 2
#
# CMP 161
CMP 56 4.585 1.16 90.0 N R441 ??? ;0=1,1=0.016000
PRP SIGNAL_MODEL 'RESISTOR-G155-100R0-J0_0OHM_-' 
PRP ALT_SYMBOLS '(SMC_0402R_C_H016)' 
PRP PARENT_PART_TYPE 'RESISTOR' 
PRP PARENT_PPT 'RESISTOR' 
PRP PARENT_PPT_PART 'RESISTOR-G155-11002-01,10KOHM,1%' 
PRP PART_NAME 'RESISTOR' 
TOP 0 4.585 1.181 90.0 N 358 4 1
TOP 1 4.585 1.139 90.0 N 2 577 2
#
# CMP 162
CMP 56 4.53 1.16 90.0 N R440 ??? ;0=1,1=0.016000
PRP SIGNAL_MODEL 'RESISTOR-G155-100R0-J0_0OHM_-' 
PRP ALT_SYMBOLS '(SMC_0402R_C_H016)' 
PRP PARENT_PART_TYPE 'RESISTOR' 
PRP PARENT_PPT 'RESISTOR' 
PRP PARENT_PPT_PART 'RESISTOR-G155-11002-01,10KOHM,1%' 
PRP PART_NAME 'RESISTOR' 
TOP 0 4.53 1.181 90.0 N 357 4 1
TOP 1 4.53 1.139 90.0 N 2 578 2
#
# CMP 163
CMP 56 1.645 3.885 180.0 N R31 ??? ;0=1,1=0.016000
PRP SIGNAL_MODEL 'RESISTOR-G155-100R0-J0_0OHM_-' 
PRP REUSE_ID '7' 
PRP ALT_SYMBOLS '(SMC_0402R_C_H016,C0402-0P8MM-45DG)' 
PRP PARENT_PART_TYPE 'RESISTOR' 
PRP PARENT_PPT 'RESISTOR' 
PRP PARENT_PPT_PART 'RESISTOR-G155-100R0-J0,0OHM,-' 
PRP PART_NAME 'RESISTOR' 
TOP 0 1.624 3.885 180.0 N 383 1 1
TOP 1 1.666 3.885 180.0 N 106 0 2
#
# CMP 164
CMP 56 3.365 4.095 0.0 N R37 ??? ;0=1,1=0.016000
PRP SIGNAL_MODEL 'RESISTOR-G155-100R0-J0_0OHM_-' 
PRP REUSE_ID '7' 
PRP ALT_SYMBOLS '(SMC_0402R_C_H016,C0402-0P8MM-45DG)' 
PRP PARENT_PART_TYPE 'RESISTOR' 
PRP PARENT_PPT 'RESISTOR' 
PRP PARENT_PPT_PART 'RESISTOR-G155-100R0-J0,0OHM,-' 
PRP PART_NAME 'RESISTOR' 
TOP 0 3.386 4.095 0.0 N 432 1 1
TOP 1 3.344 4.095 0.0 N 117 0 2
#
# CMP 165
CMP 56 3.047 3.21 180.0 N R61 ??? ;0=1,1=0.016000
PRP SIGNAL_MODEL 'RESISTOR-G155-100R0-J0_0OHM_-' 
PRP ALT_SYMBOLS '(SMC_0402R_C_H016,C0402-0P8MM-45DG)' 
PRP PARENT_PART_TYPE 'RESISTOR' 
PRP PARENT_PPT 'RESISTOR' 
PRP PARENT_PPT_PART 'RESISTOR-G155-100R0-J0,0OHM,-' 
PRP PART_NAME 'RESISTOR' 
TOP 0 3.026 3.21 180.0 N 102 2 1
TOP 1 3.068 3.21 180.0 N 9 35 2
#
# CMP 166
CMP 56 3.047 3.26 180.0 N R62 ??? ;0=1,1=0.016000
PRP SIGNAL_MODEL 'RESISTOR-G155-100R0-J0_0OHM_-' 
PRP ALT_SYMBOLS '(SMC_0402R_C_H016,C0402-0P8MM-45DG)' 
PRP PARENT_PART_TYPE 'RESISTOR' 
PRP PARENT_PPT 'RESISTOR' 
PRP PARENT_PPT_PART 'RESISTOR-G155-100R0-J0,0OHM,-' 
PRP PART_NAME 'RESISTOR' 
TOP 0 3.026 3.26 180.0 N 102 3 1
TOP 1 3.068 3.26 180.0 N 1 169 2
#
# CMP 167
CMP 56 4.905 1.855 0.0 N R92 ??? ;0=1,1=0.016000
PRP SIGNAL_MODEL 'RESISTOR-G155-100R0-J0_0OHM_-' 
PRP ALT_SYMBOLS '(SMC_0402R_C_H016,C0402-0P8MM-45DG)' 
PRP PARENT_PART_TYPE 'RESISTOR' 
PRP PARENT_PPT 'RESISTOR' 
PRP PARENT_PPT_PART 'RESISTOR-G155-100R0-J0,0OHM,-' 
PRP PART_NAME 'RESISTOR' 
TOP 0 4.926 1.855 0.0 N 227 1 1
TOP 1 4.884 1.855 0.0 N 517 2 2
#
# CMP 168
CMP 56 5.51 2.15 90.0 N R250 ??? ;0=1,1=0.016000
PRP SIGNAL_MODEL 'RESISTOR-G155-100R0-J0_0OHM_-' 
PRP ALT_SYMBOLS '(SMC_0402R_C_H016,C0402-0P8MM-45DG)' 
PRP PARENT_PART_TYPE 'RESISTOR' 
PRP PARENT_PPT 'RESISTOR' 
PRP PARENT_PPT_PART 'RESISTOR-G155-100R0-J0,0OHM,-' 
PRP PART_NAME 'RESISTOR' 
TOP 0 5.51 2.171 90.0 N 349 1 1
TOP 1 5.51 2.129 90.0 N 63 0 2
#
# CMP 169
CMP 56 0.858 2.81 270.0 N R343 ??? ;0=1,1=0.016000
PRP HARD_LOCATION 'YES' 
PRP SIGNAL_MODEL 'RESISTOR-G155-100R0-J0_0OHM_-' 
PRP ALT_SYMBOLS '(SMC_0402R_C_H016,C0402-0P8MM-45DG)' 
PRP PARENT_PART_TYPE 'RESISTOR' 
PRP PARENT_PPT 'RESISTOR' 
PRP PARENT_PPT_PART 'RESISTOR-G155-100R0-J0,0OHM,-' 
PRP PART_NAME 'RESISTOR' 
TOP 0 0.858 2.789 270.0 N 409 1 1
TOP 1 0.858 2.831 270.0 N 2 579 2
#
# CMP 170
CMP 56 1.446 3.851 180.0 N R47 ??? ;0=1,1=0.016000
PRP SIGNAL_MODEL 'RESISTOR-G155-100R0-J0_0OHM_-' 
PRP REUSE_ID '23' 
PRP ALT_SYMBOLS '(SMC_0402R_C_H016)' 
PRP PARENT_PART_TYPE 'RESISTOR' 
PRP PARENT_PPT 'RESISTOR' 
PRP PARENT_PPT_PART 'RESISTOR-G155-11002-01,10KOHM,1%' 
PRP PART_NAME 'RESISTOR' 
TOP 0 1.425 3.851 180.0 N 19 28 1
TOP 1 1.467 3.851 180.0 N 126 3 2
#
# CMP 171
CMP 56 1.561 3.776 0.0 N R49 ??? ;0=1,1=0.016000
PRP SIGNAL_MODEL 'RESISTOR-G155-100R0-J0_0OHM_-' 
PRP REUSE_ID '17' 
PRP ALT_SYMBOLS '(SMC_0402R_C_H016)' 
PRP PARENT_PART_TYPE 'RESISTOR' 
PRP PARENT_PPT 'RESISTOR' 
PRP PARENT_PPT_PART 'RESISTOR-G155-11002-01,10KOHM,1%' 
PRP PART_NAME 'RESISTOR' 
TOP 0 1.582 3.776 0.0 N 84 7 1
TOP 1 1.54 3.776 0.0 N 82 2 2
#
# CMP 172
CMP 56 3.56 4.13 0.0 N R51 ??? ;0=1,1=0.016000
PRP SIGNAL_MODEL 'RESISTOR-G155-100R0-J0_0OHM_-' 
PRP REUSE_ID '14' 
PRP ALT_SYMBOLS '(SMC_0402R_C_H016)' 
PRP PARENT_PART_TYPE 'RESISTOR' 
PRP PARENT_PPT 'RESISTOR' 
PRP PARENT_PPT_PART 'RESISTOR-G155-11002-01,10KOHM,1%' 
PRP PART_NAME 'RESISTOR' 
TOP 0 3.581 4.13 0.0 N 19 29 1
TOP 1 3.539 4.13 0.0 N 127 2 2
#
# CMP 173
CMP 56 0.995 3.585 90.0 N R130 ??? ;0=1,1=0.016000
PRP SIGNAL_MODEL 'RESISTOR-G155-100R0-J0_0OHM_-' 
PRP ALT_SYMBOLS '(SMC_0402R_C_H016)' 
PRP PARENT_PART_TYPE 'RESISTOR' 
PRP PARENT_PPT 'RESISTOR' 
PRP PARENT_PPT_PART 'RESISTOR-G155-11002-01,10KOHM,1%' 
PRP PART_NAME 'RESISTOR' 
TOP 0 0.995 3.606 90.0 N 245 5 1
TOP 1 0.995 3.564 90.0 N 2 580 2
#
# CMP 174
CMP 56 5.465 2.345 90.0 N R247 ??? ;0=1,1=0.016000
PRP SIGNAL_MODEL 'RESISTOR-G155-100R0-J0_0OHM_-' 
PRP ALT_SYMBOLS '(SMC_0402R_C_H016)' 
PRP PARENT_PART_TYPE 'RESISTOR' 
PRP PARENT_PPT 'RESISTOR' 
PRP PARENT_PPT_PART 'RESISTOR-G155-11002-01,10KOHM,1%' 
PRP PART_NAME 'RESISTOR' 
TOP 0 5.465 2.366 90.0 N 55 7 1
TOP 1 5.465 2.324 90.0 N 54 2 2
#
# CMP 175
CMP 56 4.345 2.975 180.0 N R295 ??? ;0=1,1=0.016000
PRP SIGNAL_MODEL 'RESISTOR-G155-100R0-J0_0OHM_-' 
PRP ALT_SYMBOLS '(SMC_0402R_C_H016)' 
PRP PARENT_PART_TYPE 'RESISTOR' 
PRP PARENT_PPT 'RESISTOR' 
PRP PARENT_PPT_PART 'RESISTOR-G155-11002-01,10KOHM,1%' 
PRP PART_NAME 'RESISTOR' 
TOP 0 4.324 2.975 180.0 N 1 170 1
TOP 1 4.366 2.975 180.0 N 286 2 2
#
# CMP 176
CMP 56 4.37 1.1 90.0 N R355 ??? ;0=1,1=0.016000
PRP SIGNAL_MODEL 'RESISTOR-G155-100R0-J0_0OHM_-' 
PRP ALT_SYMBOLS '(SMC_0402R_C_H016)' 
PRP PARENT_PART_TYPE 'RESISTOR' 
PRP PARENT_PPT 'RESISTOR' 
PRP PARENT_PPT_PART 'RESISTOR-G155-11002-01,10KOHM,1%' 
PRP PART_NAME 'RESISTOR' 
TOP 0 4.37 1.121 90.0 N 49 4 1
TOP 1 4.37 1.079 90.0 N 9 36 2
#
# CMP 177
CMP 56 4.415 1.1 90.0 N R358 ??? ;0=1,1=0.016000
PRP HARD_LOCATION 'YES' 
PRP SIGNAL_MODEL 'RESISTOR-G155-100R0-J0_0OHM_-' 
PRP ALT_SYMBOLS '(SMC_0402R_C_H016)' 
PRP PARENT_PART_TYPE 'RESISTOR' 
PRP PARENT_PPT 'RESISTOR' 
PRP PARENT_PPT_PART 'RESISTOR-G155-11002-01,10KOHM,1%' 
PRP PART_NAME 'RESISTOR' 
TOP 0 4.415 1.121 90.0 N 47 4 1
TOP 1 4.415 1.079 90.0 N 9 37 2
#
# CMP 178
CMP 56 0.833 0.932 90.0 N R161 ??? ;0=1,1=0.016000
PRP SIGNAL_MODEL 'RESISTOR-G155-100R0-J0_0OHM_-' 
PRP REUSE_ID '4' 
PRP ALT_SYMBOLS '(SMC_0402R_C_H016)' 
PRP PARENT_PART_TYPE 'RESISTOR' 
PRP PARENT_PPT 'RESISTOR' 
PRP PARENT_PPT_PART 'RESISTOR-G155-14701-01,4.7KOHM,1%' 
PRP PART_NAME 'RESISTOR' 
TOP 0 0.833 0.953 90.0 N 301 1 1
TOP 1 0.833 0.911 90.0 N 2 581 2
#
# CMP 179
CMP 56 0.698 0.932 90.0 N R163 ??? ;0=1,1=0.016000
PRP SIGNAL_MODEL 'RESISTOR-G155-100R0-J0_0OHM_-' 
PRP REUSE_ID '7' 
PRP ALT_SYMBOLS '(SMC_0402R_C_H016)' 
PRP PARENT_PART_TYPE 'RESISTOR' 
PRP PARENT_PPT 'RESISTOR' 
PRP PARENT_PPT_PART 'RESISTOR-G155-14701-01,4.7KOHM,1%' 
PRP PART_NAME 'RESISTOR' 
TOP 0 0.698 0.953 90.0 N 302 1 1
TOP 1 0.698 0.911 90.0 N 2 582 2
#
# CMP 180
CMP 56 3.919 2.531 90.0 N R173 ??? ;0=1,1=0.016000
PRP SIGNAL_MODEL 'RESISTOR-G155-100R0-J0_0OHM_-' 
PRP REUSE_ID '2' 
PRP ALT_SYMBOLS '(SMC_0402R_C_H016)' 
PRP PARENT_PART_TYPE 'RESISTOR' 
PRP PARENT_PPT 'RESISTOR' 
PRP PARENT_PPT_PART 'RESISTOR-G155-14701-01,4.7KOHM,1%' 
PRP PART_NAME 'RESISTOR' 
TOP 0 3.919 2.552 90.0 N 2 583 1
TOP 1 3.919 2.51 90.0 N 305 3 2
#
# CMP 181
CMP 56 0.53 0.676 270.0 N R123 ??? ;0=1,1=0.016000
PRP HARD_LOCATION 'YES' 
PRP SIGNAL_MODEL 'RESISTOR-G155-049R9-01_49.9OHMA' 
PRP REUSE_ID '6' 
PRP ALT_SYMBOLS '(SMC_0402R_C_H016)' 
PRP PARENT_PART_TYPE 'RESISTOR' 
PRP PARENT_PPT 'RESISTOR' 
PRP PARENT_PPT_PART 'RESISTOR-G155-149R9-01,49.9OHM,1%' 
PRP PART_NAME 'RESISTOR' 
TOP 0 0.53 0.655 270.0 N 269 3 1
TOP 1 0.53 0.697 270.0 N 137 2 2
#
# CMP 182
CMP 56 5.754 2.345 90.0 N R251 ??? ;0=1,1=0.016000
PRP ALT_SYMBOLS '(SMC_0402R_C_H016)' 
PRP PARENT_PART_TYPE 'RESISTOR' 
PRP PARENT_PPT 'RESISTOR' 
PRP PARENT_PPT_PART 'RESISTOR-G155-03322-01,33.2KOHM,1%' 
PRP PART_NAME 'RESISTOR' 
TOP 0 5.754 2.366 90.0 N 58 6 1
TOP 1 5.754 2.324 90.0 N 67 4 2
#
# CMP 183
CMP 56 0.697 1.599 180.0 N R144 ??? ;0=1,1=0.016000
PRP SIGNAL_MODEL 'DEFAULT_RESISTOR_33OHM_2_1' 
PRP ALT_SYMBOLS '(SMC_0402R_C_H016)' 
PRP PARENT_PART_TYPE 'RESISTOR' 
PRP PARENT_PPT 'RESISTOR' 
PRP PARENT_PPT_PART 'RESISTOR-G155-133R0-01,33OHM,1%' 
PRP PART_NAME 'RESISTOR' 
TOP 0 0.676 1.599 180.0 N 287 1 1
TOP 1 0.718 1.599 180.0 N 288 2 2
#
# CMP 184
CMP 56 0.829 1.549 0.0 N R148 ??? ;0=1,1=0.016000
PRP HARD_LOCATION 'YES' 
PRP SIGNAL_MODEL 'RESISTOR-G155-100R0-J0_0OHM_-' 
PRP ALT_SYMBOLS '(SMC_0402R_C_H016)' 
PRP PARENT_PART_TYPE 'RESISTOR' 
PRP PARENT_PPT 'RESISTOR' 
PRP PARENT_PPT_PART 'RESISTOR-G155-11002-01,10KOHM,1%' 
PRP PART_NAME 'RESISTOR' 
TOP 0 0.85 1.549 0.0 N 1 171 1
TOP 1 0.808 1.549 0.0 N 290 2 2
#
# CMP 185
CMP 56 0.695 1.495 180.0 N R59 ??? ;0=1,1=0.016000
PRP SIGNAL_MODEL 'DEFAULT_RESISTOR_33OHM_2_1' 
PRP ALT_SYMBOLS '(SMC_0402R_C_H016)' 
PRP PARENT_PART_TYPE 'RESISTOR' 
PRP PARENT_PPT 'RESISTOR' 
PRP PARENT_PPT_PART 'RESISTOR-G155-133R0-01,33OHM,1%' 
PRP PART_NAME 'RESISTOR' 
TOP 0 0.674 1.495 180.0 N 224 1 1
TOP 1 0.716 1.495 180.0 N 290 3 2
#
# CMP 186
CMP 56 0.825 1.5 0.0 N R27 ??? ;0=1,1=0.016000
PRP SIGNAL_MODEL 'DEFAULT_RESISTOR_33OHM_2_1' 
PRP ALT_SYMBOLS '(SMC_0402R_C_H016)' 
PRP PARENT_PART_TYPE 'RESISTOR' 
PRP PARENT_PPT 'RESISTOR' 
PRP PARENT_PPT_PART 'RESISTOR-G155-133R0-01,33OHM,1%' 
PRP PART_NAME 'RESISTOR' 
TOP 0 0.846 1.5 0.0 N 307 1 1
TOP 1 0.804 1.5 0.0 N 290 4 2
#
# CMP 187
CMP 56 0.72 2.915 0.0 N R340 ??? ;0=1,1=0.016000
PRP SIGNAL_MODEL 'RESISTOR-G155-100R0-J0_0OHM_-' 
PRP ALT_SYMBOLS '(SMC_0402R_C_H016)' 
PRP PARENT_PART_TYPE 'RESISTOR' 
PRP PARENT_PPT 'RESISTOR' 
PRP PARENT_PPT_PART 'RESISTOR-G155-14701-01,4.7KOHM,1%' 
PRP PART_NAME 'RESISTOR' 
TOP 0 0.741 2.915 0.0 N 1 172 1
TOP 1 0.699 2.915 0.0 N 407 3 2
#
# CMP 188
CMP 56 0.66 3.035 90.0 N R332 ??? ;0=1,1=0.016000
PRP SIGNAL_MODEL 'DEFAULT_RESISTOR_33OHM_2_1' 
PRP ALT_SYMBOLS '(SMC_0402R_C_H016)' 
PRP PARENT_PART_TYPE 'RESISTOR' 
PRP PARENT_PPT 'RESISTOR' 
PRP PARENT_PPT_PART 'RESISTOR-G155-133R0-01,33OHM,1%' 
PRP PART_NAME 'RESISTOR' 
TOP 0 0.66 3.056 90.0 N 320 4 1
TOP 1 0.66 3.014 90.0 N 401 1 2
#
# CMP 189
CMP 56 0.577 0.676 90.0 N R379 ??? ;0=1,1=0.016000
PRP HARD_LOCATION 'YES' 
PRP SIGNAL_MODEL 'RESISTOR-G155-100R0-J0_0OHM_-' 
PRP REUSE_ID '2' 
PRP ALT_SYMBOLS '(SMC_0402R_C_H016)' 
PRP PARENT_PART_TYPE 'RESISTOR' 
PRP PARENT_PPT 'RESISTOR' 
PRP PARENT_PPT_PART 'RESISTOR-G155-14701-01,4.7KOHM,1%' 
PRP PART_NAME 'RESISTOR' 
TOP 0 0.577 0.697 90.0 N 1 173 1
TOP 1 0.577 0.655 90.0 N 444 3 2
#
# CMP 190
CMP 56 0.22 2.875 0.0 N R336 ??? ;0=1,1=0.016000
PRP ALT_SYMBOLS '(SMC_0402R_C_H016)' 
PRP PARENT_PART_TYPE 'RESISTOR' 
PRP PARENT_PPT 'RESISTOR' 
PRP PARENT_PPT_PART 'RESISTOR-G155-11001-01,1KOHM,1%' 
PRP PART_NAME 'RESISTOR' 
TOP 0 0.241 2.875 0.0 N 403 1 1
TOP 1 0.199 2.875 0.0 N 2 584 2
#
# CMP 191
CMP 56 0.22 2.925 180.0 N R335 ??? ;0=1,1=0.016000
PRP SIGNAL_MODEL 'RESISTOR-G155-100R0-J0_0OHM_-' 
PRP ALT_SYMBOLS '(SMC_0402R_C_H016)' 
PRP PARENT_PART_TYPE 'RESISTOR' 
PRP PARENT_PPT 'RESISTOR' 
PRP PARENT_PPT_PART 'RESISTOR-G155-14701-01,4.7KOHM,1%' 
PRP PART_NAME 'RESISTOR' 
TOP 0 0.199 2.925 180.0 N 1 174 1
TOP 1 0.241 2.925 180.0 N 403 2 2
#
# CMP 192
CMP 56 0.29 2.85 90.0 N R334 ??? ;0=1,1=0.016000
PRP ALT_SYMBOLS '(SMC_0402R_C_H016)' 
PRP PARENT_PART_TYPE 'RESISTOR' 
PRP PARENT_PPT 'RESISTOR' 
PRP PARENT_PPT_PART 'RESISTOR-G155-11001-01,1KOHM,1%' 
PRP PART_NAME 'RESISTOR' 
TOP 0 0.29 2.871 90.0 N 402 1 1
TOP 1 0.29 2.829 90.0 N 2 585 2
#
# CMP 193
CMP 56 0.335 2.85 270.0 N R333 ??? ;0=1,1=0.016000
PRP SIGNAL_MODEL 'RESISTOR-G155-100R0-J0_0OHM_-' 
PRP ALT_SYMBOLS '(SMC_0402R_C_H016)' 
PRP PARENT_PART_TYPE 'RESISTOR' 
PRP PARENT_PPT 'RESISTOR' 
PRP PARENT_PPT_PART 'RESISTOR-G155-14701-01,4.7KOHM,1%' 
PRP PART_NAME 'RESISTOR' 
TOP 0 0.335 2.829 270.0 N 1 175 1
TOP 1 0.335 2.871 270.0 N 402 2 2
#
# CMP 194
CMP 56 0.22 3.025 0.0 N R338 ??? ;0=1,1=0.016000
PRP ALT_SYMBOLS '(SMC_0402R_C_H016)' 
PRP PARENT_PART_TYPE 'RESISTOR' 
PRP PARENT_PPT 'RESISTOR' 
PRP PARENT_PPT_PART 'RESISTOR-G155-11001-01,1KOHM,1%' 
PRP PART_NAME 'RESISTOR' 
TOP 0 0.241 3.025 0.0 N 404 1 1
TOP 1 0.199 3.025 0.0 N 2 586 2
#
# CMP 195
CMP 56 0.22 2.975 180.0 N R337 ??? ;0=1,1=0.016000
PRP SIGNAL_MODEL 'RESISTOR-G155-100R0-J0_0OHM_-' 
PRP ALT_SYMBOLS '(SMC_0402R_C_H016)' 
PRP PARENT_PART_TYPE 'RESISTOR' 
PRP PARENT_PPT 'RESISTOR' 
PRP PARENT_PPT_PART 'RESISTOR-G155-14701-01,4.7KOHM,1%' 
PRP PART_NAME 'RESISTOR' 
TOP 0 0.199 2.975 180.0 N 1 176 1
TOP 1 0.241 2.975 180.0 N 404 2 2
#
# CMP 196
CMP 56 0.799 0.732 90.0 N R2 ??? ;0=1,1=0.016000
PRP REUSE_ID '1' 
PRP ALT_SYMBOLS '(SMC_0402R_C_H016)' 
PRP PARENT_PART_TYPE 'RESISTOR' 
PRP PARENT_PPT 'RESISTOR' 
PRP PARENT_PPT_PART 'RESISTOR-G155-13300-01,330OHM,1%' 
PRP PART_NAME 'RESISTOR' 
TOP 0 0.799 0.753 90.0 N 319 1 1
TOP 1 0.799 0.711 90.0 N 212 3 2
#
# CMP 197
CMP 56 1.3297 0.708 0.0 N R176 ??? ;0=1,1=0.016000
PRP SIGNAL_MODEL 'DEFAULT_RESISTOR_33OHM_2_1' 
PRP ALT_SYMBOLS '(SMC_0402R_C_H016)' 
PRP PARENT_PART_TYPE 'RESISTOR' 
PRP PARENT_PPT 'RESISTOR' 
PRP PARENT_PPT_PART 'RESISTOR-G155-133R0-01,33OHM,1%' 
PRP PART_NAME 'RESISTOR' 
TOP 0 1.3507 0.708 0.0 N 307 2 1
TOP 1 1.3087 0.708 0.0 N 225 6 2
#
# CMP 198
CMP 56 1.3295 0.658 0.0 N R175 ??? ;0=1,1=0.016000
PRP SIGNAL_MODEL 'DEFAULT_RESISTOR_33OHM_2_1' 
PRP ALT_SYMBOLS '(SMC_0402R_C_H016)' 
PRP PARENT_PART_TYPE 'RESISTOR' 
PRP PARENT_PPT 'RESISTOR' 
PRP PARENT_PPT_PART 'RESISTOR-G155-133R0-01,33OHM,1%' 
PRP PART_NAME 'RESISTOR' 
TOP 0 1.3505 0.658 0.0 N 306 1 1
TOP 1 1.3085 0.658 0.0 N 223 4 2
#
# CMP 199
CMP 56 5.741 3.857 180.0 N R10 ??? ;0=1,1=0.016000
PRP SIGNAL_MODEL 'RESISTOR-G155-100R0-J0_0OHM_-' 
PRP REUSE_ID '15' 
PRP ALT_SYMBOLS '(SMC_0402R_C_H016)' 
PRP PARENT_PART_TYPE 'RESISTOR' 
PRP PARENT_PPT 'RESISTOR' 
PRP PARENT_PPT_PART 'RESISTOR-G155-11002-01,10KOHM,1%' 
PRP PART_NAME 'RESISTOR' 
TOP 0 5.72 3.857 180.0 N 124 2 1
TOP 1 5.762 3.857 180.0 N 2 587 2
#
# CMP 200
CMP 56 0.908 2.81 90.0 N R91 ??? ;0=1,1=0.016000
PRP SIGNAL_MODEL 'DEFAULT_RESISTOR_33OHM_2_1' 
PRP ALT_SYMBOLS '(SMC_0402R_C_H016)' 
PRP PARENT_PART_TYPE 'RESISTOR' 
PRP PARENT_PPT 'RESISTOR' 
PRP PARENT_PPT_PART 'RESISTOR-G155-133R0-01,33OHM,1%' 
PRP PART_NAME 'RESISTOR' 
TOP 0 0.908 2.831 90.0 N 226 1 1
TOP 1 0.908 2.789 90.0 N 213 1 2
#
# CMP 201
CMP 56 0.85 2.423 270.0 N R281 ??? ;0=1,1=0.016000
PRP SIGNAL_MODEL 'RESISTOR-G155-100R0-J0_0OHM_-' 
PRP ALT_SYMBOLS '(SMC_0402R_C_H016)' 
PRP PARENT_PART_TYPE 'RESISTOR' 
PRP PARENT_PPT 'RESISTOR' 
PRP PARENT_PPT_PART 'RESISTOR-G155-14701-01,4.7KOHM,1%' 
PRP PART_NAME 'RESISTOR' 
TOP 0 0.85 2.402 270.0 N 1 177 1
TOP 1 0.85 2.444 270.0 N 363 2 2
#
# CMP 202
CMP 56 0.896 2.423 270.0 N R314 ??? ;0=1,1=0.016000
PRP SIGNAL_MODEL 'RESISTOR-G155-100R0-J0_0OHM_-' 
PRP ALT_SYMBOLS '(SMC_0402R_C_H016)' 
PRP PARENT_PART_TYPE 'RESISTOR' 
PRP PARENT_PPT 'RESISTOR' 
PRP PARENT_PPT_PART 'RESISTOR-G155-14701-01,4.7KOHM,1%' 
PRP PART_NAME 'RESISTOR' 
TOP 0 0.896 2.402 270.0 N 1 178 1
TOP 1 0.896 2.444 270.0 N 386 1 2
#
# CMP 203
CMP 56 1.059 0.718 0.0 N R344 ??? ;0=1,1=0.016000
PRP SIGNAL_MODEL 'RESISTOR-G155-100R0-J0_0OHM_-' 
PRP ALT_SYMBOLS '(SMC_0402R_C_H016)' 
PRP PARENT_PART_TYPE 'RESISTOR' 
PRP PARENT_PPT 'RESISTOR' 
PRP PARENT_PPT_PART 'RESISTOR-G155-14701-01,4.7KOHM,1%' 
PRP PART_NAME 'RESISTOR' 
TOP 0 1.08 0.718 0.0 N 211 4 1
TOP 1 1.038 0.718 0.0 N 2 588 2
#
# CMP 204
CMP 56 1.1948 0.6587 180.0 N R1991 ??? ;0=1,1=0.016000
PRP SIGNAL_MODEL 'RESISTOR-G155-100R0-J0_0OHM_-' 
PRP ALT_SYMBOLS '(SMC_0402R_C_H016)' 
PRP PARENT_PART_TYPE 'RESISTOR' 
PRP PARENT_PPT 'RESISTOR' 
PRP PARENT_PPT_PART 'RESISTOR-G155-11002-01,10KOHM,1%' 
PRP PART_NAME 'RESISTOR' 
TOP 0 1.1738 0.6587 180.0 N 1 179 1
TOP 1 1.2158 0.6587 180.0 N 223 5 2
#
# CMP 205
CMP 56 0.715 2.423 270.0 N R282 ??? ;0=1,1=0.016000
PRP SIGNAL_MODEL 'RESISTOR-G155-100R0-J0_0OHM_-' 
PRP ALT_SYMBOLS '(SMC_0402R_C_H016)' 
PRP PARENT_PART_TYPE 'RESISTOR' 
PRP PARENT_PPT 'RESISTOR' 
PRP PARENT_PPT_PART 'RESISTOR-G155-14701-01,4.7KOHM,1%' 
PRP PART_NAME 'RESISTOR' 
TOP 0 0.715 2.402 270.0 N 1 180 1
TOP 1 0.715 2.444 270.0 N 364 2 2
#
# CMP 206
CMP 56 0.805 2.423 90.0 N R316 ??? ;0=1,1=0.016000
PRP SIGNAL_MODEL 'RESISTOR-G155-100R0-J0_0OHM_-' 
PRP ALT_SYMBOLS '(SMC_0402R_C_H016,C0402-0P8MM-45DG)' 
PRP PARENT_PART_TYPE 'RESISTOR' 
PRP PARENT_PPT 'RESISTOR' 
PRP PARENT_PPT_PART 'RESISTOR-G155-100R0-J0,0OHM,-' 
PRP PART_NAME 'RESISTOR' 
TOP 0 0.805 2.444 90.0 N 363 3 1
TOP 1 0.805 2.402 90.0 N 388 3 2
#
# CMP 207
CMP 56 0.76 2.423 90.0 N R315 ??? ;0=1,1=0.016000
PRP SIGNAL_MODEL 'RESISTOR-G155-100R0-J0_0OHM_-' 
PRP ALT_SYMBOLS '(SMC_0402R_C_H016,C0402-0P8MM-45DG)' 
PRP PARENT_PART_TYPE 'RESISTOR' 
PRP PARENT_PPT 'RESISTOR' 
PRP PARENT_PPT_PART 'RESISTOR-G155-100R0-J0,0OHM,-' 
PRP PART_NAME 'RESISTOR' 
TOP 0 0.76 2.444 90.0 N 364 3 1
TOP 1 0.76 2.402 90.0 N 387 3 2
#
# CMP 208
CMP 56 0.829 1.594 0.0 N R26 ??? ;0=1,1=0.016000
PRP SIGNAL_MODEL 'DEFAULT_RESISTOR_33OHM_2_1' 
PRP ALT_SYMBOLS '(SMC_0402R_C_H016)' 
PRP PARENT_PART_TYPE 'RESISTOR' 
PRP PARENT_PPT 'RESISTOR' 
PRP PARENT_PPT_PART 'RESISTOR-G155-133R0-01,33OHM,1%' 
PRP PART_NAME 'RESISTOR' 
TOP 0 0.85 1.594 0.0 N 306 2 1
TOP 1 0.808 1.594 0.0 N 288 3 2
#
# CMP 209
CMP 56 0.829 1.639 0.0 N R147 ??? ;0=1,1=0.016000
PRP HARD_LOCATION 'YES' 
PRP SIGNAL_MODEL 'RESISTOR-G155-100R0-J0_0OHM_-' 
PRP ALT_SYMBOLS '(SMC_0402R_C_H016)' 
PRP PARENT_PART_TYPE 'RESISTOR' 
PRP PARENT_PPT 'RESISTOR' 
PRP PARENT_PPT_PART 'RESISTOR-G155-11002-01,10KOHM,1%' 
PRP PART_NAME 'RESISTOR' 
TOP 0 0.85 1.639 0.0 N 1 181 1
TOP 1 0.808 1.639 0.0 N 288 4 2
#
# CMP 210
CMP 56 0.829 1.684 0.0 N R58 ??? ;0=1,1=0.016000
PRP HARD_LOCATION 'YES' 
PRP SIGNAL_MODEL 'DEFAULT_RESISTOR_33OHM_2_1' 
PRP ALT_SYMBOLS '(SMC_0402R_C_H016)' 
PRP PARENT_PART_TYPE 'RESISTOR' 
PRP PARENT_PPT 'RESISTOR' 
PRP PARENT_PPT_PART 'RESISTOR-G155-133R0-01,33OHM,1%' 
PRP PART_NAME 'RESISTOR' 
TOP 0 0.85 1.684 0.0 N 222 1 1
TOP 1 0.808 1.684 0.0 N 288 5 2
#
# CMP 211
CMP 56 0.696 1.544 180.0 N R145 ??? ;0=1,1=0.016000
PRP SIGNAL_MODEL 'DEFAULT_RESISTOR_33OHM_2_1' 
PRP ALT_SYMBOLS '(SMC_0402R_C_H016)' 
PRP PARENT_PART_TYPE 'RESISTOR' 
PRP PARENT_PPT 'RESISTOR' 
PRP PARENT_PPT_PART 'RESISTOR-G155-133R0-01,33OHM,1%' 
PRP PART_NAME 'RESISTOR' 
TOP 0 0.675 1.544 180.0 N 289 1 1
TOP 1 0.717 1.544 180.0 N 290 5 2
#
# CMP 212
CMP 56 2.083 2.952 90.0 N R409 ??? ;0=1,1=0.016000
PRP REUSE_ID '7' 
PRP ALT_SYMBOLS '(SMC_0402R_C_H016)' 
PRP PARENT_PART_TYPE 'RESISTOR' 
PRP PARENT_PPT 'RESISTOR' 
PRP PARENT_PPT_PART 'RESISTOR-G155-11001-01,1KOHM,1%' 
PRP PART_NAME 'RESISTOR' 
TOP 0 2.083 2.973 90.0 N 466 2 1
TOP 1 2.083 2.931 90.0 N 2 589 2
#
# CMP 213
CMP 56 2.128 2.952 90.0 N R413 ??? ;0=1,1=0.016000
PRP REUSE_ID '10' 
PRP ALT_SYMBOLS '(SMC_0402R_C_H016)' 
PRP PARENT_PART_TYPE 'RESISTOR' 
PRP PARENT_PPT 'RESISTOR' 
PRP PARENT_PPT_PART 'RESISTOR-G155-11001-01,1KOHM,1%' 
PRP PART_NAME 'RESISTOR' 
TOP 0 2.128 2.973 90.0 N 468 2 1
TOP 1 2.128 2.931 90.0 N 2 590 2
#
# CMP 214
CMP 56 5.475 2.87 180.0 N R43 ??? ;0=1,1=0.016000
PRP SIGNAL_MODEL 'RESISTOR-G155-100R0-J0_0OHM_-' 
PRP ALT_SYMBOLS '(SMC_0402R_C_H016,C0402-0P8MM-45DG)' 
PRP PARENT_PART_TYPE 'RESISTOR' 
PRP PARENT_PPT 'RESISTOR' 
PRP PARENT_PPT_PART 'RESISTOR-G155-100R0-J0,0OHM,-' 
PRP PART_NAME 'RESISTOR' 
TOP 0 5.454 2.87 180.0 N 183 1 1
TOP 1 5.496 2.87 180.0 N 281 1 2
#
# CMP 215
CMP 56 5.525 3.065 0.0 N R41 ??? ;0=1,1=0.016000
PRP SIGNAL_MODEL 'RESISTOR-G155-100R0-J0_0OHM_-' 
PRP ALT_SYMBOLS '(SMC_0402R_C_H016,C0402-0P8MM-45DG)' 
PRP PARENT_PART_TYPE 'RESISTOR' 
PRP PARENT_PPT 'RESISTOR' 
PRP PARENT_PPT_PART 'RESISTOR-G155-100R0-J0,0OHM,-' 
PRP PART_NAME 'RESISTOR' 
TOP 0 5.546 3.065 0.0 N 181 1 1
TOP 1 5.504 3.065 0.0 N 282 1 2
#
# CMP 216
CMP 56 5.525 2.815 0.0 N R42 ??? ;0=1,1=0.016000
PRP SIGNAL_MODEL 'RESISTOR-G155-100R0-J0_0OHM_-' 
PRP ALT_SYMBOLS '(SMC_0402R_C_H016,C0402-0P8MM-45DG)' 
PRP PARENT_PART_TYPE 'RESISTOR' 
PRP PARENT_PPT 'RESISTOR' 
PRP PARENT_PPT_PART 'RESISTOR-G155-100R0-J0,0OHM,-' 
PRP PART_NAME 'RESISTOR' 
TOP 0 5.546 2.815 0.0 N 182 1 1
TOP 1 5.504 2.815 0.0 N 280 0 2
#
# CMP 217
CMP 56 5.525 2.595 0.0 N R28 ??? ;0=1,1=0.016000
PRP SIGNAL_MODEL 'RESISTOR-G155-100R0-J0_0OHM_-' 
PRP ALT_SYMBOLS '(SMC_0402R_C_H016,C0402-0P8MM-45DG)' 
PRP PARENT_PART_TYPE 'RESISTOR' 
PRP PARENT_PPT 'RESISTOR' 
PRP PARENT_PPT_PART 'RESISTOR-G155-100R0-J0,0OHM,-' 
PRP PART_NAME 'RESISTOR' 
TOP 0 5.546 2.595 0.0 N 180 1 1
TOP 1 5.504 2.595 0.0 N 279 1 2
#
# CMP 218
CMP 56 1.456 3.991 0.0 N R30 ??? ;0=1,1=0.016000
PRP REUSE_ID '25' 
PRP ALT_SYMBOLS '(SMC_0402R_C_H016)' 
PRP PARENT_PART_TYPE 'RESISTOR' 
PRP PARENT_PPT 'RESISTOR' 
PRP PARENT_PPT_PART 'RESISTOR-G155-12201-01,2.2KOHM,1%' 
PRP PART_NAME 'RESISTOR' 
TOP 0 1.477 3.991 0.0 N 105 2 1
TOP 1 1.435 3.991 0.0 N 104 0 2
#
# CMP 219
CMP 56 1.456 3.946 0.0 N R48 ??? ;0=1,1=0.016000
PRP REUSE_ID '26' 
PRP ALT_SYMBOLS '(SMC_0402R_C_H016)' 
PRP PARENT_PART_TYPE 'RESISTOR' 
PRP PARENT_PPT 'RESISTOR' 
PRP PARENT_PPT_PART 'RESISTOR-A155-05101-DL,5.1KOHM,1%' 
PRP PART_NAME 'RESISTOR' 
TOP 0 1.477 3.946 0.0 N 82 3 1
TOP 1 1.435 3.946 0.0 N 2 591 2
#
# CMP 220
CMP 56 1.456 3.901 180.0 N R142 ??? ;0=1,1=0.016000
PRP SIGNAL_MODEL 'RESISTOR-G155-11000-01_100OHM_A' 
PRP REUSE_ID '5' 
PRP ALT_SYMBOLS '(SMC_0402R_C_H016)' 
PRP PARENT_PART_TYPE 'RESISTOR' 
PRP PARENT_PPT 'RESISTOR' 
PRP PARENT_PPT_PART 'RESISTOR-G155-11000-01,100OHM,1%' 
PRP PART_NAME 'RESISTOR' 
TOP 0 1.435 3.901 180.0 N 285 2 1
TOP 1 1.477 3.901 180.0 N 82 4 2
#
# CMP 221
CMP 56 1.1947 0.7086 0.0 N R1 ??? ;0=1,1=0.016000
PRP REUSE_ID '26' 
PRP ALT_SYMBOLS '(SMC_0402R_C_H016)' 
PRP PARENT_PART_TYPE 'RESISTOR' 
PRP PARENT_PPT 'RESISTOR' 
PRP PARENT_PPT_PART 'RESISTOR-G155-13300-01,330OHM,1%' 
PRP PART_NAME 'RESISTOR' 
TOP 0 1.2157 0.7086 0.0 N 248 1 1
TOP 1 1.1737 0.7086 0.0 N 211 5 2
#
# CMP 222
CMP 56 0.83 0.665 0.0 N R3 ??? ;0=1,1=0.016000
PRP SIGNAL_MODEL 'RESISTOR-G155-100R0-J0_0OHM_-' 
PRP REUSE_ID '30' 
PRP ALT_SYMBOLS '(SMC_0402R_C_H016)' 
PRP PARENT_PART_TYPE 'RESISTOR' 
PRP PARENT_PPT 'RESISTOR' 
PRP PARENT_PPT_PART 'RESISTOR-G155-14701-01,4.7KOHM,1%' 
PRP PART_NAME 'RESISTOR' 
TOP 0 0.851 0.665 0.0 N 1 182 1
TOP 1 0.809 0.665 0.0 N 212 4 2
#
# CMP 223
CMP 56 5.91 4.11 90.0 N R118 ??? ;0=1,1=0.016000
PRP ALT_SYMBOLS '(SMC_0402R_C_H016)' 
PRP PARENT_PART_TYPE 'RESISTOR' 
PRP PARENT_PPT 'RESISTOR' 
PRP PARENT_PPT_PART 'RESISTOR-G155-13300-01,330OHM,1%' 
PRP PART_NAME 'RESISTOR' 
TOP 0 5.91 4.131 90.0 N 165 1 1
TOP 1 5.91 4.089 90.0 N 81 4 2
#
# CMP 224
CMP 56 6.025 4.11 90.0 N R119 ??? ;0=1,1=0.016000
PRP ALT_SYMBOLS '(SMC_0402R_C_H016)' 
PRP PARENT_PART_TYPE 'RESISTOR' 
PRP PARENT_PPT 'RESISTOR' 
PRP PARENT_PPT_PART 'RESISTOR-G155-13300-01,330OHM,1%' 
PRP PART_NAME 'RESISTOR' 
TOP 0 6.025 4.131 90.0 N 168 1 1
TOP 1 6.025 4.089 90.0 N 80 3 2
#
# CMP 225
CMP 56 0.868 0.71 180.0 N R24 ??? ;0=1,1=0.016000
PRP SIGNAL_MODEL 'RESISTOR-G155-100R0-J0_0OHM_-' 
PRP ALT_SYMBOLS '(SMC_0402R_C_H016)' 
PRP PARENT_PART_TYPE 'RESISTOR' 
PRP PARENT_PPT 'RESISTOR' 
PRP PARENT_PPT_PART 'RESISTOR-G155-14701-01,4.7KOHM,1%' 
PRP PART_NAME 'RESISTOR' 
TOP 0 0.847 0.71 180.0 N 212 5 1
TOP 1 0.889 0.71 180.0 N 2 592 2
#
# CMP 226
CMP 56 2.173 2.952 90.0 N R416 ??? ;0=1,1=0.016000
PRP REUSE_ID '8' 
PRP ALT_SYMBOLS '(SMC_0402R_C_H016)' 
PRP PARENT_PART_TYPE 'RESISTOR' 
PRP PARENT_PPT 'RESISTOR' 
PRP PARENT_PPT_PART 'RESISTOR-G155-11001-01,1KOHM,1%' 
PRP PART_NAME 'RESISTOR' 
TOP 0 2.173 2.973 90.0 N 470 2 1
TOP 1 2.173 2.931 90.0 N 2 593 2
#
# CMP 227
CMP 56 4.905 1.81 0.0 N R195 ??? ;0=1,1=0.016000
PRP SIGNAL_MODEL 'DEFAULT_RESISTOR_33OHM_2_1' 
PRP ALT_SYMBOLS '(SMC_0402R_C_H016)' 
PRP PARENT_PART_TYPE 'RESISTOR' 
PRP PARENT_PPT 'RESISTOR' 
PRP PARENT_PPT_PART 'RESISTOR-G155-133R0-01,33OHM,1%' 
PRP PART_NAME 'RESISTOR' 
TOP 0 4.926 1.81 0.0 N 280 1 1
TOP 1 4.884 1.81 0.0 N 316 1 2
#
# CMP 228
CMP 56 1.055 3.71 90.0 N R18 ??? ;0=1,1=0.016000
PRP SIGNAL_MODEL 'RESISTOR-G155-100R0-J0_0OHM_-' 
PRP ALT_SYMBOLS '(SMC_0402R_C_H016)' 
PRP PARENT_PART_TYPE 'RESISTOR' 
PRP PARENT_PPT 'RESISTOR' 
PRP PARENT_PPT_PART 'RESISTOR-G155-14701-01,4.7KOHM,1%' 
PRP PART_NAME 'RESISTOR' 
TOP 0 1.055 3.731 90.0 N 132 7 1
TOP 1 1.055 3.689 90.0 N 245 6 2
#
# CMP 229
CMP 56 4.905 2.025 180.0 N R264 ??? ;0=1,1=0.016000
PRP ALT_SYMBOLS '(SMC_0402R_C_H016)' 
PRP PARENT_PART_TYPE 'RESISTOR' 
PRP PARENT_PPT 'RESISTOR' 
PRP PARENT_PPT_PART 'RESISTOR-G155-11003-01,100KOHM,1%' 
PRP PART_NAME 'RESISTOR' 
TOP 0 4.884 2.025 180.0 N 1 183 1
TOP 1 4.926 2.025 180.0 N 230 2 2
#
# CMP 230
CMP 56 4.905 1.765 180.0 N R209 ??? ;0=1,1=0.016000
PRP SIGNAL_MODEL 'RESISTOR-G155-100R0-J0_0OHM_-' 
PRP ALT_SYMBOLS '(SMC_0402R_C_H016)' 
PRP PARENT_PART_TYPE 'RESISTOR' 
PRP PARENT_PPT 'RESISTOR' 
PRP PARENT_PPT_PART 'RESISTOR-G155-14701-01,4.7KOHM,1%' 
PRP PART_NAME 'RESISTOR' 
TOP 0 4.884 1.765 180.0 N 203 5 1
TOP 1 4.926 1.765 180.0 N 1 184 2
#
# CMP 231
CMP 56 4.905 1.975 0.0 N R265 ??? ;0=1,1=0.016000
PRP ALT_SYMBOLS '(SMC_0402R_C_H016)' 
PRP PARENT_PART_TYPE 'RESISTOR' 
PRP PARENT_PPT 'RESISTOR' 
PRP PARENT_PPT_PART 'RESISTOR-G155-11003-01,100KOHM,1%' 
PRP PART_NAME 'RESISTOR' 
TOP 0 4.926 1.975 0.0 N 1 185 1
TOP 1 4.884 1.975 0.0 N 351 2 2
#
# CMP 232
CMP 56 4.53 2.44 90.0 N R215 ??? ;0=1,1=0.016000
PRP SIGNAL_MODEL 'RESISTOR-G155-100R0-J0_0OHM_-' 
PRP ALT_SYMBOLS '(SMC_0402R_C_H016)' 
PRP PARENT_PART_TYPE 'RESISTOR' 
PRP PARENT_PPT 'RESISTOR' 
PRP PARENT_PPT_PART 'RESISTOR-G155-11002-01,10KOHM,1%' 
PRP PART_NAME 'RESISTOR' 
TOP 0 4.53 2.461 90.0 N 1 186 1
TOP 1 4.53 2.419 90.0 N 334 1 2
#
# CMP 233
CMP 56 4.485 2.44 270.0 N R216 ??? ;0=1,1=0.016000
PRP ALT_SYMBOLS '(SMC_0402R_C_H016)' 
PRP PARENT_PART_TYPE 'RESISTOR' 
PRP PARENT_PPT 'RESISTOR' 
PRP PARENT_PPT_PART 'RESISTOR-G155-11001-01,1KOHM,1%' 
PRP PART_NAME 'RESISTOR' 
TOP 0 4.485 2.419 270.0 N 334 2 1
TOP 1 4.485 2.461 270.0 N 2 594 2
#
# CMP 234
CMP 56 2.8175 1.945 180.0 N R89 ??? ;0=1,1=0.016000
PRP SIGNAL_MODEL 'RESISTOR-G155-11000-01_100OHM_A' 
PRP ALT_SYMBOLS '(SMC_0402R_C_H016)' 
PRP PARENT_PART_TYPE 'RESISTOR' 
PRP PARENT_PPT 'RESISTOR' 
PRP PARENT_PPT_PART 'RESISTOR-G155-11000-01,100OHM,1%' 
PRP PART_NAME 'RESISTOR' 
TOP 0 2.7965 1.945 180.0 N 231 2 1
TOP 1 2.8385 1.945 180.0 N 233 2 2
#
# CMP 235
CMP 56 3.44 2.21 0.0 N R76 ??? ;0=1,1=0.016000
PRP SIGNAL_MODEL 'DEFAULT_RESISTOR_33OHM_2_1' 
PRP ALT_SYMBOLS '(SMC_0402R_C_H016)' 
PRP PARENT_PART_TYPE 'RESISTOR' 
PRP PARENT_PPT 'RESISTOR' 
PRP PARENT_PPT_PART 'RESISTOR-G155-133R0-01,33OHM,1%' 
PRP PART_NAME 'RESISTOR' 
TOP 0 3.461 2.21 0.0 N 528 1 1
TOP 1 3.419 2.21 0.0 N 530 1 2
#
# CMP 236
CMP 56 3.35 2.21 180.0 N R77 ??? ;0=1,1=0.016000
PRP SIGNAL_MODEL 'DEFAULT_RESISTOR_33OHM_2_1' 
PRP ALT_SYMBOLS '(SMC_0402R_C_H016)' 
PRP PARENT_PART_TYPE 'RESISTOR' 
PRP PARENT_PPT 'RESISTOR' 
PRP PARENT_PPT_PART 'RESISTOR-G155-133R0-01,33OHM,1%' 
PRP PART_NAME 'RESISTOR' 
TOP 0 3.329 2.21 180.0 N 529 1 1
TOP 1 3.371 2.21 180.0 N 531 1 2
#
# CMP 237
CMP 56 3.35 2.255 0.0 N R75 ??? ;0=1,1=0.016000
PRP SIGNAL_MODEL 'RESISTOR-G155-100R0-J0_0OHM_-' 
PRP ALT_SYMBOLS '(SMC_0402R_C_H016)' 
PRP PARENT_PART_TYPE 'RESISTOR' 
PRP PARENT_PPT 'RESISTOR' 
PRP PARENT_PPT_PART 'RESISTOR-G155-14701-01,4.7KOHM,1%' 
PRP PART_NAME 'RESISTOR' 
TOP 0 3.371 2.255 0.0 N 1 187 1
TOP 1 3.329 2.255 0.0 N 529 2 2
#
# CMP 238
CMP 56 3.44 2.255 180.0 N R74 ??? ;0=1,1=0.016000
PRP SIGNAL_MODEL 'RESISTOR-G155-100R0-J0_0OHM_-' 
PRP ALT_SYMBOLS '(SMC_0402R_C_H016)' 
PRP PARENT_PART_TYPE 'RESISTOR' 
PRP PARENT_PPT 'RESISTOR' 
PRP PARENT_PPT_PART 'RESISTOR-G155-14701-01,4.7KOHM,1%' 
PRP PART_NAME 'RESISTOR' 
TOP 0 3.419 2.255 180.0 N 1 188 1
TOP 1 3.461 2.255 180.0 N 528 2 2
#
# CMP 239
CMP 56 3.554 1.93149 180.0 N R105 ??? ;0=1,1=0.016000
PRP SIGNAL_MODEL 'RESISTOR-G155-100R0-J0_0OHM_-' 
PRP ALT_SYMBOLS '(SMC_0402R_C_H016,C0402-0P8MM-45DG)' 
PRP PARENT_PART_TYPE 'RESISTOR' 
PRP PARENT_PPT 'RESISTOR' 
PRP PARENT_PPT_PART 'RESISTOR-G155-100R0-J0,0OHM,-' 
PRP PART_NAME 'RESISTOR' 
TOP 0 3.533 1.93149 180.0 N 253 2 1
TOP 1 3.575 1.93149 180.0 N 254 3 2
#
# CMP 240
CMP 56 2.91 2.32 90.0 N R44 ??? ;0=1,1=0.016000
PRP SIGNAL_MODEL 'RESISTOR-G155-100R0-J0_0OHM_-' 
PRP ALT_SYMBOLS '(SMC_0402R_C_H016)' 
PRP PARENT_PART_TYPE 'RESISTOR' 
PRP PARENT_PPT 'RESISTOR' 
PRP PARENT_PPT_PART 'RESISTOR-G155-14701-01,4.7KOHM,1%' 
PRP PART_NAME 'RESISTOR' 
TOP 0 2.91 2.341 90.0 N 76 5 1
TOP 1 2.91 2.299 90.0 N 247 2 2
#
# CMP 241
CMP 56 2.62 2.375 0.0 N R267 ??? ;0=1,1=0.016000
PRP SIGNAL_MODEL 'DEFAULT_RESISTOR_33OHM_2_1' 
PRP ALT_SYMBOLS '(SMC_0402R_C_H016)' 
PRP PARENT_PART_TYPE 'RESISTOR' 
PRP PARENT_PPT 'RESISTOR' 
PRP PARENT_PPT_PART 'RESISTOR-G155-133R0-01,33OHM,1%' 
PRP PART_NAME 'RESISTOR' 
TOP 0 2.641 2.375 0.0 N 353 1 1
TOP 1 2.599 2.375 0.0 N 257 1 2
#
# CMP 242
CMP 56 2.53 2.375 180.0 N R107 ??? ;0=1,1=0.016000
PRP SIGNAL_MODEL 'RESISTOR-G155-100R0-J0_0OHM_-' 
PRP ALT_SYMBOLS '(SMC_0402R_C_H016)' 
PRP PARENT_PART_TYPE 'RESISTOR' 
PRP PARENT_PPT 'RESISTOR' 
PRP PARENT_PPT_PART 'RESISTOR-G155-14701-01,4.7KOHM,1%' 
PRP PART_NAME 'RESISTOR' 
TOP 0 2.509 2.375 180.0 N 1 189 1
TOP 1 2.551 2.375 180.0 N 257 2 2
#
# CMP 243
CMP 56 5.425 0.64 0.0 N R230 ??? ;0=1,1=0.016000
PRP SIGNAL_MODEL 'RESISTOR-G155-100R0-J0_0OHM_-' 
PRP REUSE_ID '18' 
PRP ALT_SYMBOLS '(SMC_0402R_C_H016,C0402-0P8MM-45DG)' 
PRP PARENT_PART_TYPE 'RESISTOR' 
PRP PARENT_PPT 'RESISTOR' 
PRP PARENT_PPT_PART 'RESISTOR-G155-100R0-J0,0OHM,-' 
PRP PART_NAME 'RESISTOR' 
TOP 0 5.446 0.64 0.0 N 37 2 1
TOP 1 5.404 0.64 0.0 N 203 6 2
#
# CMP 244
CMP 56 6.3 1.98874 90.0 N R101 ??? ;0=1,1=0.016000
PRP ALT_SYMBOLS '(SMC_0402R_C_H016)' 
PRP PARENT_PART_TYPE 'RESISTOR' 
PRP PARENT_PPT 'RESISTOR' 
PRP PARENT_PPT_PART 'RESISTOR-G155-11001-01,1KOHM,1%' 
PRP PART_NAME 'RESISTOR' 
TOP 0 6.3 2.00974 90.0 N 121 4 1
TOP 1 6.3 1.96774 90.0 N 250 2 2
#
# CMP 245
CMP 56 5.555 0.629 270.0 N R229 ??? ;0=1,1=0.016000
PRP SIGNAL_MODEL 'RESISTOR-G155-100R0-J0_0OHM_-' 
PRP REUSE_ID '19' 
PRP ALT_SYMBOLS '(SMC_0402R_C_H016)' 
PRP PARENT_PART_TYPE 'RESISTOR' 
PRP PARENT_PPT 'RESISTOR' 
PRP PARENT_PPT_PART 'RESISTOR-G155-14701-01,4.7KOHM,1%' 
PRP PART_NAME 'RESISTOR' 
TOP 0 5.555 0.608 270.0 N 1 190 1
TOP 1 5.555 0.65 270.0 N 37 3 2
#
# CMP 246
CMP 56 2.54 2.195 90.0 N R99 ??? ;0=1,1=0.016000
PRP SIGNAL_MODEL 'RESISTOR-G155-100R0-J0_0OHM_-' 
PRP ALT_SYMBOLS '(SMC_0402R_C_H016)' 
PRP PARENT_PART_TYPE 'RESISTOR' 
PRP PARENT_PPT 'RESISTOR' 
PRP PARENT_PPT_PART 'RESISTOR-G155-14701-01,4.7KOHM,1%' 
PRP PART_NAME 'RESISTOR' 
TOP 0 2.54 2.216 90.0 N 249 1 1
TOP 1 2.54 2.174 90.0 N 2 595 2
#
# CMP 247
CMP 56 6.255 1.98874 270.0 N R102 ??? ;0=1,1=0.016000
PRP ALT_SYMBOLS '(SMC_0402R_C_H016)' 
PRP PARENT_PART_TYPE 'RESISTOR' 
PRP PARENT_PPT 'RESISTOR' 
PRP PARENT_PPT_PART 'RESISTOR-G155-11001-01,1KOHM,1%' 
PRP PART_NAME 'RESISTOR' 
TOP 0 6.255 1.96774 270.0 N 250 3 1
TOP 1 6.255 2.00974 270.0 N 251 0 2
#
# CMP 248
CMP 56 2.54 2.285 270.0 N R100 ??? ;0=1,1=0.016000
PRP SIGNAL_MODEL 'DEFAULT_RESISTOR_33OHM_2_1' 
PRP ALT_SYMBOLS '(SMC_0402R_C_H016)' 
PRP PARENT_PART_TYPE 'RESISTOR' 
PRP PARENT_PPT 'RESISTOR' 
PRP PARENT_PPT_PART 'RESISTOR-G155-133R0-01,33OHM,1%' 
PRP PART_NAME 'RESISTOR' 
TOP 0 2.54 2.264 270.0 N 249 2 1
TOP 1 2.54 2.306 270.0 N 123 2 2
#
# CMP 249
CMP 56 6.21 1.98874 90.0 N R103 ??? ;0=1,1=0.016000
PRP ALT_SYMBOLS '(SMC_0402R_C_H016)' 
PRP PARENT_PART_TYPE 'RESISTOR' 
PRP PARENT_PPT 'RESISTOR' 
PRP PARENT_PPT_PART 'RESISTOR-G155-11001-01,1KOHM,1%' 
PRP PART_NAME 'RESISTOR' 
TOP 0 6.21 2.00974 90.0 N 251 1 1
TOP 1 6.21 1.96774 90.0 N 2 596 2
#
# CMP 250
CMP 56 5.772 0.679 90.0 N R227 ??? ;0=1,1=0.016000
PRP SIGNAL_MODEL 'RESISTOR-G155-100R0-J0_0OHM_-' 
PRP REUSE_ID '5' 
PRP ALT_SYMBOLS '(SMC_0402R_C_H016)' 
PRP PARENT_PART_TYPE 'RESISTOR' 
PRP PARENT_PPT 'RESISTOR' 
PRP PARENT_PPT_PART 'RESISTOR-G155-11002-01,10KOHM,1%' 
PRP PART_NAME 'RESISTOR' 
TOP 0 5.772 0.7 90.0 N 31 3 1
TOP 1 5.772 0.658 90.0 N 2 597 2
#
# CMP 251
CMP 56 5.775 0.775 90.0 N R225 ??? ;0=1,1=0.016000
PRP REUSE_ID '3' 
PRP ALT_SYMBOLS '(SMC_0402R_C_H016)' 
PRP PARENT_PART_TYPE 'RESISTOR' 
PRP PARENT_PPT 'RESISTOR' 
PRP PARENT_PPT_PART 'RESISTOR-G155-13300-01,330OHM,1%' 
PRP PART_NAME 'RESISTOR' 
TOP 0 5.775 0.796 90.0 N 285 3 1
TOP 1 5.775 0.754 90.0 N 31 4 2
#
# CMP 252
CMP 56 4.905 1.675 180.0 N R218 ??? ;0=1,1=0.016000
PRP SIGNAL_MODEL 'RESISTOR-G155-11000-01_100OHM_A' 
PRP ALT_SYMBOLS '(SMC_0402R_C_H016)' 
PRP PARENT_PART_TYPE 'RESISTOR' 
PRP PARENT_PPT 'RESISTOR' 
PRP PARENT_PPT_PART 'RESISTOR-G155-11000-01,100OHM,1%' 
PRP PART_NAME 'RESISTOR' 
TOP 0 4.884 1.675 180.0 N 335 1 1
TOP 1 4.926 1.675 180.0 N 2 598 2
#
# CMP 253
CMP 56 4.905 1.63 0.0 N R217 ??? ;0=1,1=0.016000
PRP SIGNAL_MODEL 'RESISTOR-G155-11000-01_100OHM_A' 
PRP ALT_SYMBOLS '(SMC_0402R_C_H016)' 
PRP PARENT_PART_TYPE 'RESISTOR' 
PRP PARENT_PPT 'RESISTOR' 
PRP PARENT_PPT_PART 'RESISTOR-G155-11000-01,100OHM,1%' 
PRP PART_NAME 'RESISTOR' 
TOP 0 4.926 1.63 0.0 N 1 191 1
TOP 1 4.884 1.63 0.0 N 335 2 2
#
# CMP 254
CMP 56 4.545 2.945 0.0 N R226 ??? ;0=1,1=0.016000
PRP ALT_SYMBOLS '(SMC_0402R_C_H016)' 
PRP PARENT_PART_TYPE 'RESISTOR' 
PRP PARENT_PPT 'RESISTOR' 
PRP PARENT_PPT_PART 'RESISTOR-G155-13300-01,330OHM,1%' 
PRP PART_NAME 'RESISTOR' 
TOP 0 4.566 2.945 0.0 N 285 4 1
TOP 1 4.524 2.945 0.0 N 33 2 2
#
# CMP 255
CMP 56 4.545 2.795 0.0 N R260 ??? ;0=1,1=0.016000
PRP ALT_SYMBOLS '(SMC_0402R_C_H016)' 
PRP PARENT_PART_TYPE 'RESISTOR' 
PRP PARENT_PPT 'RESISTOR' 
PRP PARENT_PPT_PART 'RESISTOR-G155-11001-01,1KOHM,1%' 
PRP PART_NAME 'RESISTOR' 
TOP 0 4.566 2.795 0.0 N 19 30 1
TOP 1 4.524 2.795 0.0 N 33 3 2
#
# CMP 256
CMP 56 3.395 2.885 270.0 N R342 ??? ;0=1,1=0.016000
PRP SIGNAL_MODEL 'RESISTOR-G155-100R0-J0_0OHM_-' 
PRP ALT_SYMBOLS '(SMC_0402R_C_H016)' 
PRP PARENT_PART_TYPE 'RESISTOR' 
PRP PARENT_PPT 'RESISTOR' 
PRP PARENT_PPT_PART 'RESISTOR-G155-14701-01,4.7KOHM,1%' 
PRP PART_NAME 'RESISTOR' 
TOP 0 3.395 2.864 270.0 N 1 192 1
TOP 1 3.395 2.906 270.0 N 408 1 2
#
# CMP 257
CMP 56 3.35 2.885 270.0 N R363 ??? ;0=1,1=0.016000
PRP SIGNAL_MODEL 'DEFAULT_RESISTOR_33OHM_2_1' 
PRP ALT_SYMBOLS '(SMC_0402R_C_H016)' 
PRP PARENT_PART_TYPE 'RESISTOR' 
PRP PARENT_PPT 'RESISTOR' 
PRP PARENT_PPT_PART 'RESISTOR-G155-133R0-01,33OHM,1%' 
PRP PART_NAME 'RESISTOR' 
TOP 0 3.35 2.864 270.0 N 427 1 1
TOP 1 3.35 2.906 270.0 N 408 2 2
#
# CMP 258
CMP 56 4.575 2.44 270.0 N R223 ??? ;0=1,1=0.016000
PRP ALT_SYMBOLS '(SMC_0402R_C_H016)' 
PRP PARENT_PART_TYPE 'RESISTOR' 
PRP PARENT_PPT 'RESISTOR' 
PRP PARENT_PPT_PART 'RESISTOR-G155-11001-01,1KOHM,1%' 
PRP PART_NAME 'RESISTOR' 
TOP 0 4.575 2.419 270.0 N 338 1 1
TOP 1 4.575 2.461 270.0 N 1 193 2
#
# CMP 259
CMP 56 4.62 2.44 90.0 N R224 ??? ;0=1,1=0.016000
PRP ALT_SYMBOLS '(SMC_0402R_C_H016)' 
PRP PARENT_PART_TYPE 'RESISTOR' 
PRP PARENT_PPT 'RESISTOR' 
PRP PARENT_PPT_PART 'RESISTOR-G155-11001-01,1KOHM,1%' 
PRP PART_NAME 'RESISTOR' 
TOP 0 4.62 2.461 90.0 N 2 599 1
TOP 1 4.62 2.419 90.0 N 338 2 2
#
# CMP 260
CMP 56 4.395 2.44 90.0 N R219 ??? ;0=1,1=0.016000
PRP SIGNAL_MODEL 'RESISTOR-G155-100R0-J0_0OHM_-' 
PRP ALT_SYMBOLS '(SMC_0402R_C_H016)' 
PRP PARENT_PART_TYPE 'RESISTOR' 
PRP PARENT_PPT 'RESISTOR' 
PRP PARENT_PPT_PART 'RESISTOR-G155-11002-01,10KOHM,1%' 
PRP PART_NAME 'RESISTOR' 
TOP 0 4.395 2.461 90.0 N 1 194 1
TOP 1 4.395 2.419 90.0 N 336 1 2
#
# CMP 261
CMP 56 4.44 2.44 270.0 N R220 ??? ;0=1,1=0.016000
PRP ALT_SYMBOLS '(SMC_0402R_C_H016)' 
PRP PARENT_PART_TYPE 'RESISTOR' 
PRP PARENT_PPT 'RESISTOR' 
PRP PARENT_PPT_PART 'RESISTOR-G155-11001-01,1KOHM,1%' 
PRP PART_NAME 'RESISTOR' 
TOP 0 4.44 2.419 270.0 N 336 2 1
TOP 1 4.44 2.461 270.0 N 2 600 2
#
# CMP 262
CMP 56 4.35 2.44 270.0 N R207 ??? ;0=1,1=0.016000
PRP SIGNAL_MODEL 'DEFAULT_RESISTOR_33OHM_2_1' 
PRP ALT_SYMBOLS '(SMC_0402R_C_H016)' 
PRP PARENT_PART_TYPE 'RESISTOR' 
PRP PARENT_PPT 'RESISTOR' 
PRP PARENT_PPT_PART 'RESISTOR-G155-149R9-01,49.9OHM,1%' 
PRP PART_NAME 'RESISTOR' 
TOP 0 4.35 2.419 270.0 N 328 1 1
TOP 1 4.35 2.461 270.0 N 329 1 2
#
# CMP 263
CMP 56 4.961 2.707 270.0 N R174 ??? ;0=1,1=0.016000
PRP SIGNAL_MODEL 'RESISTOR-G155-100R0-J0_0OHM_-' 
PRP ALT_SYMBOLS '(SMC_0402R_C_H016)' 
PRP PARENT_PART_TYPE 'RESISTOR' 
PRP PARENT_PPT 'RESISTOR' 
PRP PARENT_PPT_PART 'RESISTOR-G155-11002-01,10KOHM,1%' 
PRP PART_NAME 'RESISTOR' 
TOP 0 4.961 2.686 270.0 N 23 4 1
TOP 1 4.961 2.728 270.0 N 2 601 2
#
# CMP 264
CMP 56 4.375 3.865 0.0 N R319 ??? ;0=1,1=0.016000
PRP SIGNAL_MODEL 'DEFAULT_RESISTOR_33OHM_2_1' 
PRP ALT_SYMBOLS '(SMC_0402R_C_H016)' 
PRP PARENT_PART_TYPE 'RESISTOR' 
PRP PARENT_PPT 'RESISTOR' 
PRP PARENT_PPT_PART 'RESISTOR-G155-133R0-01,33OHM,1%' 
PRP PART_NAME 'RESISTOR' 
TOP 0 4.396 3.865 0.0 N 391 1 1
TOP 1 4.354 3.865 0.0 N 93 3 2
#
# CMP 265
CMP 56 3.277 3.205 180.0 N R149 ??? ;0=1,1=0.016000
PRP HARD_LOCATION 'YES' 
PRP SIGNAL_MODEL 'RESISTOR-G155-100R0-J0_0OHM_-' 
PRP ALT_SYMBOLS '(SMC_0402R_C_H016)' 
PRP PARENT_PART_TYPE 'RESISTOR' 
PRP PARENT_PPT 'RESISTOR' 
PRP PARENT_PPT_PART 'RESISTOR-G155-14701-01,4.7KOHM,1%' 
PRP PART_NAME 'RESISTOR' 
TOP 0 3.256 3.205 180.0 N 1 195 1
TOP 1 3.298 3.205 180.0 N 292 1 2
#
# CMP 266
CMP 56 3.277 3.43 180.0 N R155 ??? ;0=1,1=0.016000
PRP SIGNAL_MODEL 'RESISTOR-G155-100R0-J0_0OHM_-' 
PRP ALT_SYMBOLS '(SMC_0402R_C_H016)' 
PRP PARENT_PART_TYPE 'RESISTOR' 
PRP PARENT_PPT 'RESISTOR' 
PRP PARENT_PPT_PART 'RESISTOR-G155-14701-01,4.7KOHM,1%' 
PRP PART_NAME 'RESISTOR' 
TOP 0 3.256 3.43 180.0 N 2 602 1
TOP 1 3.298 3.43 180.0 N 291 2 2
#
# CMP 267
CMP 56 3.277 3.25 180.0 N R152 ??? ;0=1,1=0.016000
PRP HARD_LOCATION 'YES' 
PRP SIGNAL_MODEL 'RESISTOR-G155-100R0-J0_0OHM_-' 
PRP ALT_SYMBOLS '(SMC_0402R_C_H016)' 
PRP PARENT_PART_TYPE 'RESISTOR' 
PRP PARENT_PPT 'RESISTOR' 
PRP PARENT_PPT_PART 'RESISTOR-G155-14701-01,4.7KOHM,1%' 
PRP PART_NAME 'RESISTOR' 
TOP 0 3.256 3.25 180.0 N 2 603 1
TOP 1 3.298 3.25 180.0 N 292 2 2
#
# CMP 268
CMP 56 3.277 3.385 180.0 N R146 ??? ;0=1,1=0.016000
PRP SIGNAL_MODEL 'RESISTOR-G155-100R0-J0_0OHM_-' 
PRP ALT_SYMBOLS '(SMC_0402R_C_H016)' 
PRP PARENT_PART_TYPE 'RESISTOR' 
PRP PARENT_PPT 'RESISTOR' 
PRP PARENT_PPT_PART 'RESISTOR-G155-11002-01,10KOHM,1%' 
PRP PART_NAME 'RESISTOR' 
TOP 0 3.256 3.385 180.0 N 1 196 1
TOP 1 3.298 3.385 180.0 N 291 3 2
#
# CMP 269
CMP 56 3.277 3.34 180.0 N R150 ??? ;0=1,1=0.016000
PRP HARD_LOCATION 'YES' 
PRP SIGNAL_MODEL 'RESISTOR-G155-100R0-J0_0OHM_-' 
PRP ALT_SYMBOLS '(SMC_0402R_C_H016)' 
PRP PARENT_PART_TYPE 'RESISTOR' 
PRP PARENT_PPT 'RESISTOR' 
PRP PARENT_PPT_PART 'RESISTOR-G155-14701-01,4.7KOHM,1%' 
PRP PART_NAME 'RESISTOR' 
TOP 0 3.256 3.34 180.0 N 1 197 1
TOP 1 3.298 3.34 180.0 N 294 1 2
#
# CMP 270
CMP 56 3.277 3.295 180.0 N R153 ??? ;0=1,1=0.016000
PRP HARD_LOCATION 'YES' 
PRP SIGNAL_MODEL 'RESISTOR-G155-100R0-J0_0OHM_-' 
PRP ALT_SYMBOLS '(SMC_0402R_C_H016)' 
PRP PARENT_PART_TYPE 'RESISTOR' 
PRP PARENT_PPT 'RESISTOR' 
PRP PARENT_PPT_PART 'RESISTOR-G155-14701-01,4.7KOHM,1%' 
PRP PART_NAME 'RESISTOR' 
TOP 0 3.256 3.295 180.0 N 2 604 1
TOP 1 3.298 3.295 180.0 N 294 2 2
#
# CMP 271
CMP 56 3.277 3.475 180.0 N R60 ??? ;0=1,1=0.016000
PRP SIGNAL_MODEL 'DEFAULT_RESISTOR_33OHM_2_1' 
PRP ALT_SYMBOLS '(SMC_0402R_C_H016)' 
PRP PARENT_PART_TYPE 'RESISTOR' 
PRP PARENT_PPT 'RESISTOR' 
PRP PARENT_PPT_PART 'RESISTOR-G155-133R0-01,33OHM,1%' 
PRP PART_NAME 'RESISTOR' 
TOP 0 3.256 3.475 180.0 N 519 1 1
TOP 1 3.298 3.475 180.0 N 291 4 2
#
# CMP 272
CMP 56 3.047 3.35 0.0 N R151 ??? ;0=1,1=0.016000
PRP HARD_LOCATION 'YES' 
PRP SIGNAL_MODEL 'RESISTOR-G155-100R0-J0_0OHM_-' 
PRP ALT_SYMBOLS '(SMC_0402R_C_H016)' 
PRP PARENT_PART_TYPE 'RESISTOR' 
PRP PARENT_PPT 'RESISTOR' 
PRP PARENT_PPT_PART 'RESISTOR-G155-14701-01,4.7KOHM,1%' 
PRP PART_NAME 'RESISTOR' 
TOP 0 3.068 3.35 0.0 N 1 198 1
TOP 1 3.026 3.35 0.0 N 295 1 2
#
# CMP 273
CMP 56 3.047 3.305 0.0 N R154 ??? ;0=1,1=0.016000
PRP HARD_LOCATION 'YES' 
PRP SIGNAL_MODEL 'RESISTOR-G155-100R0-J0_0OHM_-' 
PRP ALT_SYMBOLS '(SMC_0402R_C_H016)' 
PRP PARENT_PART_TYPE 'RESISTOR' 
PRP PARENT_PPT 'RESISTOR' 
PRP PARENT_PPT_PART 'RESISTOR-G155-14701-01,4.7KOHM,1%' 
PRP PART_NAME 'RESISTOR' 
TOP 0 3.068 3.305 0.0 N 2 605 1
TOP 1 3.026 3.305 0.0 N 295 2 2
#
# CMP 274
CMP 56 3.912 3.092 180.0 N R165 ??? ;0=1,1=0.016000
PRP SIGNAL_MODEL 'RESISTOR-G155-100R0-J0_0OHM_-' 
PRP REUSE_ID '17' 
PRP ALT_SYMBOLS '(SMC_0402R_C_H016)' 
PRP PARENT_PART_TYPE 'RESISTOR' 
PRP PARENT_PPT 'RESISTOR' 
PRP PARENT_PPT_PART 'RESISTOR-G155-11002-01,10KOHM,1%' 
PRP PART_NAME 'RESISTOR' 
TOP 0 3.891 3.092 180.0 N 20 3 1
TOP 1 3.933 3.092 180.0 N 2 606 2
#
# CMP 275
CMP 56 3.573 4.197 180.0 N R263 ??? ;0=1,1=0.016000
PRP SIGNAL_MODEL 'RESISTOR-G155-100R0-J0_0OHM_-' 
PRP REUSE_ID '15' 
PRP ALT_SYMBOLS '(SMC_0402R_C_H016,C0402-0P8MM-45DG)' 
PRP PARENT_PART_TYPE 'RESISTOR' 
PRP PARENT_PPT 'RESISTOR' 
PRP PARENT_PPT_PART 'RESISTOR-G155-100R0-J0,0OHM,-' 
PRP PART_NAME 'RESISTOR' 
TOP 0 3.552 4.197 180.0 N 127 3 1
TOP 1 3.594 4.197 180.0 N 346 1 2
#
# CMP 276
CMP 56 3.543 3.987 180.0 N R36 ??? ;0=1,1=0.016000
PRP SIGNAL_MODEL 'RESISTOR-G155-100R0-J0_0OHM_-' 
PRP REUSE_ID '32' 
PRP ALT_SYMBOLS '(SMC_0402R_C_H016)' 
PRP PARENT_PART_TYPE 'RESISTOR' 
PRP PARENT_PPT 'RESISTOR' 
PRP PARENT_PPT_PART 'RESISTOR-G155-11002-01,10KOHM,1%' 
PRP PART_NAME 'RESISTOR' 
TOP 0 3.522 3.987 180.0 N 116 2 1
TOP 1 3.564 3.987 180.0 N 115 0 2
#
# CMP 277
CMP 56 3.543 4.077 0.0 N R53 ??? ;0=1,1=0.016000
PRP REUSE_ID '12' 
PRP ALT_SYMBOLS '(SMC_0402R_C_H016)' 
PRP PARENT_PART_TYPE 'RESISTOR' 
PRP PARENT_PPT 'RESISTOR' 
PRP PARENT_PPT_PART 'RESISTOR-G152-10344-01,30KOHM,0.1%' 
PRP PART_NAME 'RESISTOR' 
TOP 0 3.564 4.077 0.0 N 110 7 1
TOP 1 3.522 4.077 0.0 N 79 4 2
#
# CMP 278
CMP 56 3.765 3.37 0.0 N R201 ??? ;0=1,1=0.016000
PRP HARD_LOCATION 'YES' 
PRP SIGNAL_MODEL 'RESISTOR-G155-100R0-J0_0OHM_-' 
PRP ALT_SYMBOLS '(SMC_0402R_C_H016)' 
PRP PARENT_PART_TYPE 'RESISTOR' 
PRP PARENT_PPT 'RESISTOR' 
PRP PARENT_PPT_PART 'RESISTOR-G155-14701-01,4.7KOHM,1%' 
PRP PART_NAME 'RESISTOR' 
TOP 0 3.786 3.37 0.0 N 322 1 1
TOP 1 3.744 3.37 0.0 N 1 199 2
#
# CMP 279
CMP 56 3.765 3.415 0.0 N R205 ??? ;0=1,1=0.016000
PRP HARD_LOCATION 'YES' 
PRP SIGNAL_MODEL 'DEFAULT_RESISTOR_33OHM_2_1' 
PRP ALT_SYMBOLS '(SMC_0402R_C_H016)' 
PRP PARENT_PART_TYPE 'RESISTOR' 
PRP PARENT_PPT 'RESISTOR' 
PRP PARENT_PPT_PART 'RESISTOR-G155-133R0-01,33OHM,1%' 
PRP PART_NAME 'RESISTOR' 
TOP 0 3.786 3.415 0.0 N 322 2 1
TOP 1 3.744 3.415 0.0 N 326 2 2
#
# CMP 280
CMP 56 3.765 3.325 0.0 N R204 ??? ;0=1,1=0.016000
PRP HARD_LOCATION 'YES' 
PRP SIGNAL_MODEL 'DEFAULT_RESISTOR_33OHM_2_1' 
PRP ALT_SYMBOLS '(SMC_0402R_C_H016)' 
PRP PARENT_PART_TYPE 'RESISTOR' 
PRP PARENT_PPT 'RESISTOR' 
PRP PARENT_PPT_PART 'RESISTOR-G155-133R0-01,33OHM,1%' 
PRP PART_NAME 'RESISTOR' 
TOP 0 3.786 3.325 0.0 N 321 1 1
TOP 1 3.744 3.325 0.0 N 325 1 2
#
# CMP 281
CMP 56 3.765 3.28 0.0 N R200 ??? ;0=1,1=0.016000
PRP HARD_LOCATION 'YES' 
PRP SIGNAL_MODEL 'RESISTOR-G155-100R0-J0_0OHM_-' 
PRP ALT_SYMBOLS '(SMC_0402R_C_H016)' 
PRP PARENT_PART_TYPE 'RESISTOR' 
PRP PARENT_PPT 'RESISTOR' 
PRP PARENT_PPT_PART 'RESISTOR-G155-14701-01,4.7KOHM,1%' 
PRP PART_NAME 'RESISTOR' 
TOP 0 3.786 3.28 0.0 N 321 2 1
TOP 1 3.744 3.28 0.0 N 1 200 2
#
# CMP 282
CMP 56 3.765 3.235 180.0 N R191 ??? ;0=1,1=0.016000
PRP SIGNAL_MODEL 'RESISTOR-G155-100R0-J0_0OHM_-' 
PRP ALT_SYMBOLS '(SMC_0402R_C_H016)' 
PRP PARENT_PART_TYPE 'RESISTOR' 
PRP PARENT_PPT 'RESISTOR' 
PRP PARENT_PPT_PART 'RESISTOR-G155-14701-01,4.7KOHM,1%' 
PRP PART_NAME 'RESISTOR' 
TOP 0 3.744 3.235 180.0 N 1 201 1
TOP 1 3.786 3.235 180.0 N 312 2 2
#
# CMP 283
CMP 56 3.485 3.235 180.0 N R206 ??? ;0=1,1=0.016000
PRP HARD_LOCATION 'YES' 
PRP SIGNAL_MODEL 'DEFAULT_RESISTOR_33OHM_2_1' 
PRP ALT_SYMBOLS '(SMC_0402R_C_H016)' 
PRP PARENT_PART_TYPE 'RESISTOR' 
PRP PARENT_PPT 'RESISTOR' 
PRP PARENT_PPT_PART 'RESISTOR-G155-133R0-01,33OHM,1%' 
PRP PART_NAME 'RESISTOR' 
TOP 0 3.464 3.235 180.0 N 323 1 1
TOP 1 3.506 3.235 180.0 N 327 2 2
#
# CMP 284
CMP 56 3.485 3.28 180.0 N R202 ??? ;0=1,1=0.016000
PRP HARD_LOCATION 'YES' 
PRP SIGNAL_MODEL 'RESISTOR-G155-100R0-J0_0OHM_-' 
PRP ALT_SYMBOLS '(SMC_0402R_C_H016)' 
PRP PARENT_PART_TYPE 'RESISTOR' 
PRP PARENT_PPT 'RESISTOR' 
PRP PARENT_PPT_PART 'RESISTOR-G155-14701-01,4.7KOHM,1%' 
PRP PART_NAME 'RESISTOR' 
TOP 0 3.464 3.28 180.0 N 323 2 1
TOP 1 3.506 3.28 180.0 N 1 202 2
#
# CMP 285
CMP 56 3.485 3.415 180.0 N R203 ??? ;0=1,1=0.016000
PRP SIGNAL_MODEL 'DEFAULT_RESISTOR_33OHM_2_1' 
PRP ALT_SYMBOLS '(SMC_0402R_C_H016)' 
PRP PARENT_PART_TYPE 'RESISTOR' 
PRP PARENT_PPT 'RESISTOR' 
PRP PARENT_PPT_PART 'RESISTOR-G155-133R0-01,33OHM,1%' 
PRP PART_NAME 'RESISTOR' 
TOP 0 3.464 3.415 180.0 N 318 1 1
TOP 1 3.506 3.415 180.0 N 324 1 2
#
# CMP 286
CMP 56 3.485 3.325 180.0 N R192 ??? ;0=1,1=0.016000
PRP SIGNAL_MODEL 'RESISTOR-G155-100R0-J0_0OHM_-' 
PRP ALT_SYMBOLS '(SMC_0402R_C_H016)' 
PRP PARENT_PART_TYPE 'RESISTOR' 
PRP PARENT_PPT 'RESISTOR' 
PRP PARENT_PPT_PART 'RESISTOR-G155-14701-01,4.7KOHM,1%' 
PRP PART_NAME 'RESISTOR' 
TOP 0 3.464 3.325 180.0 N 313 2 1
TOP 1 3.506 3.325 180.0 N 2 607 2
#
# CMP 287
CMP 56 3.485 3.37 180.0 N R199 ??? ;0=1,1=0.016000
PRP SIGNAL_MODEL 'RESISTOR-G155-100R0-J0_0OHM_-' 
PRP ALT_SYMBOLS '(SMC_0402R_C_H016)' 
PRP PARENT_PART_TYPE 'RESISTOR' 
PRP PARENT_PPT 'RESISTOR' 
PRP PARENT_PPT_PART 'RESISTOR-G155-14701-01,4.7KOHM,1%' 
PRP PART_NAME 'RESISTOR' 
TOP 0 3.464 3.37 180.0 N 318 2 1
TOP 1 3.506 3.37 180.0 N 1 203 2
#
# CMP 288
CMP 56 3.485 2.885 90.0 N R341 ??? ;0=1,1=0.016000
PRP SIGNAL_MODEL 'RESISTOR-G155-100R0-J0_0OHM_-' 
PRP ALT_SYMBOLS '(SMC_0402R_C_H016)' 
PRP PARENT_PART_TYPE 'RESISTOR' 
PRP PARENT_PPT 'RESISTOR' 
PRP PARENT_PPT_PART 'RESISTOR-G155-14701-01,4.7KOHM,1%' 
PRP PART_NAME 'RESISTOR' 
TOP 0 3.485 2.906 90.0 N 1 204 1
TOP 1 3.485 2.864 90.0 N 399 1 2
#
# CMP 289
CMP 56 3.44 2.885 90.0 N R330 ??? ;0=1,1=0.016000
PRP SIGNAL_MODEL 'DEFAULT_RESISTOR_33OHM_2_1' 
PRP ALT_SYMBOLS '(SMC_0402R_C_H016)' 
PRP PARENT_PART_TYPE 'RESISTOR' 
PRP PARENT_PPT 'RESISTOR' 
PRP PARENT_PPT_PART 'RESISTOR-G155-133R0-01,33OHM,1%' 
PRP PART_NAME 'RESISTOR' 
TOP 0 3.44 2.906 90.0 N 398 1 1
TOP 1 3.44 2.864 90.0 N 399 2 2
#
# CMP 290
CMP 56 4.935 3.525 270.0 N R110 ??? ;0=1,1=0.016000
PRP SIGNAL_MODEL 'DEFAULT_RESISTOR_33OHM_2_1' 
PRP ALT_SYMBOLS '(SMC_0402R_C_H016)' 
PRP PARENT_PART_TYPE 'RESISTOR' 
PRP PARENT_PPT 'RESISTOR' 
PRP PARENT_PPT_PART 'RESISTOR-G155-133R0-01,33OHM,1%' 
PRP PART_NAME 'RESISTOR' 
TOP 0 4.935 3.504 270.0 N 260 1 1
TOP 1 4.935 3.546 270.0 N 242 3 2
#
# CMP 291
CMP 56 5.01 3.455 180.0 N R269 ??? ;0=1,1=0.016000
PRP ALT_SYMBOLS '(SMC_0402R_C_H016)' 
PRP PARENT_PART_TYPE 'RESISTOR' 
PRP PARENT_PPT 'RESISTOR' 
PRP PARENT_PPT_PART 'RESISTOR-G155-11003-01,100KOHM,1%' 
PRP PART_NAME 'RESISTOR' 
TOP 0 4.989 3.455 180.0 N 1 205 1
TOP 1 5.031 3.455 180.0 N 259 1 2
#
# CMP 292
CMP 56 4.985 3.525 270.0 N R109 ??? ;0=1,1=0.016000
PRP SIGNAL_MODEL 'DEFAULT_RESISTOR_33OHM_2_1' 
PRP ALT_SYMBOLS '(SMC_0402R_C_H016)' 
PRP PARENT_PART_TYPE 'RESISTOR' 
PRP PARENT_PPT 'RESISTOR' 
PRP PARENT_PPT_PART 'RESISTOR-G155-133R0-01,33OHM,1%' 
PRP PART_NAME 'RESISTOR' 
TOP 0 4.985 3.504 270.0 N 259 2 1
TOP 1 4.985 3.546 270.0 N 240 2 2
#
# CMP 293
CMP 56 4.885 3.525 270.0 N R111 ??? ;0=1,1=0.016000
PRP SIGNAL_MODEL 'DEFAULT_RESISTOR_33OHM_2_1' 
PRP ALT_SYMBOLS '(SMC_0402R_C_H016)' 
PRP PARENT_PART_TYPE 'RESISTOR' 
PRP PARENT_PPT 'RESISTOR' 
PRP PARENT_PPT_PART 'RESISTOR-G155-133R0-01,33OHM,1%' 
PRP PART_NAME 'RESISTOR' 
TOP 0 4.885 3.504 270.0 N 261 2 1
TOP 1 4.885 3.546 270.0 N 244 1 2
#
# CMP 294
CMP 56 4.757 3.551 0.0 N R115 ??? ;0=1,1=0.016000
PRP SIGNAL_MODEL 'RESISTOR-G155-100R0-J0_0OHM_-' 
PRP ALT_SYMBOLS '(SMC_0402R_C_H016)' 
PRP PARENT_PART_TYPE 'RESISTOR' 
PRP PARENT_PPT 'RESISTOR' 
PRP PARENT_PPT_PART 'RESISTOR-G155-14701-01,4.7KOHM,1%' 
PRP PART_NAME 'RESISTOR' 
TOP 0 4.778 3.551 0.0 N 70 3 1
TOP 1 4.736 3.551 0.0 N 241 4 2
#
# CMP 295
CMP 56 4.245 4.115 180.0 N R318 ??? ;0=1,1=0.016000
PRP SIGNAL_MODEL 'RESISTOR-G155-100R0-J0_0OHM_-' 
PRP ALT_SYMBOLS '(SMC_0402R_C_H016)' 
PRP PARENT_PART_TYPE 'RESISTOR' 
PRP PARENT_PPT 'RESISTOR' 
PRP PARENT_PPT_PART 'RESISTOR-G155-11002-01,10KOHM,1%' 
PRP PART_NAME 'RESISTOR' 
TOP 0 4.224 4.115 180.0 N 1 206 1
TOP 1 4.266 4.115 180.0 N 390 2 2
#
# CMP 296
CMP 56 4.245 4.065 180.0 N R317 ??? ;0=1,1=0.016000
PRP SIGNAL_MODEL 'RESISTOR-G155-100R0-J0_0OHM_-' 
PRP ALT_SYMBOLS '(SMC_0402R_C_H016)' 
PRP PARENT_PART_TYPE 'RESISTOR' 
PRP PARENT_PPT 'RESISTOR' 
PRP PARENT_PPT_PART 'RESISTOR-G155-11002-01,10KOHM,1%' 
PRP PART_NAME 'RESISTOR' 
TOP 0 4.224 4.065 180.0 N 1 207 1
TOP 1 4.266 4.065 180.0 N 389 2 2
#
# CMP 297
CMP 56 4.375 4.065 0.0 N R321 ??? ;0=1,1=0.016000
PRP SIGNAL_MODEL 'DEFAULT_RESISTOR_33OHM_2_1' 
PRP ALT_SYMBOLS '(SMC_0402R_C_H016)' 
PRP PARENT_PART_TYPE 'RESISTOR' 
PRP PARENT_PPT 'RESISTOR' 
PRP PARENT_PPT_PART 'RESISTOR-G155-133R0-01,33OHM,1%' 
PRP PART_NAME 'RESISTOR' 
TOP 0 4.396 4.065 0.0 N 392 1 1
TOP 1 4.354 4.065 0.0 N 389 3 2
#
# CMP 298
CMP 56 4.375 4.115 0.0 N R322 ??? ;0=1,1=0.016000
PRP SIGNAL_MODEL 'DEFAULT_RESISTOR_33OHM_2_1' 
PRP ALT_SYMBOLS '(SMC_0402R_C_H016)' 
PRP PARENT_PART_TYPE 'RESISTOR' 
PRP PARENT_PPT 'RESISTOR' 
PRP PARENT_PPT_PART 'RESISTOR-G155-133R0-01,33OHM,1%' 
PRP PART_NAME 'RESISTOR' 
TOP 0 4.396 4.115 0.0 N 393 1 1
TOP 1 4.354 4.115 0.0 N 390 3 2
#
# CMP 299
CMP 56 6.015 2.79 0.0 N R82 ??? ;0=1,1=0.016000
PRP SIGNAL_MODEL 'DEFAULT_RESISTOR_33OHM_2_1' 
PRP ALT_SYMBOLS '(SMC_0402R_C_H016)' 
PRP PARENT_PART_TYPE 'RESISTOR' 
PRP PARENT_PPT 'RESISTOR' 
PRP PARENT_PPT_PART 'RESISTOR-G155-133R0-01,33OHM,1%' 
PRP PART_NAME 'RESISTOR' 
TOP 0 6.036 2.79 0.0 N 229 2 1
TOP 1 5.994 2.79 0.0 N 201 1 2
#
# CMP 300
CMP 56 6.015 2.615 0.0 N R81 ??? ;0=1,1=0.016000
PRP SIGNAL_MODEL 'DEFAULT_RESISTOR_33OHM_2_1' 
PRP ALT_SYMBOLS '(SMC_0402R_C_H016)' 
PRP PARENT_PART_TYPE 'RESISTOR' 
PRP PARENT_PPT 'RESISTOR' 
PRP PARENT_PPT_PART 'RESISTOR-G155-133R0-01,33OHM,1%' 
PRP PART_NAME 'RESISTOR' 
TOP 0 6.036 2.615 0.0 N 230 3 1
TOP 1 5.994 2.615 0.0 N 198 1 2
#
# CMP 301
CMP 56 5.525 2.77 0.0 N R135 ??? ;0=1,1=0.016000
PRP SIGNAL_MODEL 'RESISTOR-G155-100R0-J0_0OHM_-' 
PRP ALT_SYMBOLS '(SMC_0402R_C_H016,C0402-0P8MM-45DG)' 
PRP PARENT_PART_TYPE 'RESISTOR' 
PRP PARENT_PPT 'RESISTOR' 
PRP PARENT_PPT_PART 'RESISTOR-G155-100R0-J0,0OHM,-' 
PRP PART_NAME 'RESISTOR' 
TOP 0 5.546 2.77 0.0 N 142 2 1
TOP 1 5.504 2.77 0.0 N 280 2 2
#
# CMP 302
CMP 56 5.523 2.721 0.0 N R133 ??? ;0=1,1=0.016000
PRP SIGNAL_MODEL 'DEFAULT_RESISTOR_33OHM_2_1' 
PRP ALT_SYMBOLS '(SMC_0402R_C_H016)' 
PRP PARENT_PART_TYPE 'RESISTOR' 
PRP PARENT_PPT 'RESISTOR' 
PRP PARENT_PPT_PART 'RESISTOR-G155-133R0-01,33OHM,1%' 
PRP PART_NAME 'RESISTOR' 
TOP 0 5.544 2.721 0.0 N 1 208 1
TOP 1 5.502 2.721 0.0 N 210 1 2
#
# CMP 303
CMP 56 5.525 2.64 0.0 N R134 ??? ;0=1,1=0.016000
PRP SIGNAL_MODEL 'DEFAULT_RESISTOR_33OHM_2_1' 
PRP ALT_SYMBOLS '(SMC_0402R_C_H016)' 
PRP PARENT_PART_TYPE 'RESISTOR' 
PRP PARENT_PPT 'RESISTOR' 
PRP PARENT_PPT_PART 'RESISTOR-G155-133R0-01,33OHM,1%' 
PRP PART_NAME 'RESISTOR' 
TOP 0 5.546 2.64 0.0 N 141 2 1
TOP 1 5.504 2.64 0.0 N 279 2 2
#
# CMP 304
CMP 56 5.452 2.792 90.0 N R403 ??? ;0=1,1=0.016000
PRP SIGNAL_MODEL 'RESISTOR-G155-100R0-J0_0OHM_-' 
PRP ALT_SYMBOLS '(SMC_0402R_C_H016)' 
PRP PARENT_PART_TYPE 'RESISTOR' 
PRP PARENT_PPT 'RESISTOR' 
PRP PARENT_PPT_PART 'RESISTOR-G155-11002-01,10KOHM,1%' 
PRP PART_NAME 'RESISTOR' 
TOP 0 5.452 2.813 90.0 N 1 209 1
TOP 1 5.452 2.771 90.0 N 280 3 2
#
# CMP 305
CMP 56 5.4525 2.6585 270.0 N R402 ??? ;0=1,1=0.016000
PRP SIGNAL_MODEL 'RESISTOR-G155-100R0-J0_0OHM_-' 
PRP ALT_SYMBOLS '(SMC_0402R_C_H016)' 
PRP PARENT_PART_TYPE 'RESISTOR' 
PRP PARENT_PPT 'RESISTOR' 
PRP PARENT_PPT_PART 'RESISTOR-G155-14701-01,4.7KOHM,1%' 
PRP PART_NAME 'RESISTOR' 
TOP 0 5.4525 2.6375 270.0 N 279 3 1
TOP 1 5.4525 2.6795 270.0 N 2 608 2
#
# CMP 306
CMP 56 6.145 4.115 90.0 N R169 ??? ;0=1,1=0.016000
PRP REUSE_ID '12' 
PRP ALT_SYMBOLS '(SMC_0402R_C_H016)' 
PRP PARENT_PART_TYPE 'RESISTOR' 
PRP PARENT_PPT 'RESISTOR' 
PRP PARENT_PPT_PART 'RESISTOR-G155-13300-01,330OHM,1%' 
PRP PART_NAME 'RESISTOR' 
TOP 0 6.145 4.136 90.0 N 149 1 1
TOP 1 6.145 4.094 90.0 N 88 25 2
#
# CMP 307
CMP 56 3.978 2.531 90.0 N R171 ??? ;0=1,1=0.016000
PRP SIGNAL_MODEL 'RESISTOR-G155-100R0-J0_0OHM_-' 
PRP REUSE_ID '20' 
PRP ALT_SYMBOLS '(SMC_0402R_C_H016)' 
PRP PARENT_PART_TYPE 'RESISTOR' 
PRP PARENT_PPT 'RESISTOR' 
PRP PARENT_PPT_PART 'RESISTOR-G155-14701-01,4.7KOHM,1%' 
PRP PART_NAME 'RESISTOR' 
TOP 0 3.978 2.552 90.0 N 2 609 1
TOP 1 3.978 2.51 90.0 N 304 3 2
#
# CMP 308
CMP 56 3.47 2.355 90.0 N R168 ??? ;0=1,1=0.016000
PRP REUSE_ID '26' 
PRP ALT_SYMBOLS '(SMC_0402R_C_H016)' 
PRP PARENT_PART_TYPE 'RESISTOR' 
PRP PARENT_PPT 'RESISTOR' 
PRP PARENT_PPT_PART 'RESISTOR-G155-11004-01,1MOHM,1%' 
PRP PART_NAME 'RESISTOR' 
TOP 0 3.47 2.376 90.0 N 114 3 1
TOP 1 3.47 2.334 90.0 N 109 3 2
#
# CMP 309
CMP 56 5.525 3.02 0.0 N R137 ??? ;0=1,1=0.016000
PRP SIGNAL_MODEL 'DEFAULT_RESISTOR_33OHM_2_1' 
PRP ALT_SYMBOLS '(SMC_0402R_C_H016)' 
PRP PARENT_PART_TYPE 'RESISTOR' 
PRP PARENT_PPT 'RESISTOR' 
PRP PARENT_PPT_PART 'RESISTOR-G155-133R0-01,33OHM,1%' 
PRP PART_NAME 'RESISTOR' 
TOP 0 5.546 3.02 0.0 N 140 2 1
TOP 1 5.504 3.02 0.0 N 282 2 2
#
# CMP 310
CMP 56 5.523 2.9225 0.0 N R136 ??? ;0=1,1=0.016000
PRP SIGNAL_MODEL 'DEFAULT_RESISTOR_33OHM_2_1' 
PRP ALT_SYMBOLS '(SMC_0402R_C_H016)' 
PRP PARENT_PART_TYPE 'RESISTOR' 
PRP PARENT_PPT 'RESISTOR' 
PRP PARENT_PPT_PART 'RESISTOR-G155-133R0-01,33OHM,1%' 
PRP PART_NAME 'RESISTOR' 
TOP 0 5.544 2.9225 0.0 N 139 2 1
TOP 1 5.502 2.9225 0.0 N 281 2 2
#
# CMP 311
CMP 56 0.878 0.932 90.0 N R159 ??? ;0=1,1=0.016000
PRP SIGNAL_MODEL 'RESISTOR-G155-100R0-J0_0OHM_-' 
PRP REUSE_ID '5' 
PRP ALT_SYMBOLS '(SMC_0402R_C_H016)' 
PRP PARENT_PART_TYPE 'RESISTOR' 
PRP PARENT_PPT 'RESISTOR' 
PRP PARENT_PPT_PART 'RESISTOR-G155-14701-01,4.7KOHM,1%' 
PRP PART_NAME 'RESISTOR' 
TOP 0 0.878 0.953 90.0 N 300 1 1
TOP 1 0.878 0.911 90.0 N 2 610 2
#
# CMP 312
CMP 56 5.323 4.18001 90.0 N R208 ??? ;0=1,1=0.016000
PRP ALT_SYMBOLS '(SMC_0402R_C_H016)' 
PRP PARENT_PART_TYPE 'RESISTOR' 
PRP PARENT_PPT 'RESISTOR' 
PRP PARENT_PPT_PART 'RESISTOR-G155-13300-01,330OHM,1%' 
PRP PART_NAME 'RESISTOR' 
TOP 0 5.323 4.20101 90.0 N 177 1 1
TOP 1 5.323 4.15901 90.0 N 330 2 2
#
# CMP 313
CMP 56 5.273 4.18001 270.0 N R210 ??? ;0=1,1=0.016000
PRP ALT_SYMBOLS '(SMC_0402R_C_H016)' 
PRP PARENT_PART_TYPE 'RESISTOR' 
PRP PARENT_PPT 'RESISTOR' 
PRP PARENT_PPT_PART 'RESISTOR-G155-13300-01,330OHM,1%' 
PRP PART_NAME 'RESISTOR' 
TOP 0 5.273 4.15901 270.0 N 330 3 1
TOP 1 5.273 4.20101 270.0 N 1 210 2
#
# CMP 314
CMP 56 5.435 4.24 90.0 N R257 ??? ;0=1,1=0.016000
PRP REUSE_ID '1' 
PRP ALT_SYMBOLS '(SMC_0402R_C_H016)' 
PRP PARENT_PART_TYPE 'RESISTOR' 
PRP PARENT_PPT 'RESISTOR' 
PRP PARENT_PPT_PART 'RESISTOR-G155-13300-01,330OHM,1%' 
PRP PART_NAME 'RESISTOR' 
TOP 0 5.435 4.261 90.0 N 143 1 1
TOP 1 5.435 4.219 90.0 N 1 211 2
#
# CMP 315
CMP 56 1.33 0.753 180.0 N R158 ??? ;0=1,1=0.016000
PRP SIGNAL_MODEL 'RESISTOR-G155-100R0-J0_0OHM_-' 
PRP REUSE_ID '1' 
PRP ALT_SYMBOLS '(SMC_0402R_C_H016)' 
PRP PARENT_PART_TYPE 'RESISTOR' 
PRP PARENT_PPT 'RESISTOR' 
PRP PARENT_PPT_PART 'RESISTOR-G155-14701-01,4.7KOHM,1%' 
PRP PART_NAME 'RESISTOR' 
TOP 0 1.309 0.753 180.0 N 1 212 1
TOP 1 1.351 0.753 180.0 N 300 2 2
#
# CMP 316
CMP 56 5.452 3.04 90.0 N R405 ??? ;0=1,1=0.016000
PRP SIGNAL_MODEL 'RESISTOR-G155-100R0-J0_0OHM_-' 
PRP ALT_SYMBOLS '(SMC_0402R_C_H016)' 
PRP PARENT_PART_TYPE 'RESISTOR' 
PRP PARENT_PPT 'RESISTOR' 
PRP PARENT_PPT_PART 'RESISTOR-G155-11002-01,10KOHM,1%' 
PRP PART_NAME 'RESISTOR' 
TOP 0 5.452 3.061 90.0 N 1 213 1
TOP 1 5.452 3.019 90.0 N 282 3 2
#
# CMP 317
CMP 56 5.452 2.9435 90.0 N R404 ??? ;0=1,1=0.016000
PRP SIGNAL_MODEL 'RESISTOR-G155-100R0-J0_0OHM_-' 
PRP ALT_SYMBOLS '(SMC_0402R_C_H016)' 
PRP PARENT_PART_TYPE 'RESISTOR' 
PRP PARENT_PPT 'RESISTOR' 
PRP PARENT_PPT_PART 'RESISTOR-G155-11002-01,10KOHM,1%' 
PRP PART_NAME 'RESISTOR' 
TOP 0 5.452 2.9645 90.0 N 1 214 1
TOP 1 5.452 2.9225 90.0 N 281 3 2
#
# CMP 318
CMP 56 6.027 4.24 90.0 N R279 ??? ;0=1,1=0.016000
PRP ALT_SYMBOLS '(SMC_0402R_C_H016)' 
PRP PARENT_PART_TYPE 'RESISTOR' 
PRP PARENT_PPT 'RESISTOR' 
PRP PARENT_PPT_PART 'RESISTOR-G155-13300-01,330OHM,1%' 
PRP PART_NAME 'RESISTOR' 
TOP 0 6.027 4.261 90.0 N 145 1 1
TOP 1 6.027 4.219 90.0 N 1 215 2
#
# CMP 319
CMP 56 6.14 4.24 90.0 N R280 ??? ;0=1,1=0.016000
PRP ALT_SYMBOLS '(SMC_0402R_C_H016)' 
PRP PARENT_PART_TYPE 'RESISTOR' 
PRP PARENT_PPT 'RESISTOR' 
PRP PARENT_PPT_PART 'RESISTOR-G155-13300-01,330OHM,1%' 
PRP PART_NAME 'RESISTOR' 
TOP 0 6.14 4.261 90.0 N 147 1 1
TOP 1 6.14 4.219 90.0 N 1 216 2
#
# CMP 320
CMP 56 5.675 4.105 90.0 N R180 ??? ;0=1,1=0.016000
PRP REUSE_ID '1' 
PRP ALT_SYMBOLS '(SMC_0402R_C_H016)' 
PRP PARENT_PART_TYPE 'RESISTOR' 
PRP PARENT_PPT 'RESISTOR' 
PRP PARENT_PPT_PART 'RESISTOR-G155-11001-01,1KOHM,1%' 
PRP PART_NAME 'RESISTOR' 
TOP 0 5.675 4.126 90.0 N 176 1 1
TOP 1 5.675 4.084 90.0 N 13 11 2
#
# CMP 321
CMP 56 5.79 4.075 0.0 N R262 ??? ;0=1,1=0.016000
PRP ALT_SYMBOLS '(SMC_0402R_C_H016)' 
PRP PARENT_PART_TYPE 'RESISTOR' 
PRP PARENT_PPT 'RESISTOR' 
PRP PARENT_PPT_PART 'RESISTOR-G155-11001-01,1KOHM,1%' 
PRP PART_NAME 'RESISTOR' 
TOP 0 5.811 4.075 0.0 N 350 0 1
TOP 1 5.769 4.075 0.0 N 3 21 2
#
# CMP 322
CMP 56 5.79 4.12 180.0 N R256 ??? ;0=1,1=0.016000
PRP ALT_SYMBOLS '(SMC_0402R_C_H016)' 
PRP PARENT_PART_TYPE 'RESISTOR' 
PRP PARENT_PPT 'RESISTOR' 
PRP PARENT_PPT_PART 'RESISTOR-G155-11001-01,1KOHM,1%' 
PRP PART_NAME 'RESISTOR' 
TOP 0 5.769 4.12 180.0 N 173 1 1
TOP 1 5.811 4.12 180.0 N 350 1 2
#
# CMP 323
CMP 56 5.55 4.115 180.0 N R108 ??? ;0=1,1=0.016000
PRP SIGNAL_MODEL 'RESISTOR-G155-11000-01_100OHM_A' 
PRP ALT_SYMBOLS '(SMC_0402R_C_H016)' 
PRP PARENT_PART_TYPE 'RESISTOR' 
PRP PARENT_PPT 'RESISTOR' 
PRP PARENT_PPT_PART 'RESISTOR-G155-11000-01,100OHM,1%' 
PRP PART_NAME 'RESISTOR' 
TOP 0 5.529 4.115 180.0 N 175 1 1
TOP 1 5.571 4.115 180.0 N 258 0 2
#
# CMP 324
CMP 56 5.55 4.07 0.0 N R139 ??? ;0=1,1=0.016000
PRP SIGNAL_MODEL 'DEFAULT_RESISTOR_33OHM_2_1' 
PRP ALT_SYMBOLS '(SMC_0402R_C_H016)' 
PRP PARENT_PART_TYPE 'RESISTOR' 
PRP PARENT_PPT 'RESISTOR' 
PRP PARENT_PPT_PART 'RESISTOR-G155-133R0-01,33OHM,1%' 
PRP PART_NAME 'RESISTOR' 
TOP 0 5.571 4.07 0.0 N 258 1 1
TOP 1 5.529 4.07 0.0 N 9 38 2
#
# CMP 325
CMP 56 0.788 0.932 270.0 N R160 ??? ;0=1,1=0.016000
PRP SIGNAL_MODEL 'RESISTOR-G155-100R0-J0_0OHM_-' 
PRP REUSE_ID '6' 
PRP ALT_SYMBOLS '(SMC_0402R_C_H016)' 
PRP PARENT_PART_TYPE 'RESISTOR' 
PRP PARENT_PPT 'RESISTOR' 
PRP PARENT_PPT_PART 'RESISTOR-G155-14701-01,4.7KOHM,1%' 
PRP PART_NAME 'RESISTOR' 
TOP 0 0.788 0.911 270.0 N 1 217 1
TOP 1 0.788 0.953 270.0 N 301 2 2
#
# CMP 326
CMP 56 5.555 4.24 90.0 N R258 ??? ;0=1,1=0.016000
PRP ALT_SYMBOLS '(SMC_0402R_C_H016)' 
PRP PARENT_PART_TYPE 'RESISTOR' 
PRP PARENT_PPT 'RESISTOR' 
PRP PARENT_PPT_PART 'RESISTOR-G155-13300-01,330OHM,1%' 
PRP PART_NAME 'RESISTOR' 
TOP 0 5.555 4.261 90.0 N 166 1 1
TOP 1 5.555 4.219 90.0 N 1 218 2
#
# CMP 327
CMP 56 5.67 4.24 90.0 N R259 ??? ;0=1,1=0.016000
PRP ALT_SYMBOLS '(SMC_0402R_C_H016)' 
PRP PARENT_PART_TYPE 'RESISTOR' 
PRP PARENT_PPT 'RESISTOR' 
PRP PARENT_PPT_PART 'RESISTOR-G155-13300-01,330OHM,1%' 
PRP PART_NAME 'RESISTOR' 
TOP 0 5.67 4.261 90.0 N 169 1 1
TOP 1 5.67 4.219 90.0 N 1 219 2
#
# CMP 328
CMP 56 5.435 4.145 270.0 N R138 ??? ;0=1,1=0.016000
PRP ALT_SYMBOLS '(SMC_0402R_C_H016)' 
PRP PARENT_PART_TYPE 'RESISTOR' 
PRP PARENT_PPT 'RESISTOR' 
PRP PARENT_PPT_PART 'RESISTOR-G155-13300-01,330OHM,1%' 
PRP PART_NAME 'RESISTOR' 
TOP 0 5.435 4.124 270.0 N 174 1 1
TOP 1 5.435 4.166 270.0 N 1 220 2
#
# CMP 329
CMP 56 0.743 0.932 270.0 N R162 ??? ;0=1,1=0.016000
PRP SIGNAL_MODEL 'RESISTOR-G155-100R0-J0_0OHM_-' 
PRP REUSE_ID '8' 
PRP ALT_SYMBOLS '(SMC_0402R_C_H016)' 
PRP PARENT_PART_TYPE 'RESISTOR' 
PRP PARENT_PPT 'RESISTOR' 
PRP PARENT_PPT_PART 'RESISTOR-G155-14701-01,4.7KOHM,1%' 
PRP PART_NAME 'RESISTOR' 
TOP 0 0.743 0.911 270.0 N 1 221 1
TOP 1 0.743 0.953 270.0 N 302 2 2
#
# CMP 330
CMP 56 5.79 4.24 90.0 N R261 ??? ;0=1,1=0.016000
PRP ALT_SYMBOLS '(SMC_0402R_C_H016)' 
PRP PARENT_PART_TYPE 'RESISTOR' 
PRP PARENT_PPT 'RESISTOR' 
PRP PARENT_PPT_PART 'RESISTOR-G155-13300-01,330OHM,1%' 
PRP PART_NAME 'RESISTOR' 
TOP 0 5.79 4.261 90.0 N 171 1 1
TOP 1 5.79 4.219 90.0 N 1 222 2
#
# CMP 331
CMP 56 0.721 0.838 90.0 N R45 ??? ;0=1,1=0.016000
PRP SIGNAL_MODEL 'DEFAULT_RESISTOR_33OHM_2_1' 
PRP REUSE_ID '15' 
PRP ALT_SYMBOLS '(SMC_0402R_C_H016)' 
PRP PARENT_PART_TYPE 'RESISTOR' 
PRP PARENT_PPT 'RESISTOR' 
PRP PARENT_PPT_PART 'RESISTOR-G155-133R0-01,33OHM,1%' 
PRP PART_NAME 'RESISTOR' 
TOP 0 0.721 0.859 90.0 N 223 6 1
TOP 1 0.721 0.817 90.0 N 485 1 2
#
# CMP 332
CMP 56 5.51 2.345 90.0 N R244 ??? ;0=1,1=0.016000
PRP SIGNAL_MODEL 'RESISTOR-G155-100R0-J0_0OHM_-' 
PRP ALT_SYMBOLS '(SMC_0402R_C_H016,C0402-0P8MM-45DG)' 
PRP PARENT_PART_TYPE 'RESISTOR' 
PRP PARENT_PPT 'RESISTOR' 
PRP PARENT_PPT_PART 'RESISTOR-G155-100R0-J0,0OHM,-' 
PRP PART_NAME 'RESISTOR' 
TOP 0 5.51 2.366 90.0 N 346 2 1
TOP 1 5.51 2.324 90.0 N 54 3 2
#
# CMP 333
CMP 56 5.555 2.345 270.0 N R246 ??? ;0=1,1=0.016000
PRP ALT_SYMBOLS '(SMC_0402R_C_H016)' 
PRP PARENT_PART_TYPE 'RESISTOR' 
PRP PARENT_PPT 'RESISTOR' 
PRP PARENT_PPT_PART 'RESISTOR-A155-05101-DL,5.1KOHM,1%' 
PRP PART_NAME 'RESISTOR' 
TOP 0 5.555 2.324 270.0 N 54 4 1
TOP 1 5.555 2.366 270.0 N 2 611 2
#
# CMP 334
CMP 56 5.6 2.345 270.0 N R249 ??? ;0=1,1=0.016000
PRP SIGNAL_MODEL 'RESISTOR-G155-100R0-J0_0OHM_-' 
PRP ALT_SYMBOLS '(SMC_0402R_C_H016)' 
PRP PARENT_PART_TYPE 'RESISTOR' 
PRP PARENT_PPT 'RESISTOR' 
PRP PARENT_PPT_PART 'RESISTOR-G155-14701-01,4.7KOHM,1%' 
PRP PART_NAME 'RESISTOR' 
TOP 0 5.6 2.324 270.0 N 62 2 1
TOP 1 5.6 2.366 270.0 N 61 0 2
#
# CMP 335
CMP 56 5.41 2.275 180.0 N R243 ??? ;0=1,1=0.016000
PRP SIGNAL_MODEL 'RESISTOR-G155-100R0-J0_0OHM_-' 
PRP ALT_SYMBOLS '(SMC_0402R_C_H016)' 
PRP PARENT_PART_TYPE 'RESISTOR' 
PRP PARENT_PPT 'RESISTOR' 
PRP PARENT_PPT_PART 'RESISTOR-G155-14701-01,4.7KOHM,1%' 
PRP PART_NAME 'RESISTOR' 
TOP 0 5.389 2.275 180.0 N 19 31 1
TOP 1 5.431 2.275 180.0 N 56 3 2
#
# CMP 336
CMP 56 6.4 1.08 180.0 N R417 ??? ;0=1,1=0.016000
PRP REUSE_ID '8' 
PRP ALT_SYMBOLS '(SMC_0402R_C_H016)' 
PRP PARENT_PART_TYPE 'RESISTOR' 
PRP PARENT_PPT 'RESISTOR' 
PRP PARENT_PPT_PART 'RESISTOR-G155-11001-01,1KOHM,1%' 
PRP PART_NAME 'RESISTOR' 
TOP 0 6.379 1.08 180.0 N 471 2 1
TOP 1 6.421 1.08 180.0 N 2 612 2
#
# CMP 337
CMP 56 6.4 1.02 180.0 N R415 ??? ;0=1,1=0.016000
PRP REUSE_ID '7' 
PRP ALT_SYMBOLS '(SMC_0402R_C_H016)' 
PRP PARENT_PART_TYPE 'RESISTOR' 
PRP PARENT_PPT 'RESISTOR' 
PRP PARENT_PPT_PART 'RESISTOR-G155-11001-01,1KOHM,1%' 
PRP PART_NAME 'RESISTOR' 
TOP 0 6.379 1.02 180.0 N 469 2 1
TOP 1 6.421 1.02 180.0 N 2 613 2
#
# CMP 338
CMP 56 6.4 0.965 180.0 N R411 ??? ;0=1,1=0.016000
PRP REUSE_ID '5' 
PRP ALT_SYMBOLS '(SMC_0402R_C_H016)' 
PRP PARENT_PART_TYPE 'RESISTOR' 
PRP PARENT_PPT 'RESISTOR' 
PRP PARENT_PPT_PART 'RESISTOR-G155-11001-01,1KOHM,1%' 
PRP PART_NAME 'RESISTOR' 
TOP 0 6.379 0.965 180.0 N 467 2 1
TOP 1 6.421 0.965 180.0 N 2 614 2
#
# CMP 339
CMP 56 6.01902 1.92965 90.0 N R300 ??? ;0=1,1=0.016000
PRP SIGNAL_MODEL 'RESISTOR-G155-100R0-J0_0OHM_-' 
PRP ALT_SYMBOLS '(SMC_0402R_C_H016)' 
PRP PARENT_PART_TYPE 'RESISTOR' 
PRP PARENT_PPT 'RESISTOR' 
PRP PARENT_PPT_PART 'RESISTOR-G155-14701-01,4.7KOHM,1%' 
PRP PART_NAME 'RESISTOR' 
TOP 0 6.01902 1.95065 90.0 N 1 223 1
TOP 1 6.01902 1.90865 90.0 N 377 2 2
#
# CMP 340
CMP 56 6.06902 1.92965 90.0 N R65 ??? ;0=1,1=0.016000
PRP SIGNAL_MODEL 'RESISTOR-G155-100R0-J0_0OHM_-' 
PRP ALT_SYMBOLS '(SMC_0402R_C_H016)' 
PRP PARENT_PART_TYPE 'RESISTOR' 
PRP PARENT_PPT 'RESISTOR' 
PRP PARENT_PPT_PART 'RESISTOR-G155-14701-01,4.7KOHM,1%' 
PRP PART_NAME 'RESISTOR' 
TOP 0 6.06902 1.95065 90.0 N 1 224 1
TOP 1 6.06902 1.90865 90.0 N 521 2 2
#
# CMP 341
CMP 56 5.96902 1.92965 90.0 N R69 ??? ;0=1,1=0.016000
PRP ALT_SYMBOLS '(SMC_0402R_C_H016)' 
PRP PARENT_PART_TYPE 'RESISTOR' 
PRP PARENT_PPT 'RESISTOR' 
PRP PARENT_PPT_PART 'RESISTOR-G155-11001-01,1KOHM,1%' 
PRP PART_NAME 'RESISTOR' 
TOP 0 5.96902 1.95065 90.0 N 524 2 1
TOP 1 5.96902 1.90865 90.0 N 2 615 2
#
# CMP 342
CMP 56 5.91902 1.92965 270.0 N R64 ??? ;0=1,1=0.016000
PRP SIGNAL_MODEL 'RESISTOR-G155-100R0-J0_0OHM_-' 
PRP ALT_SYMBOLS '(SMC_0402R_C_H016)' 
PRP PARENT_PART_TYPE 'RESISTOR' 
PRP PARENT_PPT 'RESISTOR' 
PRP PARENT_PPT_PART 'RESISTOR-G155-14701-01,4.7KOHM,1%' 
PRP PART_NAME 'RESISTOR' 
TOP 0 5.91902 1.90865 270.0 N 1 225 1
TOP 1 5.91902 1.95065 270.0 N 520 2 2
#
# CMP 343
CMP 56 4.037 2.531 90.0 N R293 ??? ;0=1,1=0.016000
PRP SIGNAL_MODEL 'RESISTOR-G155-100R0-J0_0OHM_-' 
PRP ALT_SYMBOLS '(SMC_0402R_C_H016)' 
PRP PARENT_PART_TYPE 'RESISTOR' 
PRP PARENT_PPT 'RESISTOR' 
PRP PARENT_PPT_PART 'RESISTOR-G155-14701-01,4.7KOHM,1%' 
PRP PART_NAME 'RESISTOR' 
TOP 0 4.037 2.552 90.0 N 2 616 1
TOP 1 4.037 2.51 90.0 N 373 3 2
#
# CMP 344
CMP 56 1.28 3.115 90.0 N R131 ??? ;0=1,1=0.016000
PRP SIGNAL_MODEL 'RESISTOR-G155-11000-01_100OHM_A' 
PRP ALT_SYMBOLS '(SMC_0402R_C_H016)' 
PRP PARENT_PART_TYPE 'RESISTOR' 
PRP PARENT_PPT 'RESISTOR' 
PRP PARENT_PPT_PART 'RESISTOR-G155-11000-01,100OHM,1%' 
PRP PART_NAME 'RESISTOR' 
TOP 0 1.28 3.136 90.0 N 277 1 1
TOP 1 1.28 3.094 90.0 N 197 2 2
#
# CMP 345
CMP 56 1.36 3.235 180.0 N R349 ??? ;0=1,1=0.016000
PRP ALT_SYMBOLS '(SMC_0402R_C_H016)' 
PRP PARENT_PART_TYPE 'RESISTOR' 
PRP PARENT_PPT 'RESISTOR' 
PRP PARENT_PPT_PART 'RESISTOR-G155-11003-01,100KOHM,1%' 
PRP PART_NAME 'RESISTOR' 
TOP 0 1.339 3.235 180.0 N 278 1 1
TOP 1 1.381 3.235 180.0 N 88 26 2
#
# CMP 346
CMP 56 1.36 3.28 180.0 N R132 ??? ;0=1,1=0.016000
PRP SIGNAL_MODEL 'RESISTOR-G155-11000-01_100OHM_A' 
PRP ALT_SYMBOLS '(SMC_0402R_C_H016)' 
PRP PARENT_PART_TYPE 'RESISTOR' 
PRP PARENT_PPT 'RESISTOR' 
PRP PARENT_PPT_PART 'RESISTOR-G155-11000-01,100OHM,1%' 
PRP PART_NAME 'RESISTOR' 
TOP 0 1.339 3.28 180.0 N 278 2 1
TOP 1 1.381 3.28 180.0 N 200 2 2
#
# CMP 347
CMP 56 3.335 2.532 90.0 N R80 ??? ;0=1,1=0.016000
PRP SIGNAL_MODEL 'DEFAULT_RESISTOR_33OHM_2_1' 
PRP ALT_SYMBOLS '(SMC_0402R_C_H016)' 
PRP PARENT_PART_TYPE 'RESISTOR' 
PRP PARENT_PPT 'RESISTOR' 
PRP PARENT_PPT_PART 'RESISTOR-G155-133R0-01,33OHM,1%' 
PRP PART_NAME 'RESISTOR' 
TOP 0 3.335 2.553 90.0 N 535 1 1
TOP 1 3.335 2.511 90.0 N 379 3 2
#
# CMP 348
CMP 57 2.105 3.43 90.0 N R454 ??? ;0=1,1=0.025000
PRP SIGNAL_MODEL 'RESISTOR-G155-02101-01_2.1KOHMA' 
PRP ALT_SYMBOLS '(SMC_0402R_C)' 
PRP PARENT_PART_TYPE 'RESISTOR' 
PRP PARENT_PPT 'RESISTOR' 
PRP PARENT_PPT_PART 'RESISTOR-G155-02101-01,2.1KOHM,1%' 
PRP PART_NAME 'RESISTOR' 
TOP 0 2.105 3.451 90.0 N 486 2 1
TOP 1 2.105 3.409 90.0 N 479 2 2
#
# CMP 349
CMP 57 1.175 3.585 270.0 N R463 ??? ;0=1,1=0.025000
PRP ALT_SYMBOLS '(SMC_0402R_C)' 
PRP PARENT_PART_TYPE 'RESISTOR' 
PRP PARENT_PPT 'RESISTOR' 
PRP PARENT_PPT_PART 'RESISTOR-G155-01202-01,12KOHM,1%' 
PRP PART_NAME 'RESISTOR' 
TOP 0 1.175 3.564 270.0 N 494 1 1
TOP 1 1.175 3.606 270.0 N 2 617 2
#
# CMP 350
CMP 57 5.741 3.907 180.0 N R16 ??? ;0=1,1=0.025000
PRP REUSE_ID '14' 
PRP ALT_SYMBOLS '(SMC_0402R_C)' 
PRP PARENT_PART_TYPE 'RESISTOR' 
PRP PARENT_PPT 'RESISTOR' 
PRP PARENT_PPT_PART 'RESISTOR-G155-03921-01,3.92KOHM,1%' 
PRP PART_NAME 'RESISTOR' 
TOP 0 5.72 3.907 180.0 N 293 3 1
TOP 1 5.762 3.907 180.0 N 2 618 2
#
# CMP 351
CMP 57 5.425 0.69 180.0 N R233 ??? ;0=1,1=0.025000
PRP REUSE_ID '16' 
PRP ALT_SYMBOLS '(SMC_0402R_C)' 
PRP PARENT_PART_TYPE 'RESISTOR' 
PRP PARENT_PPT 'RESISTOR' 
PRP PARENT_PPT_PART 'RESISTOR-G155-02101-01,2.1KOHM,1%' 
PRP PART_NAME 'RESISTOR' 
TOP 0 5.404 0.69 180.0 N 2 619 1
TOP 1 5.446 0.69 180.0 N 339 2 2
#
# CMP 352
CMP 57 5.557 0.726 90.0 N R232 ??? ;0=1,1=0.025000
PRP REUSE_ID '15' 
PRP ALT_SYMBOLS '(SMC_0402R_C)' 
PRP PARENT_PART_TYPE 'RESISTOR' 
PRP PARENT_PPT 'RESISTOR' 
PRP PARENT_PPT_PART 'RESISTOR-G155-02101-01,2.1KOHM,1%' 
PRP PART_NAME 'RESISTOR' 
TOP 0 5.557 0.747 90.0 N 2 620 1
TOP 1 5.557 0.705 90.0 N 339 3 2
#
# CMP 353
CMP 57 3.814 3.092 180.0 N R177 ??? ;0=1,1=0.025000
PRP REUSE_ID '16' 
PRP ALT_SYMBOLS '(SMC_0402R_C)' 
PRP PARENT_PART_TYPE 'RESISTOR' 
PRP PARENT_PPT 'RESISTOR' 
PRP PARENT_PPT_PART 'RESISTOR-G152-00055-01,1.13KOHM,1%' 
PRP PART_NAME 'RESISTOR' 
TOP 0 3.793 3.092 180.0 N 21 5 1
TOP 1 3.835 3.092 180.0 N 20 4 2
#
# CMP 354
CMP 59 5.645 2.345 90.0 N C263 ??? ;0=1,1=0.012990
PRP ALT_SYMBOLS '(SMC_0201R_C)' 
PRP PARENT_PART_TYPE 'CAPACITOR' 
PRP PARENT_PPT 'CAPACITOR' 
PRP PARENT_PPT_PART 'CAPACITOR-G104-0B472-EK,4700PF,10%' 
PRP PART_NAME 'CAPACITOR' 
TOP 0 5.645 2.35543 90.0 N 61 1 1
TOP 1 5.645 2.33457 90.0 N 58 7 2
#
# CMP 355
CMP 60 3.765 1.06 180.0 N C164 ??? ;0=1,1=0.057000
PRP ALT_SYMBOLS '(SMC_0805R_H057)' 
PRP PARENT_PART_TYPE 'CAPACITOR' 
PRP PARENT_PPT 'CAPACITOR' 
PRP PARENT_PPT_PART 'CAPACITOR-G107-0F226-CM,22UF,20%' 
PRP PART_NAME 'CAPACITOR' 
TOP 0 3.732 1.06 180.0 N 9 39 1
TOP 1 3.798 1.06 180.0 N 2 621 2
#
# CMP 356
CMP 60 3.46 1.345 90.0 N C143 ??? ;0=1,1=0.057000
PRP ALT_SYMBOLS '(SMC_0805R_H057)' 
PRP PARENT_PART_TYPE 'CAPACITOR' 
PRP PARENT_PPT 'CAPACITOR' 
PRP PARENT_PPT_PART 'CAPACITOR-G107-0F476-AM,47UF,20%' 
PRP PART_NAME 'CAPACITOR' 
TOP 0 3.46 1.378 90.0 N 14 7 1
TOP 1 3.46 1.312 90.0 N 2 622 2
#
# CMP 357
CMP 60 3.785 1.335 90.0 N C125 ??? ;0=1,1=0.057000
PRP ALT_SYMBOLS '(SMC_0805R_H057)' 
PRP PARENT_PART_TYPE 'CAPACITOR' 
PRP PARENT_PPT 'CAPACITOR' 
PRP PARENT_PPT_PART 'CAPACITOR-G107-0F476-AM,47UF,20%' 
PRP PART_NAME 'CAPACITOR' 
TOP 0 3.785 1.368 90.0 N 6 13 1
TOP 1 3.785 1.302 90.0 N 2 623 2
#
# CMP 358
CMP 60 5.494 3.206 0.0 N C303 ??? ;0=1,1=0.057000
PRP ALT_SYMBOLS '(SMC_0805R_H057)' 
PRP PARENT_PART_TYPE 'CAPACITOR' 
PRP PARENT_PPT 'CAPACITOR' 
PRP PARENT_PPT_PART 'CAPACITOR-G107-0F106-EM,10UF,20%' 
PRP PART_NAME 'CAPACITOR' 
TOP 0 5.527 3.206 0.0 N 30 15 1
TOP 1 5.461 3.206 0.0 N 2 624 2
#
# CMP 359
CMP 60 5.498 3.288 0.0 N C299 ??? ;0=1,1=0.057000
PRP ALT_SYMBOLS '(SMC_0805R_H057)' 
PRP PARENT_PART_TYPE 'CAPACITOR' 
PRP PARENT_PPT 'CAPACITOR' 
PRP PARENT_PPT_PART 'CAPACITOR-G107-0F106-EM,10UF,20%' 
PRP PART_NAME 'CAPACITOR' 
TOP 0 5.531 3.288 0.0 N 30 16 1
TOP 1 5.465 3.288 0.0 N 2 625 2
#
# CMP 360
CMP 60 5.498 3.364 0.0 N C297 ??? ;0=1,1=0.057000
PRP ALT_SYMBOLS '(SMC_0805R_H057)' 
PRP PARENT_PART_TYPE 'CAPACITOR' 
PRP PARENT_PPT 'CAPACITOR' 
PRP PARENT_PPT_PART 'CAPACITOR-G107-0F106-EM,10UF,20%' 
PRP PART_NAME 'CAPACITOR' 
TOP 0 5.531 3.364 0.0 N 30 17 1
TOP 1 5.465 3.364 0.0 N 2 626 2
#
# CMP 361
CMP 60 5.498 3.441 0.0 N C301 ??? ;0=1,1=0.057000
PRP ALT_SYMBOLS '(SMC_0805R_H057)' 
PRP PARENT_PART_TYPE 'CAPACITOR' 
PRP PARENT_PPT 'CAPACITOR' 
PRP PARENT_PPT_PART 'CAPACITOR-G107-0F106-EM,10UF,20%' 
PRP PART_NAME 'CAPACITOR' 
TOP 0 5.531 3.441 0.0 N 30 18 1
TOP 1 5.465 3.441 0.0 N 2 627 2
#
# CMP 362
CMP 60 5.4 1.82 270.0 N C179 ??? ;0=1,1=0.057000
PRP REUSE_ID '24' 
PRP ALT_SYMBOLS '(SMC_0805R_H057)' 
PRP PARENT_PART_TYPE 'CAPACITOR' 
PRP PARENT_PPT 'CAPACITOR' 
PRP PARENT_PPT_PART 'CAPACITOR-G107-0F476-AM,47UF,20%' 
PRP PART_NAME 'CAPACITOR' 
TOP 0 5.4 1.787 270.0 N 15 11 1
TOP 1 5.4 1.853 270.0 N 2 628 2
#
# CMP 363
CMP 60 3.645 2.23 180.0 N C158 ??? ;0=1,1=0.057000
PRP ALT_SYMBOLS '(SMC_0805R_H057)' 
PRP PARENT_PART_TYPE 'CAPACITOR' 
PRP PARENT_PPT 'CAPACITOR' 
PRP PARENT_PPT_PART 'CAPACITOR-G107-0F226-CM,22UF,20%' 
PRP PART_NAME 'CAPACITOR' 
TOP 0 3.612 2.23 180.0 N 16 9 1
TOP 1 3.678 2.23 180.0 N 2 629 2
#
# CMP 364
CMP 60 3.035 1.945 180.0 N C64 ??? ;0=1,1=0.057000
PRP ALT_SYMBOLS '(SMC_0805R_H057)' 
PRP PARENT_PART_TYPE 'CAPACITOR' 
PRP PARENT_PPT 'CAPACITOR' 
PRP PARENT_PPT_PART 'CAPACITOR-G107-0F106-EM,10UF,20%' 
PRP PART_NAME 'CAPACITOR' 
TOP 0 3.002 1.945 180.0 N 122 3 1
TOP 1 3.068 1.945 180.0 N 2 630 2
#
# CMP 365
CMP 60 4.966 1.263 0.0 N C168 ??? ;0=1,1=0.057000
PRP ALT_SYMBOLS '(SMC_0805R_H057)' 
PRP PARENT_PART_TYPE 'CAPACITOR' 
PRP PARENT_PPT 'CAPACITOR' 
PRP PARENT_PPT_PART 'CAPACITOR-G107-0F226-CM,22UF,20%' 
PRP PART_NAME 'CAPACITOR' 
TOP 0 4.999 1.263 0.0 N 9 40 1
TOP 1 4.933 1.263 0.0 N 2 631 2
#
# CMP 366
CMP 60 3.035 2.88 270.0 N C282 ??? ;0=1,1=0.057000
PRP ALT_SYMBOLS '(SMC_0805R_H057)' 
PRP PARENT_PART_TYPE 'CAPACITOR' 
PRP PARENT_PPT 'CAPACITOR' 
PRP PARENT_PPT_PART 'CAPACITOR-G107-0F106-EM,10UF,20%' 
PRP PART_NAME 'CAPACITOR' 
TOP 0 3.035 2.847 270.0 N 76 6 1
TOP 1 3.035 2.913 270.0 N 2 632 2
#
# CMP 367
CMP 60 3.11 2.88 270.0 N C283 ??? ;0=1,1=0.057000
PRP ALT_SYMBOLS '(SMC_0805R_H057)' 
PRP PARENT_PART_TYPE 'CAPACITOR' 
PRP PARENT_PPT 'CAPACITOR' 
PRP PARENT_PPT_PART 'CAPACITOR-G107-0F106-EM,10UF,20%' 
PRP PART_NAME 'CAPACITOR' 
TOP 0 3.11 2.847 270.0 N 76 7 1
TOP 1 3.11 2.913 270.0 N 2 633 2
#
# CMP 368
CMP 60 2.96 2.88 270.0 N C58 ??? ;0=1,1=0.057000
PRP ALT_SYMBOLS '(SMC_0805R_H057)' 
PRP PARENT_PART_TYPE 'CAPACITOR' 
PRP PARENT_PPT 'CAPACITOR' 
PRP PARENT_PPT_PART 'CAPACITOR-G107-0F106-EM,10UF,20%' 
PRP PART_NAME 'CAPACITOR' 
TOP 0 2.96 2.847 270.0 N 76 8 1
TOP 1 2.96 2.913 270.0 N 2 634 2
#
# CMP 369
CMP 60 4.167 2.855 0.0 N C243 ??? ;0=1,1=0.057000
PRP ALT_SYMBOLS '(SMC_0805R_H057)' 
PRP PARENT_PART_TYPE 'CAPACITOR' 
PRP PARENT_PPT 'CAPACITOR' 
PRP PARENT_PPT_PART 'CAPACITOR-G107-0F226-CM,22UF,20%' 
PRP PART_NAME 'CAPACITOR' 
TOP 0 4.2 2.855 0.0 N 1 226 1
TOP 1 4.134 2.855 0.0 N 2 635 2
#
# CMP 370
CMP 60 4.167 2.936 0.0 N C241 ??? ;0=1,1=0.057000
PRP ALT_SYMBOLS '(SMC_0805R_H057)' 
PRP PARENT_PART_TYPE 'CAPACITOR' 
PRP PARENT_PPT 'CAPACITOR' 
PRP PARENT_PPT_PART 'CAPACITOR-G107-0F226-CM,22UF,20%' 
PRP PART_NAME 'CAPACITOR' 
TOP 0 4.2 2.936 0.0 N 1 227 1
TOP 1 4.134 2.936 0.0 N 2 636 2
#
# CMP 371
CMP 60 3.662 2.985 90.0 N C180 ??? ;0=1,1=0.057000
PRP REUSE_ID '12' 
PRP ALT_SYMBOLS '(SMC_0805R_H057)' 
PRP PARENT_PART_TYPE 'CAPACITOR' 
PRP PARENT_PPT 'CAPACITOR' 
PRP PARENT_PPT_PART 'CAPACITOR-G107-0F226-CM,22UF,20%' 
PRP PART_NAME 'CAPACITOR' 
TOP 0 3.662 3.018 90.0 N 19 32 1
TOP 1 3.662 2.952 90.0 N 2 637 2
#
# CMP 372
CMP 60 5.047 2.454 180.0 N C181 ??? ;0=1,1=0.057000
PRP ALT_SYMBOLS '(SMC_0805R_H057)' 
PRP PARENT_PART_TYPE 'CAPACITOR' 
PRP PARENT_PPT 'CAPACITOR' 
PRP PARENT_PPT_PART 'CAPACITOR-G107-0F226-CM,22UF,20%' 
PRP PART_NAME 'CAPACITOR' 
TOP 0 5.014 2.454 180.0 N 19 33 1
TOP 1 5.08 2.454 180.0 N 2 638 2
#
# CMP 373
CMP 61 3.77 0.79 90.0 N C245 ??? ;0=1,1=0.022000
PRP SIGNAL_MODEL 'DEFAULT_CAPACITOR_100000pF_1_2' 
PRP ALT_SYMBOLS '(SMC_0402R_C_H022,C0402-1MM-TRIANGLE-S0,C0402-P8MM-S0)' 
PRP PARENT_PART_TYPE 'CAPACITOR' 
PRP PARENT_PPT 'CAPACITOR' 
PRP PARENT_PPT_PART 'CAPACITOR-G105-0B104-EK,0.1UF,10%' 
PRP PART_NAME 'CAPACITOR' 
TOP 0 3.77 0.811 90.0 N 19 34 1
TOP 1 3.77 0.769 90.0 N 2 639 2
#
# CMP 374
CMP 61 3.52 1.355 90.0 N C136 ??? ;0=1,1=0.022000
PRP SIGNAL_MODEL 'DEFAULT_CAPACITOR_100000pF_1_2' 
PRP ALT_SYMBOLS '(SMC_0402R_C_H022,C0402_BGA,C0402-0P8MM-45DG,C0402-1MM-TRIANGLE-S0)' 
PRP PARENT_PART_TYPE 'CAPACITOR' 
PRP PARENT_PPT 'CAPACITOR' 
PRP PARENT_PPT_PART 'CAPACITOR-G105-0B104-CK,0.1UF,10%' 
PRP PART_NAME 'CAPACITOR' 
TOP 0 3.52 1.376 90.0 N 14 8 1
TOP 1 3.52 1.334 90.0 N 2 640 2
#
# CMP 375
CMP 61 3.02303 0.605 270.0 N C36 ??? ;0=1,1=0.022000
PRP HARD_LOCATION 'YES' 
PRP SIGNAL_MODEL 'DEFAULT_CAPACITOR_100000pF_1_2' 
PRP ALT_SYMBOLS '(SMC_0402R_C_H022,C0402_BGA,C0402-0P8MM-45DG,C0402-1MM-TRIANGLE-S0)' 
PRP PARENT_PART_TYPE 'CAPACITOR' 
PRP PARENT_PPT 'CAPACITOR' 
PRP PARENT_PPT_PART 'CAPACITOR-G105-0B104-CK,0.1UF,10%' 
PRP PART_NAME 'CAPACITOR' 
TOP 0 3.02303 0.584 270.0 N 100 1 1
TOP 1 3.02303 0.626 270.0 N 101 1 2
#
# CMP 376
CMP 61 2.97303 0.605 270.0 N C35 ??? ;0=1,1=0.022000
PRP HARD_LOCATION 'YES' 
PRP SIGNAL_MODEL 'DEFAULT_CAPACITOR_100000pF_1_2' 
PRP ALT_SYMBOLS '(SMC_0402R_C_H022,C0402_BGA,C0402-0P8MM-45DG,C0402-1MM-TRIANGLE-S0)' 
PRP PARENT_PART_TYPE 'CAPACITOR' 
PRP PARENT_PPT 'CAPACITOR' 
PRP PARENT_PPT_PART 'CAPACITOR-G105-0B104-CK,0.1UF,10%' 
PRP PART_NAME 'CAPACITOR' 
TOP 0 2.97303 0.584 270.0 N 98 1 1
TOP 1 2.97303 0.626 270.0 N 99 1 2
#
# CMP 377
CMP 61 2.85055 0.605 270.0 N C34 ??? ;0=1,1=0.022000
PRP HARD_LOCATION 'YES' 
PRP SIGNAL_MODEL 'DEFAULT_CAPACITOR_100000pF_1_2' 
PRP ALT_SYMBOLS '(SMC_0402R_C_H022,C0402_BGA,C0402-0P8MM-45DG,C0402-1MM-TRIANGLE-S0)' 
PRP PARENT_PART_TYPE 'CAPACITOR' 
PRP PARENT_PPT 'CAPACITOR' 
PRP PARENT_PPT_PART 'CAPACITOR-G105-0B104-CK,0.1UF,10%' 
PRP PART_NAME 'CAPACITOR' 
TOP 0 2.85055 0.584 270.0 N 96 1 1
TOP 1 2.85055 0.626 270.0 N 97 1 2
#
# CMP 378
CMP 61 2.80055 0.605 270.0 N C28 ??? ;0=1,1=0.022000
PRP HARD_LOCATION 'YES' 
PRP SIGNAL_MODEL 'DEFAULT_CAPACITOR_100000pF_1_2' 
PRP ALT_SYMBOLS '(SMC_0402R_C_H022,C0402_BGA,C0402-0P8MM-45DG,C0402-1MM-TRIANGLE-S0)' 
PRP PARENT_PART_TYPE 'CAPACITOR' 
PRP PARENT_PPT 'CAPACITOR' 
PRP PARENT_PPT_PART 'CAPACITOR-G105-0B104-CK,0.1UF,10%' 
PRP PART_NAME 'CAPACITOR' 
TOP 0 2.80055 0.584 270.0 N 73 1 1
TOP 1 2.80055 0.626 270.0 N 74 1 2
#
# CMP 379
CMP 61 2.70807 0.605 270.0 N C27 ??? ;0=1,1=0.022000
PRP HARD_LOCATION 'YES' 
PRP SIGNAL_MODEL 'DEFAULT_CAPACITOR_100000pF_1_2' 
PRP ALT_SYMBOLS '(SMC_0402R_C_H022,C0402_BGA,C0402-0P8MM-45DG,C0402-1MM-TRIANGLE-S0)' 
PRP PARENT_PART_TYPE 'CAPACITOR' 
PRP PARENT_PPT 'CAPACITOR' 
PRP PARENT_PPT_PART 'CAPACITOR-G105-0B104-CK,0.1UF,10%' 
PRP PART_NAME 'CAPACITOR' 
TOP 0 2.70807 0.584 270.0 N 68 1 1
TOP 1 2.70807 0.626 270.0 N 69 1 2
#
# CMP 380
CMP 61 2.65807 0.605 270.0 N C26 ??? ;0=1,1=0.022000
PRP HARD_LOCATION 'YES' 
PRP SIGNAL_MODEL 'DEFAULT_CAPACITOR_100000pF_1_2' 
PRP ALT_SYMBOLS '(SMC_0402R_C_H022,C0402_BGA,C0402-0P8MM-45DG,C0402-1MM-TRIANGLE-S0)' 
PRP PARENT_PART_TYPE 'CAPACITOR' 
PRP PARENT_PPT 'CAPACITOR' 
PRP PARENT_PPT_PART 'CAPACITOR-G105-0B104-CK,0.1UF,10%' 
PRP PART_NAME 'CAPACITOR' 
TOP 0 2.65807 0.584 270.0 N 59 1 1
TOP 1 2.65807 0.626 270.0 N 60 1 2
#
# CMP 381
CMP 61 2.51122 0.605 270.0 N C25 ??? ;0=1,1=0.022000
PRP HARD_LOCATION 'YES' 
PRP SIGNAL_MODEL 'DEFAULT_CAPACITOR_100000pF_1_2' 
PRP ALT_SYMBOLS '(SMC_0402R_C_H022,C0402_BGA,C0402-0P8MM-45DG,C0402-1MM-TRIANGLE-S0)' 
PRP PARENT_PART_TYPE 'CAPACITOR' 
PRP PARENT_PPT 'CAPACITOR' 
PRP PARENT_PPT_PART 'CAPACITOR-G105-0B104-CK,0.1UF,10%' 
PRP PART_NAME 'CAPACITOR' 
TOP 0 2.51122 0.584 270.0 N 43 1 1
TOP 1 2.51122 0.626 270.0 N 44 1 2
#
# CMP 382
CMP 61 2.46122 0.605 270.0 N C24 ??? ;0=1,1=0.022000
PRP SIGNAL_MODEL 'DEFAULT_CAPACITOR_100000pF_1_2' 
PRP ALT_SYMBOLS '(SMC_0402R_C_H022,C0402_BGA,C0402-0P8MM-45DG,C0402-1MM-TRIANGLE-S0)' 
PRP PARENT_PART_TYPE 'CAPACITOR' 
PRP PARENT_PPT 'CAPACITOR' 
PRP PARENT_PPT_PART 'CAPACITOR-G105-0B104-CK,0.1UF,10%' 
PRP PART_NAME 'CAPACITOR' 
TOP 0 2.46122 0.584 270.0 N 39 1 1
TOP 1 2.46122 0.626 270.0 N 40 1 2
#
# CMP 383
CMP 61 2.3431 0.6049 270.0 N C19 ??? ;0=1,1=0.022000
PRP SIGNAL_MODEL 'DEFAULT_CAPACITOR_100000pF_1_2' 
PRP ALT_SYMBOLS '(SMC_0402R_C_H022,C0402_BGA,C0402-0P8MM-45DG,C0402-1MM-TRIANGLE-S0)' 
PRP PARENT_PART_TYPE 'CAPACITOR' 
PRP PARENT_PPT 'CAPACITOR' 
PRP PARENT_PPT_PART 'CAPACITOR-G105-0B104-CK,0.1UF,10%' 
PRP PART_NAME 'CAPACITOR' 
TOP 0 2.3431 0.5839 270.0 N 24 1 1
TOP 1 2.3431 0.6259 270.0 N 25 2 2
#
# CMP 384
CMP 61 2.39311 0.605 270.0 N C23 ??? ;0=1,1=0.022000
PRP SIGNAL_MODEL 'DEFAULT_CAPACITOR_100000pF_1_2' 
PRP ALT_SYMBOLS '(SMC_0402R_C_H022,C0402_BGA,C0402-0P8MM-45DG,C0402-1MM-TRIANGLE-S0)' 
PRP PARENT_PART_TYPE 'CAPACITOR' 
PRP PARENT_PPT 'CAPACITOR' 
PRP PARENT_PPT_PART 'CAPACITOR-G105-0B104-CK,0.1UF,10%' 
PRP PART_NAME 'CAPACITOR' 
TOP 0 2.39311 0.584 270.0 N 34 1 1
TOP 1 2.39311 0.626 270.0 N 35 2 2
#
# CMP 385
CMP 61 2.2 0.635 270.0 N C290 ??? ;0=1,1=0.022000
PRP SIGNAL_MODEL 'DEFAULT_CAPACITOR_100000pF_1_2' 
PRP ALT_SYMBOLS '(SMC_0402R_C_H022,C0402-1MM-TRIANGLE-S0,C0402-P8MM-S0)' 
PRP PARENT_PART_TYPE 'CAPACITOR' 
PRP PARENT_PPT 'CAPACITOR' 
PRP PARENT_PPT_PART 'CAPACITOR-G105-0B104-EK,0.1UF,10%' 
PRP PART_NAME 'CAPACITOR' 
TOP 0 2.2 0.614 270.0 N 81 5 1
TOP 1 2.2 0.656 270.0 N 2 641 2
#
# CMP 386
CMP 61 2.155 0.635 270.0 N C289 ??? ;0=1,1=0.022000
PRP ALT_SYMBOLS '(SMC_0402R_C_H022,C0402_BGA,C0402-0P8MM-45DG,C0402-P8MM-S0,C0402-1MM-TRIANGLE-S0)' 
PRP PARENT_PART_TYPE 'CAPACITOR' 
PRP PARENT_PPT 'CAPACITOR' 
PRP PARENT_PPT_PART 'CAPACITOR-G105-0C106-BM,10UF,20%' 
PRP PART_NAME 'CAPACITOR' 
TOP 0 2.155 0.614 270.0 N 81 6 1
TOP 1 2.155 0.656 270.0 N 2 642 2
#
# CMP 387
CMP 61 3.505 1.81 90.0 N C67 ??? ;0=1,1=0.022000
PRP SIGNAL_MODEL 'DEFAULT_CAPACITOR_100000pF_1_2' 
PRP ALT_SYMBOLS '(SMC_0402R_C_H022,C0402_BGA,C0402-0P8MM-45DG,C0402-1MM-TRIANGLE-S0)' 
PRP PARENT_PART_TYPE 'CAPACITOR' 
PRP PARENT_PPT 'CAPACITOR' 
PRP PARENT_PPT_PART 'CAPACITOR-G105-0B104-CK,0.1UF,10%' 
PRP PART_NAME 'CAPACITOR' 
TOP 0 3.505 1.831 90.0 N 1 228 1
TOP 1 3.505 1.789 90.0 N 2 643 2
#
# CMP 388
CMP 61 3.89729 1.29361 0.0 N C116 ??? ;0=1,1=0.022000
PRP SIGNAL_MODEL 'DEFAULT_CAPACITOR_100000pF_1_2' 
PRP ALT_SYMBOLS '(SMC_0402R_C_H022,C0402_BGA,C0402-0P8MM-45DG,C0402-1MM-TRIANGLE-S0)' 
PRP PARENT_PART_TYPE 'CAPACITOR' 
PRP PARENT_PPT 'CAPACITOR' 
PRP PARENT_PPT_PART 'CAPACITOR-G105-0B104-CK,0.1UF,10%' 
PRP PART_NAME 'CAPACITOR' 
TOP 0 3.91829 1.29361 0.0 N 9 41 1
TOP 1 3.87629 1.29361 0.0 N 2 644 2
#
# CMP 389
CMP 61 3.8653 1.745 0.0 N C104 ??? ;0=1,1=0.022000
PRP SIGNAL_MODEL 'DEFAULT_CAPACITOR_100000pF_1_2' 
PRP ALT_SYMBOLS '(SMC_0402R_C_H022,C0402_BGA,C0402-0P8MM-45DG,C0402-1MM-TRIANGLE-S0)' 
PRP PARENT_PART_TYPE 'CAPACITOR' 
PRP PARENT_PPT 'CAPACITOR' 
PRP PARENT_PPT_PART 'CAPACITOR-G105-0B104-CK,0.1UF,10%' 
PRP PART_NAME 'CAPACITOR' 
TOP 0 3.8863 1.745 0.0 N 6 14 1
TOP 1 3.8443 1.745 0.0 N 2 645 2
#
# CMP 390
CMP 61 3.98 3.45 270.0 N C123 ??? ;0=1,1=0.022000
PRP SIGNAL_MODEL 'DEFAULT_CAPACITOR_100000pF_1_2' 
PRP ALT_SYMBOLS '(SMC_0402R_C_H022,C0402-1MM-TRIANGLE-S0,C0402-P8MM-S0)' 
PRP PARENT_PART_TYPE 'CAPACITOR' 
PRP PARENT_PPT 'CAPACITOR' 
PRP PARENT_PPT_PART 'CAPACITOR-G105-0B104-EK,0.1UF,10%' 
PRP PART_NAME 'CAPACITOR' 
TOP 0 3.98 3.429 270.0 N 1 229 1
TOP 1 3.98 3.471 270.0 N 2 646 2
#
# CMP 391
CMP 61 0.7 3.405 90.0 N C94 ??? ;0=1,1=0.022000
PRP SIGNAL_MODEL 'DEFAULT_CAPACITOR_100000pF_1_2' 
PRP REUSE_ID '17' 
PRP ALT_SYMBOLS '(SMC_0402R_C_H022,C0402-1MM-TRIANGLE-S0,C0402-P8MM-S0)' 
PRP PARENT_PART_TYPE 'CAPACITOR' 
PRP PARENT_PPT 'CAPACITOR' 
PRP PARENT_PPT_PART 'CAPACITOR-G105-0B104-EK,0.1UF,10%' 
PRP PART_NAME 'CAPACITOR' 
TOP 0 0.7 3.426 90.0 N 132 8 1
TOP 1 0.7 3.384 90.0 N 2 647 2
#
# CMP 392
CMP 61 1.265 3.585 270.0 N C101 ??? ;0=1,1=0.022000
PRP SIGNAL_MODEL 'DEFAULT_CAPACITOR_100000pF_1_2' 
PRP REUSE_ID '3' 
PRP ALT_SYMBOLS '(SMC_0402R_C_H022,C0402-1MM-TRIANGLE-S0,C0402-P8MM-S0)' 
PRP PARENT_PART_TYPE 'CAPACITOR' 
PRP PARENT_PPT 'CAPACITOR' 
PRP PARENT_PPT_PART 'CAPACITOR-G105-0B104-EK,0.1UF,10%' 
PRP PART_NAME 'CAPACITOR' 
TOP 0 1.265 3.564 270.0 N 5 3 1
TOP 1 1.265 3.606 270.0 N 2 648 2
#
# CMP 393
CMP 61 4.17 3.45 270.0 N C102 ??? ;0=1,1=0.022000
PRP SIGNAL_MODEL 'DEFAULT_CAPACITOR_100000pF_1_2' 
PRP REUSE_ID '10' 
PRP ALT_SYMBOLS '(SMC_0402R_C_H022,C0402-1MM-TRIANGLE-S0,C0402-P8MM-S0)' 
PRP PARENT_PART_TYPE 'CAPACITOR' 
PRP PARENT_PPT 'CAPACITOR' 
PRP PARENT_PPT_PART 'CAPACITOR-G105-0B104-EK,0.1UF,10%' 
PRP PART_NAME 'CAPACITOR' 
TOP 0 4.17 3.429 270.0 N 1 230 1
TOP 1 4.17 3.471 270.0 N 2 649 2
#
# CMP 394
CMP 61 0.22 3.075 180.0 N C39 ??? ;0=1,1=0.022000
PRP SIGNAL_MODEL 'DEFAULT_CAPACITOR_100000pF_1_2' 
PRP ALT_SYMBOLS '(SMC_0402R_C_H022,C0402-1MM-TRIANGLE-S0,C0402-P8MM-S0)' 
PRP PARENT_PART_TYPE 'CAPACITOR' 
PRP PARENT_PPT 'CAPACITOR' 
PRP PARENT_PPT_PART 'CAPACITOR-G105-0B104-EK,0.1UF,10%' 
PRP PART_NAME 'CAPACITOR' 
TOP 0 0.199 3.075 180.0 N 2 650 1
TOP 1 0.241 3.075 180.0 N 1 231 2
#
# CMP 395
CMP 61 0.656 0.615 180.0 N C82 ??? ;0=1,1=0.022000
PRP HARD_LOCATION 'YES' 
PRP SIGNAL_MODEL 'DEFAULT_CAPACITOR_100000pF_1_2' 
PRP REUSE_ID '5' 
PRP ALT_SYMBOLS '(SMC_0402R_C_H022,C0402_BGA,C0402-0P8MM-45DG,C0402-1MM-TRIANGLE-S0)' 
PRP PARENT_PART_TYPE 'CAPACITOR' 
PRP PARENT_PPT 'CAPACITOR' 
PRP PARENT_PPT_PART 'CAPACITOR-G105-0B104-CK,0.1UF,10%' 
PRP PART_NAME 'CAPACITOR' 
TOP 0 0.635 0.615 180.0 N 1 232 1
TOP 1 0.677 0.615 180.0 N 2 651 2
#
# CMP 396
CMP 61 0.86 0.812 270.0 N C1 ??? ;0=1,1=0.022000
PRP SIGNAL_MODEL 'DEFAULT_CAPACITOR_100000pF_1_2' 
PRP REUSE_ID '2' 
PRP ALT_SYMBOLS '(SMC_0402R_C_H022,C0402-1MM-TRIANGLE-S0,C0402-P8MM-S0)' 
PRP PARENT_PART_TYPE 'CAPACITOR' 
PRP PARENT_PPT 'CAPACITOR' 
PRP PARENT_PPT_PART 'CAPACITOR-G105-0B104-EK,0.1UF,10%' 
PRP PART_NAME 'CAPACITOR' 
TOP 0 0.86 0.791 270.0 N 1 233 1
TOP 1 0.86 0.833 270.0 N 2 652 2
#
# CMP 397
CMP 61 1.8 4.045 270.0 N C45 ??? ;0=1,1=0.022000
PRP REUSE_ID '8' 
PRP ALT_SYMBOLS '(SMC_0402R_C_H022,SMC_0402R_V2_H022,C0402-1MM-TRIANGLE-S0,C0402-P8MM-S0)' 
PRP PARENT_PART_TYPE 'CAPACITOR' 
PRP PARENT_PPT 'CAPACITOR' 
PRP PARENT_PPT_PART 'CAPACITOR-G105-0A102-FJ,1000PF,5%' 
PRP PART_NAME 'CAPACITOR' 
TOP 0 1.8 4.024 270.0 N 107 3 1
TOP 1 1.8 4.066 270.0 N 108 1 2
#
# CMP 398
CMP 61 1.745 3.91 180.0 N C44 ??? ;0=1,1=0.022000
PRP SIGNAL_MODEL 'DEFAULT_CAPACITOR_100000pF_1_2' 
PRP REUSE_ID '11' 
PRP ALT_SYMBOLS '(SMC_0402R_C_H022,C0402-1MM-TRIANGLE-S0,C0402-P8MM-S0)' 
PRP PARENT_PART_TYPE 'CAPACITOR' 
PRP PARENT_PPT 'CAPACITOR' 
PRP PARENT_PPT_PART 'CAPACITOR-G105-0B104-EK,0.1UF,10%' 
PRP PART_NAME 'CAPACITOR' 
TOP 0 1.724 3.91 180.0 N 106 1 1
TOP 1 1.766 3.91 180.0 N 107 4 2
#
# CMP 399
CMP 61 1.456 4.036 180.0 N C42 ??? ;0=1,1=0.022000
PRP REUSE_ID '22' 
PRP ALT_SYMBOLS '(SMC_0402R_C_H022)' 
PRP PARENT_PART_TYPE 'CAPACITOR' 
PRP PARENT_PPT 'CAPACITOR' 
PRP PARENT_PPT_PART 'CAPACITOR-G105-0B222-FK,2200PF,10%' 
PRP PART_NAME 'CAPACITOR' 
TOP 0 1.435 4.036 180.0 N 104 1 1
TOP 1 1.477 4.036 180.0 N 90 7 2
#
# CMP 400
CMP 61 4.78 1.84211 90.0 N C145 ??? ;0=1,1=0.022000
PRP SIGNAL_MODEL 'DEFAULT_CAPACITOR_100000pF_1_2' 
PRP ALT_SYMBOLS '(SMC_0402R_C_H022,C0402_BGA,C0402-0P8MM-45DG,C0402-1MM-TRIANGLE-S0)' 
PRP PARENT_PART_TYPE 'CAPACITOR' 
PRP PARENT_PPT 'CAPACITOR' 
PRP PARENT_PPT_PART 'CAPACITOR-G105-0B104-CK,0.1UF,10%' 
PRP PART_NAME 'CAPACITOR' 
TOP 0 4.78 1.86311 90.0 N 1 234 1
TOP 1 4.78 1.82111 90.0 N 2 653 2
#
# CMP 401
CMP 61 5.61 1.98 180.0 N C266 ??? ;0=1,1=0.022000
PRP ALT_SYMBOLS '(SMC_0402R_C_H022,SMC_0402R_V2_H022,C0402-1MM-TRIANGLE-S0,C0402-P8MM-S0)' 
PRP PARENT_PART_TYPE 'CAPACITOR' 
PRP PARENT_PPT 'CAPACITOR' 
PRP PARENT_PPT_PART 'CAPACITOR-G105-0A102-FJ,1000PF,5%' 
PRP PART_NAME 'CAPACITOR' 
TOP 0 5.589 1.98 180.0 N 64 3 1
TOP 1 5.631 1.98 180.0 N 65 1 2
#
# CMP 402
CMP 61 1.63 3.525 90.0 N C88 ??? ;0=1,1=0.022000
PRP SIGNAL_MODEL 'DEFAULT_CAPACITOR_100000pF_1_2' 
PRP ALT_SYMBOLS '(SMC_0402R_C_H022,C0402-1MM-TRIANGLE-S0,C0402-P8MM-S0)' 
PRP PARENT_PART_TYPE 'CAPACITOR' 
PRP PARENT_PPT 'CAPACITOR' 
PRP PARENT_PPT_PART 'CAPACITOR-G105-0B104-EK,0.1UF,10%' 
PRP PART_NAME 'CAPACITOR' 
TOP 0 1.63 3.546 90.0 N 88 27 1
TOP 1 1.63 3.504 90.0 N 2 654 2
#
# CMP 403
CMP 61 5.39 1.625 90.0 N C178 ??? ;0=1,1=0.022000
PRP SIGNAL_MODEL 'DEFAULT_CAPACITOR_100000pF_1_2' 
PRP REUSE_ID '23' 
PRP ALT_SYMBOLS '(SMC_0402R_C_H022,C0402_BGA,C0402-0P8MM-45DG,C0402-1MM-TRIANGLE-S0)' 
PRP PARENT_PART_TYPE 'CAPACITOR' 
PRP PARENT_PPT 'CAPACITOR' 
PRP PARENT_PPT_PART 'CAPACITOR-G105-0B104-CK,0.1UF,10%' 
PRP PART_NAME 'CAPACITOR' 
TOP 0 5.39 1.646 90.0 N 15 12 1
TOP 1 5.39 1.604 90.0 N 2 655 2
#
# CMP 404
CMP 61 3.63 2.17 180.0 N C150 ??? ;0=1,1=0.022000
PRP SIGNAL_MODEL 'DEFAULT_CAPACITOR_100000pF_1_2' 
PRP ALT_SYMBOLS '(SMC_0402R_C_H022,C0402_BGA,C0402-0P8MM-45DG,C0402-1MM-TRIANGLE-S0)' 
PRP PARENT_PART_TYPE 'CAPACITOR' 
PRP PARENT_PPT 'CAPACITOR' 
PRP PARENT_PPT_PART 'CAPACITOR-G105-0B104-CK,0.1UF,10%' 
PRP PART_NAME 'CAPACITOR' 
TOP 0 3.609 2.17 180.0 N 16 10 1
TOP 1 3.651 2.17 180.0 N 2 656 2
#
# CMP 405
CMP 61 3.02 2.005 180.0 N C65 ??? ;0=1,1=0.022000
PRP SIGNAL_MODEL 'DEFAULT_CAPACITOR_100000pF_1_2' 
PRP ALT_SYMBOLS '(SMC_0402R_C_H022,C0402-1MM-TRIANGLE-S0,C0402-P8MM-S0)' 
PRP PARENT_PART_TYPE 'CAPACITOR' 
PRP PARENT_PPT 'CAPACITOR' 
PRP PARENT_PPT_PART 'CAPACITOR-G105-0B104-EK,0.1UF,10%' 
PRP PART_NAME 'CAPACITOR' 
TOP 0 2.999 2.005 180.0 N 122 4 1
TOP 1 3.041 2.005 180.0 N 2 657 2
#
# CMP 406
CMP 61 3.02 2.05 180.0 N C66 ??? ;0=1,1=0.022000
PRP SIGNAL_MODEL 'DEFAULT_CAPACITOR_100000pF_1_2' 
PRP ALT_SYMBOLS '(SMC_0402R_C_H022,C0402-1MM-TRIANGLE-S0,C0402-P8MM-S0)' 
PRP PARENT_PART_TYPE 'CAPACITOR' 
PRP PARENT_PPT 'CAPACITOR' 
PRP PARENT_PPT_PART 'CAPACITOR-G105-0B104-EK,0.1UF,10%' 
PRP PART_NAME 'CAPACITOR' 
TOP 0 2.999 2.05 180.0 N 122 5 1
TOP 1 3.041 2.05 180.0 N 2 658 2
#
# CMP 407
CMP 61 4.22 1.75 0.0 N C219 ??? ;0=1,1=0.022000
PRP SIGNAL_MODEL 'DEFAULT_CAPACITOR_100000pF_1_2' 
PRP ALT_SYMBOLS '(SMC_0402R_C_H022,C0402_BGA,C0402-0P8MM-45DG,C0402-1MM-TRIANGLE-S0)' 
PRP PARENT_PART_TYPE 'CAPACITOR' 
PRP PARENT_PPT 'CAPACITOR' 
PRP PARENT_PPT_PART 'CAPACITOR-G105-0B104-CK,0.1UF,10%' 
PRP PART_NAME 'CAPACITOR' 
TOP 0 4.241 1.75 0.0 N 8 14 1
TOP 1 4.199 1.75 0.0 N 2 659 2
#
# CMP 408
CMP 61 4.119 1.75 0.0 N C113 ??? ;0=1,1=0.022000
PRP SIGNAL_MODEL 'DEFAULT_CAPACITOR_100000pF_1_2' 
PRP ALT_SYMBOLS '(SMC_0402R_C_H022,C0402_BGA,C0402-0P8MM-45DG,C0402-1MM-TRIANGLE-S0)' 
PRP PARENT_PART_TYPE 'CAPACITOR' 
PRP PARENT_PPT 'CAPACITOR' 
PRP PARENT_PPT_PART 'CAPACITOR-G105-0B104-CK,0.1UF,10%' 
PRP PART_NAME 'CAPACITOR' 
TOP 0 4.14 1.75 0.0 N 8 15 1
TOP 1 4.098 1.75 0.0 N 2 660 2
#
# CMP 409
CMP 61 4.305 1.57 270.0 N C133 ??? ;0=1,1=0.022000
PRP SIGNAL_MODEL 'DEFAULT_CAPACITOR_100000pF_1_2' 
PRP REUSE_ID '13' 
PRP ALT_SYMBOLS '(SMC_0402R_C_H022,C0402_BGA,C0402-0P8MM-45DG,C0402-1MM-TRIANGLE-S0)' 
PRP PARENT_PART_TYPE 'CAPACITOR' 
PRP PARENT_PPT 'CAPACITOR' 
PRP PARENT_PPT_PART 'CAPACITOR-G105-0B104-CK,0.1UF,10%' 
PRP PART_NAME 'CAPACITOR' 
TOP 0 4.305 1.549 270.0 N 10 37 1
TOP 1 4.305 1.591 270.0 N 2 661 2
#
# CMP 410
CMP 61 2.79 2.185 270.0 N C71 ??? ;0=1,1=0.022000
PRP SIGNAL_MODEL 'DEFAULT_CAPACITOR_100000pF_1_2' 
PRP ALT_SYMBOLS '(SMC_0402R_C_H022,C0402-1MM-TRIANGLE-S0,C0402-P8MM-S0)' 
PRP PARENT_PART_TYPE 'CAPACITOR' 
PRP PARENT_PPT 'CAPACITOR' 
PRP PARENT_PPT_PART 'CAPACITOR-G105-0B104-EK,0.1UF,10%' 
PRP PART_NAME 'CAPACITOR' 
TOP 0 2.79 2.164 270.0 N 122 6 1
TOP 1 2.79 2.206 270.0 N 2 662 2
#
# CMP 411
CMP 61 2.855 2.865 270.0 N C59 ??? ;0=1,1=0.022000
PRP SIGNAL_MODEL 'DEFAULT_CAPACITOR_100000pF_1_2' 
PRP ALT_SYMBOLS '(SMC_0402R_C_H022,C0402-1MM-TRIANGLE-S0,C0402-P8MM-S0)' 
PRP PARENT_PART_TYPE 'CAPACITOR' 
PRP PARENT_PPT 'CAPACITOR' 
PRP PARENT_PPT_PART 'CAPACITOR-G105-0B104-EK,0.1UF,10%' 
PRP PART_NAME 'CAPACITOR' 
TOP 0 2.855 2.844 270.0 N 76 9 1
TOP 1 2.855 2.886 270.0 N 2 663 2
#
# CMP 412
CMP 61 2.79 2.317 90.0 N C70 ??? ;0=1,1=0.022000
PRP SIGNAL_MODEL 'DEFAULT_CAPACITOR_100000pF_1_2' 
PRP ALT_SYMBOLS '(SMC_0402R_C_H022,C0402-1MM-TRIANGLE-S0,C0402-P8MM-S0)' 
PRP PARENT_PART_TYPE 'CAPACITOR' 
PRP PARENT_PPT 'CAPACITOR' 
PRP PARENT_PPT_PART 'CAPACITOR-G105-0B104-EK,0.1UF,10%' 
PRP PART_NAME 'CAPACITOR' 
TOP 0 2.79 2.338 90.0 N 76 10 1
TOP 1 2.79 2.296 90.0 N 2 664 2
#
# CMP 413
CMP 61 2.59 2.285 90.0 N C69 ??? ;0=1,1=0.022000
PRP SIGNAL_MODEL 'DEFAULT_CAPACITOR_100000pF_1_2' 
PRP ALT_SYMBOLS '(SMC_0402R_C_H022,C0402-1MM-TRIANGLE-S0,C0402-P8MM-S0)' 
PRP PARENT_PART_TYPE 'CAPACITOR' 
PRP PARENT_PPT 'CAPACITOR' 
PRP PARENT_PPT_PART 'CAPACITOR-G105-0B104-EK,0.1UF,10%' 
PRP PART_NAME 'CAPACITOR' 
TOP 0 2.59 2.306 90.0 N 123 3 1
TOP 1 2.59 2.264 90.0 N 2 665 2
#
# CMP 414
CMP 61 3.245 2.88 90.0 N C62 ??? ;0=1,1=0.022000
PRP SIGNAL_MODEL 'DEFAULT_CAPACITOR_100000pF_1_2' 
PRP ALT_SYMBOLS '(SMC_0402R_C_H022,C0402-1MM-TRIANGLE-S0,C0402-P8MM-S0)' 
PRP PARENT_PART_TYPE 'CAPACITOR' 
PRP PARENT_PPT 'CAPACITOR' 
PRP PARENT_PPT_PART 'CAPACITOR-G105-0B104-EK,0.1UF,10%' 
PRP PART_NAME 'CAPACITOR' 
TOP 0 3.245 2.901 90.0 N 13 12 1
TOP 1 3.245 2.859 90.0 N 2 666 2
#
# CMP 415
CMP 61 2.9 2.865 270.0 N C60 ??? ;0=1,1=0.022000
PRP SIGNAL_MODEL 'DEFAULT_CAPACITOR_100000pF_1_2' 
PRP ALT_SYMBOLS '(SMC_0402R_C_H022,C0402-1MM-TRIANGLE-S0,C0402-P8MM-S0)' 
PRP PARENT_PART_TYPE 'CAPACITOR' 
PRP PARENT_PPT 'CAPACITOR' 
PRP PARENT_PPT_PART 'CAPACITOR-G105-0B104-EK,0.1UF,10%' 
PRP PART_NAME 'CAPACITOR' 
TOP 0 2.9 2.844 270.0 N 76 11 1
TOP 1 2.9 2.886 270.0 N 2 667 2
#
# CMP 416
CMP 61 2.44 2.355 0.0 N C68 ??? ;0=1,1=0.022000
PRP SIGNAL_MODEL 'DEFAULT_CAPACITOR_100000pF_1_2' 
PRP ALT_SYMBOLS '(SMC_0402R_C_H022,C0402-1MM-TRIANGLE-S0,C0402-P8MM-S0)' 
PRP PARENT_PART_TYPE 'CAPACITOR' 
PRP PARENT_PPT 'CAPACITOR' 
PRP PARENT_PPT_PART 'CAPACITOR-G105-0B104-EK,0.1UF,10%' 
PRP PART_NAME 'CAPACITOR' 
TOP 0 2.461 2.355 0.0 N 1 235 1
TOP 1 2.419 2.355 0.0 N 2 668 2
#
# CMP 417
CMP 61 5.825 0.775 270.0 N C293 ??? ;0=1,1=0.022000
PRP ALT_SYMBOLS '(SMC_0402R_C_H022)' 
PRP PARENT_PART_TYPE 'CAPACITOR' 
PRP PARENT_PPT 'CAPACITOR' 
PRP PARENT_PPT_PART 'CAPACITOR-G105-0B224-DK,0.22UF,10%' 
PRP PART_NAME 'CAPACITOR' 
TOP 0 5.825 0.754 270.0 N 31 5 1
TOP 1 5.825 0.796 270.0 N 2 669 2
#
# CMP 418
CMP 61 4.3 2.008 270.0 N C149 ??? ;0=1,1=0.022000
PRP SIGNAL_MODEL 'DEFAULT_CAPACITOR_100000pF_1_2' 
PRP ALT_SYMBOLS '(SMC_0402R_C_H022,C0402_BGA,C0402-0P8MM-45DG,C0402-1MM-TRIANGLE-S0)' 
PRP PARENT_PART_TYPE 'CAPACITOR' 
PRP PARENT_PPT 'CAPACITOR' 
PRP PARENT_PPT_PART 'CAPACITOR-G105-0B104-CK,0.1UF,10%' 
PRP PART_NAME 'CAPACITOR' 
TOP 0 4.3 1.987 270.0 N 1 236 1
TOP 1 4.3 2.029 270.0 N 2 670 2
#
# CMP 419
CMP 61 4.306 1.816 90.0 N C115 ??? ;0=1,1=0.022000
PRP SIGNAL_MODEL 'DEFAULT_CAPACITOR_100000pF_1_2' 
PRP ALT_SYMBOLS '(SMC_0402R_C_H022,C0402_BGA,C0402-0P8MM-45DG,C0402-1MM-TRIANGLE-S0)' 
PRP PARENT_PART_TYPE 'CAPACITOR' 
PRP PARENT_PPT 'CAPACITOR' 
PRP PARENT_PPT_PART 'CAPACITOR-G105-0B104-CK,0.1UF,10%' 
PRP PART_NAME 'CAPACITOR' 
TOP 0 4.306 1.837 90.0 N 1 237 1
TOP 1 4.306 1.795 90.0 N 2 671 2
#
# CMP 420
CMP 61 4.344 1.741 0.0 N C212 ??? ;0=1,1=0.022000
PRP SIGNAL_MODEL 'DEFAULT_CAPACITOR_100000pF_1_2' 
PRP ALT_SYMBOLS '(SMC_0402R_C_H022,C0402_BGA,C0402-0P8MM-45DG,C0402-1MM-TRIANGLE-S0)' 
PRP PARENT_PART_TYPE 'CAPACITOR' 
PRP PARENT_PPT 'CAPACITOR' 
PRP PARENT_PPT_PART 'CAPACITOR-G105-0B104-CK,0.1UF,10%' 
PRP PART_NAME 'CAPACITOR' 
TOP 0 4.365 1.741 0.0 N 8 16 1
TOP 1 4.323 1.741 0.0 N 2 672 2
#
# CMP 421
CMP 61 4.305 1.67 90.0 N C114 ??? ;0=1,1=0.022000
PRP SIGNAL_MODEL 'DEFAULT_CAPACITOR_100000pF_1_2' 
PRP REUSE_ID '12' 
PRP ALT_SYMBOLS '(SMC_0402R_C_H022,C0402_BGA,C0402-0P8MM-45DG,C0402-1MM-TRIANGLE-S0)' 
PRP PARENT_PART_TYPE 'CAPACITOR' 
PRP PARENT_PPT 'CAPACITOR' 
PRP PARENT_PPT_PART 'CAPACITOR-G105-0B104-CK,0.1UF,10%' 
PRP PART_NAME 'CAPACITOR' 
TOP 0 4.305 1.691 90.0 N 10 38 1
TOP 1 4.305 1.649 90.0 N 2 673 2
#
# CMP 422
CMP 61 4.53411 1.755 180.0 N C165 ??? ;0=1,1=0.022000
PRP SIGNAL_MODEL 'DEFAULT_CAPACITOR_100000pF_1_2' 
PRP ALT_SYMBOLS '(SMC_0402R_C_H022,C0402_BGA,C0402-0P8MM-45DG,C0402-1MM-TRIANGLE-S0)' 
PRP PARENT_PART_TYPE 'CAPACITOR' 
PRP PARENT_PPT 'CAPACITOR' 
PRP PARENT_PPT_PART 'CAPACITOR-G105-0B104-CK,0.1UF,10%' 
PRP PART_NAME 'CAPACITOR' 
TOP 0 4.51311 1.755 180.0 N 1 238 1
TOP 1 4.55511 1.755 180.0 N 2 674 2
#
# CMP 423
CMP 61 4.29 0.73 180.0 N C244 ??? ;0=1,1=0.022000
PRP SIGNAL_MODEL 'DEFAULT_CAPACITOR_100000pF_1_2' 
PRP ALT_SYMBOLS '(SMC_0402R_C_H022,C0402-1MM-TRIANGLE-S0,C0402-P8MM-S0)' 
PRP PARENT_PART_TYPE 'CAPACITOR' 
PRP PARENT_PPT 'CAPACITOR' 
PRP PARENT_PPT_PART 'CAPACITOR-G105-0B104-EK,0.1UF,10%' 
PRP PART_NAME 'CAPACITOR' 
TOP 0 4.269 0.73 180.0 N 19 35 1
TOP 1 4.311 0.73 180.0 N 2 675 2
#
# CMP 424
CMP 61 4.275 0.94 270.0 N C246 ??? ;0=1,1=0.022000
PRP ALT_SYMBOLS '(SMC_0402R_C_H022,C0402_BGA,C0402-0P8MM-45DG,C0402-P8MM-S0,C0402-1MM-TRIANGLE-S0)' 
PRP PARENT_PART_TYPE 'CAPACITOR' 
PRP PARENT_PPT 'CAPACITOR' 
PRP PARENT_PPT_PART 'CAPACITOR-G105-0C106-BM,10UF,20%' 
PRP PART_NAME 'CAPACITOR' 
TOP 0 4.275 0.919 270.0 N 41 3 1
TOP 1 4.275 0.961 270.0 N 2 676 2
#
# CMP 425
CMP 61 4.32 0.94 270.0 N C248 ??? ;0=1,1=0.022000
PRP SIGNAL_MODEL 'DEFAULT_CAPACITOR_100000pF_1_2' 
PRP ALT_SYMBOLS '(SMC_0402R_C_H022,C0402-1MM-TRIANGLE-S0,C0402-P8MM-S0)' 
PRP PARENT_PART_TYPE 'CAPACITOR' 
PRP PARENT_PPT 'CAPACITOR' 
PRP PARENT_PPT_PART 'CAPACITOR-G105-0B104-EK,0.1UF,10%' 
PRP PART_NAME 'CAPACITOR' 
TOP 0 4.32 0.919 270.0 N 41 4 1
TOP 1 4.32 0.961 270.0 N 2 677 2
#
# CMP 426
CMP 61 3.185 3.9 90.0 N C57 ??? ;0=1,1=0.022000
PRP REUSE_ID '21' 
PRP ALT_SYMBOLS '(SMC_0402R_C_H022,SMC_0402R_V2_H022,C0402-1MM-TRIANGLE-S0,C0402-P8MM-S0)' 
PRP PARENT_PART_TYPE 'CAPACITOR' 
PRP PARENT_PPT 'CAPACITOR' 
PRP PARENT_PPT_PART 'CAPACITOR-G105-0A102-FJ,1000PF,5%' 
PRP PART_NAME 'CAPACITOR' 
TOP 0 3.185 3.921 90.0 N 118 3 1
TOP 1 3.185 3.879 90.0 N 119 1 2
#
# CMP 427
CMP 61 4.545 2.895 180.0 N C294 ??? ;0=1,1=0.022000
PRP ALT_SYMBOLS '(SMC_0402R_C_H022)' 
PRP PARENT_PART_TYPE 'CAPACITOR' 
PRP PARENT_PPT 'CAPACITOR' 
PRP PARENT_PPT_PART 'CAPACITOR-G105-0B224-DK,0.22UF,10%' 
PRP PART_NAME 'CAPACITOR' 
TOP 0 4.524 2.895 180.0 N 33 4 1
TOP 1 4.566 2.895 180.0 N 2 678 2
#
# CMP 428
CMP 61 4.545 2.845 180.0 N C229 ??? ;0=1,1=0.022000
PRP SIGNAL_MODEL 'DEFAULT_CAPACITOR_100000pF_1_2' 
PRP ALT_SYMBOLS '(SMC_0402R_C_H022,C0402_BGA,C0402-0P8MM-45DG,C0402-1MM-TRIANGLE-S0)' 
PRP PARENT_PART_TYPE 'CAPACITOR' 
PRP PARENT_PPT 'CAPACITOR' 
PRP PARENT_PPT_PART 'CAPACITOR-G105-0B104-CK,0.1UF,10%' 
PRP PART_NAME 'CAPACITOR' 
TOP 0 4.524 2.845 180.0 N 33 5 1
TOP 1 4.566 2.845 180.0 N 2 679 2
#
# CMP 429
CMP 61 5.035 3.875 90.0 N C78 ??? ;0=1,1=0.022000
PRP SIGNAL_MODEL 'DEFAULT_CAPACITOR_100000pF_1_2' 
PRP ALT_SYMBOLS '(SMC_0402R_C_H022,C0402-1MM-TRIANGLE-S0,C0402-P8MM-S0)' 
PRP PARENT_PART_TYPE 'CAPACITOR' 
PRP PARENT_PPT 'CAPACITOR' 
PRP PARENT_PPT_PART 'CAPACITOR-G105-0B104-EK,0.1UF,10%' 
PRP PART_NAME 'CAPACITOR' 
TOP 0 5.035 3.896 90.0 N 125 3 1
TOP 1 5.035 3.854 90.0 N 2 680 2
#
# CMP 430
CMP 61 5.085 3.875 90.0 N C73 ??? ;0=1,1=0.022000
PRP SIGNAL_MODEL 'DEFAULT_CAPACITOR_100000pF_1_2' 
PRP ALT_SYMBOLS '(SMC_0402R_C_H022,C0402-1MM-TRIANGLE-S0,C0402-P8MM-S0)' 
PRP PARENT_PART_TYPE 'CAPACITOR' 
PRP PARENT_PPT 'CAPACITOR' 
PRP PARENT_PPT_PART 'CAPACITOR-G105-0B104-EK,0.1UF,10%' 
PRP PART_NAME 'CAPACITOR' 
TOP 0 5.085 3.896 90.0 N 125 4 1
TOP 1 5.085 3.854 90.0 N 2 681 2
#
# CMP 431
CMP 61 4.24 3.962 270.0 N C316 ??? ;0=1,1=0.022000
PRP SIGNAL_MODEL 'DEFAULT_CAPACITOR_100000pF_1_2' 
PRP ALT_SYMBOLS '(SMC_0402R_C_H022,C0402-1MM-TRIANGLE-S0,C0402-P8MM-S0)' 
PRP PARENT_PART_TYPE 'CAPACITOR' 
PRP PARENT_PPT 'CAPACITOR' 
PRP PARENT_PPT_PART 'CAPACITOR-G105-0B104-EK,0.1UF,10%' 
PRP PART_NAME 'CAPACITOR' 
TOP 0 4.24 3.941 270.0 N 93 4 1
TOP 1 4.24 3.983 270.0 N 2 682 2
#
# CMP 432
CMP 61 3.543 4.032 180.0 N C286 ??? ;0=1,1=0.022000
PRP ALT_SYMBOLS '(SMC_0402R_C_H022)' 
PRP PARENT_PART_TYPE 'CAPACITOR' 
PRP PARENT_PPT 'CAPACITOR' 
PRP PARENT_PPT_PART 'CAPACITOR-G105-0B224-DK,0.22UF,10%' 
PRP PART_NAME 'CAPACITOR' 
TOP 0 3.522 4.032 180.0 N 79 5 1
TOP 1 3.564 4.032 180.0 N 2 683 2
#
# CMP 433
CMP 61 3.543 3.942 0.0 N C54 ??? ;0=1,1=0.022000
PRP REUSE_ID '31' 
PRP ALT_SYMBOLS '(SMC_0402R_C_H022)' 
PRP PARENT_PART_TYPE 'CAPACITOR' 
PRP PARENT_PPT 'CAPACITOR' 
PRP PARENT_PPT_PART 'CAPACITOR-G105-0B222-FK,2200PF,10%' 
PRP PART_NAME 'CAPACITOR' 
TOP 0 3.564 3.942 0.0 N 115 1 1
TOP 1 3.522 3.942 0.0 N 112 7 2
#
# CMP 434
CMP 61 3.265 4.07 0.0 N C56 ??? ;0=1,1=0.022000
PRP SIGNAL_MODEL 'DEFAULT_CAPACITOR_100000pF_1_2' 
PRP REUSE_ID '6' 
PRP ALT_SYMBOLS '(SMC_0402R_C_H022,C0402-1MM-TRIANGLE-S0,C0402-P8MM-S0)' 
PRP PARENT_PART_TYPE 'CAPACITOR' 
PRP PARENT_PPT 'CAPACITOR' 
PRP PARENT_PPT_PART 'CAPACITOR-G105-0B104-EK,0.1UF,10%' 
PRP PART_NAME 'CAPACITOR' 
TOP 0 3.286 4.07 0.0 N 117 1 1
TOP 1 3.244 4.07 0.0 N 118 4 2
#
# CMP 435
CMP 61 4.635 3.895 0.0 N C80 ??? ;0=1,1=0.022000
PRP SIGNAL_MODEL 'DEFAULT_CAPACITOR_100000pF_1_2' 
PRP REUSE_ID '2' 
PRP ALT_SYMBOLS '(SMC_0402R_C_H022,C0402_BGA,C0402-0P8MM-45DG,C0402-1MM-TRIANGLE-S0)' 
PRP PARENT_PART_TYPE 'CAPACITOR' 
PRP PARENT_PPT 'CAPACITOR' 
PRP PARENT_PPT_PART 'CAPACITOR-G105-0B104-CK,0.1UF,10%' 
PRP PART_NAME 'CAPACITOR' 
TOP 0 4.656 3.895 0.0 N 70 4 1
TOP 1 4.614 3.895 0.0 N 2 684 2
#
# CMP 436
CMP 61 4.635 3.94 0.0 N C273 ??? ;0=1,1=0.022000
PRP SIGNAL_MODEL 'DEFAULT_CAPACITOR_100000pF_1_2' 
PRP REUSE_ID '3' 
PRP ALT_SYMBOLS '(SMC_0402R_C_H022,C0402_BGA,C0402-0P8MM-45DG,C0402-1MM-TRIANGLE-S0)' 
PRP PARENT_PART_TYPE 'CAPACITOR' 
PRP PARENT_PPT 'CAPACITOR' 
PRP PARENT_PPT_PART 'CAPACITOR-G105-0B104-CK,0.1UF,10%' 
PRP PART_NAME 'CAPACITOR' 
TOP 0 4.656 3.94 0.0 N 70 5 1
TOP 1 4.614 3.94 0.0 N 2 685 2
#
# CMP 437
CMP 61 4.375 3.965 180.0 N C315 ??? ;0=1,1=0.022000
PRP SIGNAL_MODEL 'DEFAULT_CAPACITOR_100000pF_1_2' 
PRP ALT_SYMBOLS '(SMC_0402R_C_H022,C0402-1MM-TRIANGLE-S0,C0402-P8MM-S0)' 
PRP PARENT_PART_TYPE 'CAPACITOR' 
PRP PARENT_PPT 'CAPACITOR' 
PRP PARENT_PPT_PART 'CAPACITOR-G105-0B104-EK,0.1UF,10%' 
PRP PART_NAME 'CAPACITOR' 
TOP 0 4.354 3.965 180.0 N 1 239 1
TOP 1 4.396 3.965 180.0 N 2 686 2
#
# CMP 438
CMP 61 1.175 3.475 180.0 N C95 ??? ;0=1,1=0.022000
PRP SIGNAL_MODEL 'DEFAULT_CAPACITOR_100000pF_1_2' 
PRP REUSE_ID '18' 
PRP ALT_SYMBOLS '(SMC_0402R_C_H022,C0402-1MM-TRIANGLE-S0,C0402-P8MM-S0)' 
PRP PARENT_PART_TYPE 'CAPACITOR' 
PRP PARENT_PPT 'CAPACITOR' 
PRP PARENT_PPT_PART 'CAPACITOR-G105-0B104-EK,0.1UF,10%' 
PRP PART_NAME 'CAPACITOR' 
TOP 0 1.154 3.475 180.0 N 88 28 1
TOP 1 1.196 3.475 180.0 N 2 687 2
#
# CMP 439
CMP 61 1.13 3.585 270.0 N C100 ??? ;0=1,1=0.022000
PRP SIGNAL_MODEL 'DEFAULT_CAPACITOR_100000pF_1_2' 
PRP REUSE_ID '14' 
PRP ALT_SYMBOLS '(SMC_0402R_C_H022,C0402-1MM-TRIANGLE-S0,C0402-P8MM-S0)' 
PRP PARENT_PART_TYPE 'CAPACITOR' 
PRP PARENT_PPT 'CAPACITOR' 
PRP PARENT_PPT_PART 'CAPACITOR-G105-0B104-EK,0.1UF,10%' 
PRP PART_NAME 'CAPACITOR' 
TOP 0 1.13 3.564 270.0 N 4 3 1
TOP 1 1.13 3.606 270.0 N 2 688 2
#
# CMP 440
CMP 61 1.355 3.5 180.0 N C96 ??? ;0=1,1=0.022000
PRP SIGNAL_MODEL 'DEFAULT_CAPACITOR_100000pF_1_2' 
PRP REUSE_ID '21' 
PRP ALT_SYMBOLS '(SMC_0402R_C_H022,C0402-1MM-TRIANGLE-S0,C0402-P8MM-S0)' 
PRP PARENT_PART_TYPE 'CAPACITOR' 
PRP PARENT_PPT 'CAPACITOR' 
PRP PARENT_PPT_PART 'CAPACITOR-G105-0B104-EK,0.1UF,10%' 
PRP PART_NAME 'CAPACITOR' 
TOP 0 1.334 3.5 180.0 N 131 5 1
TOP 1 1.376 3.5 180.0 N 2 689 2
#
# CMP 441
CMP 61 5.51 2.045 90.0 N C265 ??? ;0=1,1=0.022000
PRP SIGNAL_MODEL 'DEFAULT_CAPACITOR_100000pF_1_2' 
PRP ALT_SYMBOLS '(SMC_0402R_C_H022,C0402-1MM-TRIANGLE-S0,C0402-P8MM-S0)' 
PRP PARENT_PART_TYPE 'CAPACITOR' 
PRP PARENT_PPT 'CAPACITOR' 
PRP PARENT_PPT_PART 'CAPACITOR-G105-0B104-EK,0.1UF,10%' 
PRP PART_NAME 'CAPACITOR' 
TOP 0 5.51 2.066 90.0 N 63 1 1
TOP 1 5.51 2.024 90.0 N 64 4 2
#
# CMP 442
CMP 63 5.713 2.681 270.0 N CR7 ??? ;0=1,1=0.047000
PRP HARD_LOCATION 'YES' 
PRP ALT_SYMBOLS '(SOT143)' 
PRP PARENT_PART_TYPE 'DIODE_4_V1' 
PRP PARENT_PPT 'DIODE_4_V1' 
PRP PARENT_PPT_PART 'DIODE_4_V1-G122-10123-01' 
PRP PART_NAME 'DIODE_4_V1' 
TOP 0 5.7425 2.6375 270.0 N 2 690 1
TOP 1 5.6755 2.6375 270.0 N 141 3 2
TOP 2 5.6755 2.7245 270.0 N 142 3 3
TOP 3 5.7505 2.7245 270.0 N 0 227 4
#
# CMP 443
CMP 63 5.708 2.966 270.0 N CR6 ??? ;0=1,1=0.047000
PRP HARD_LOCATION 'YES' 
PRP ALT_SYMBOLS '(SOT143)' 
PRP PARENT_PART_TYPE 'DIODE_4_V1' 
PRP PARENT_PPT 'DIODE_4_V1' 
PRP PARENT_PPT_PART 'DIODE_4_V1-G122-10123-01' 
PRP PART_NAME 'DIODE_4_V1' 
TOP 0 5.7375 2.9225 270.0 N 2 691 1
TOP 1 5.6705 2.9225 270.0 N 139 3 2
TOP 2 5.6705 3.0095 270.0 N 140 3 3
TOP 3 5.7455 3.0095 270.0 N 0 228 4
#
# CMP 444
CMP 65 2.44 2.24 270.0 N U10 ??? ;0=1,1=0.043300
PRP ALT_SYMBOLS '(SC70_5V1)' 
PRP PARENT_PART_TYPE 'CL5003148A' 
PRP PARENT_PPT 'CL5003148A' 
PRP PARENT_PPT_PART 'CL5003148A-G220-10019-01' 
PRP PART_NAME 'CL5003148A' 
TOP 0 2.46559 2.193 270.0 N 249 3 1
TOP 1 2.44 2.193 270.0 N 250 4 2
TOP 2 2.41441 2.193 270.0 N 2 692 3
TOP 3 2.41441 2.287 270.0 N 123 4 4
TOP 4 2.46559 2.287 270.0 N 1 240 5
#
# CMP 445
CMP 71 1.105 4.145 0.0 N no_refdes+1 ?? ;0=1
TOP 0 1.105 4.145 0.0 N 0 229 1
#
# CMP 446
CMP 71 5.78 1.165 0.0 N no_refdes+2 ?? ;0=1
TOP 0 5.78 1.165 0.0 N 0 230 1
#
# CMP 447
CMP 71 0.95 0.845 0.0 N no_refdes+3 ?? ;0=1
TOP 0 0.95 0.845 0.0 N 0 231 1
#

### steps/pcb/layers/comp_+_top/components
#
#Component attribute names
#
@0 .comp_mount_type
@1 .comp_height

# CMP 0
CMP 0 6.43289 1.52063 270.0 N J5 ??? ;0=1,1=0.200000
PRP HARD_LOCATION 'YES' 
PRP ALT_SYMBOLS '(S_F_H_2X6_RA_P100)' 
PRP PARENT_PART_TYPE 'CONN_HDR_2X6_F_S_SMT' 
PRP PARENT_PPT 'CONN_HDR_2X6_F_S_SMT' 
PRP PARENT_PPT_PART 'CONN_HDR_2X6_F_S_SMT-G200-13133-01,SMH-106-02-L-D-TR' 
PRP PART_NAME 'CONN_HDR_2X6_F_S_SMT' 
TOP 0 6.14648 1.77063 270.0 N 214 0 1
TOP 1 5.9945 1.77063 270.0 N 215 0 2
TOP 2 6.14648 1.67063 270.0 N 216 0 3
TOP 3 5.9945 1.67063 270.0 N 217 0 4
TOP 4 6.14648 1.57063 270.0 N 218 0 5
TOP 5 5.9945 1.57063 270.0 N 219 0 6
TOP 6 6.14648 1.47063 270.0 N 220 0 7
TOP 7 5.9945 1.47063 270.0 N 221 0 8
TOP 8 6.14648 1.37063 270.0 N 2 0 9
TOP 9 5.9945 1.37063 270.0 N 2 1 10
TOP 10 6.14648 1.27063 270.0 N 1 0 11
TOP 11 5.9945 1.27063 270.0 N 1 1 12
#
# CMP 1
CMP 1 0.24606 3.4315 90.0 N J13 ??? ;0=2,1=0.359840
PRP HARD_LOCATION 'YES' 
PRP ALT_SYMBOLS '(P_F_USB_2X7_GH4_RA_P035_PIH)' 
PRP PARENT_PART_TYPE 'CONN_USB_14P_GH4_F_RA_TH' 
PRP PARENT_PPT 'CONN_USB_14P_GH4_F_RA_TH' 
PRP PARENT_PPT_PART 'CONN_USB_14P_GH4_F_RA_TH-G200-13135-01,2169890002' 
PRP PART_NAME 'CONN_USB_14P_GH4_F_RA_TH' 
TOP 0 0.24606 3.4315 90.0 N 2 2 A1
TOP 1 0.2815 3.4315 90.0 N 132 0 A4
TOP 2 0.31694 3.4315 90.0 N 206 0 A5
TOP 3 0.35238 3.4315 90.0 N 207 0 A6
TOP 4 0.38782 3.4315 90.0 N 208 0 A7
TOP 5 0.42326 3.4315 90.0 N 132 1 A9
TOP 6 0.4587 3.4315 90.0 N 2 3 A12
TOP 7 0.44098 3.4008 90.0 N 2 4 B1
TOP 8 0.40554 3.4008 90.0 N 132 2 B4
TOP 9 0.3701 3.4008 90.0 N 209 0 B5
TOP 10 0.33466 3.4008 90.0 N 207 1 B6
TOP 11 0.29922 3.4008 90.0 N 208 1 B7
TOP 12 0.26378 3.4008 90.0 N 132 3 B9
TOP 13 0.22834 3.4008 90.0 N 2 5 B12
TOP 14 0.43705 3.51576 90.0 N 2 6 GH1
TOP 15 0.43705 3.31655 90.0 N 2 7 GH2
TOP 16 0.24807 3.47245 90.0 N 2 8 GH3
TOP 17 0.24807 3.35985 90.0 N 2 9 GH4
#
# CMP 2
CMP 2 3.98 3.443 90.0 N U39 ??? ;0=1,1=0.043310
PRP ALT_SYMBOLS '(SOT363_V2)' 
PRP PARENT_PART_TYPE 'NLASB3157DFT2G_SC88' 
PRP PARENT_PPT 'NLASB3157DFT2G_SC88' 
PRP PARENT_PPT_PART 'NLASB3157DFT2G_SC88-G223-10187-01' 
PRP PART_NAME 'NLASB3157DFT2G_SC88' 
TOP 0 4.00559 3.4804 90.0 N 0 0 1
TOP 1 3.98 3.4804 90.0 N 2 10 2
TOP 2 3.95441 3.4804 90.0 N 326 0 3
TOP 3 3.95441 3.4056 90.0 N 406 0 4
TOP 4 3.98 3.4056 90.0 N 1 2 5
TOP 5 4.00559 3.4056 90.0 N 488 0 6
#
# CMP 3
CMP 2 4.175 3.445 90.0 N U40 ??? ;0=1,1=0.043310
PRP ALT_SYMBOLS '(SOT363_V2)' 
PRP PARENT_PART_TYPE 'NLASB3157DFT2G_SC88' 
PRP PARENT_PPT 'NLASB3157DFT2G_SC88' 
PRP PARENT_PPT_PART 'NLASB3157DFT2G_SC88-G223-10187-01' 
PRP PART_NAME 'NLASB3157DFT2G_SC88' 
TOP 0 4.20059 3.4824 90.0 N 0 1 1
TOP 1 4.175 3.4824 90.0 N 2 11 2
TOP 2 4.14941 3.4824 90.0 N 327 0 3
TOP 3 4.14941 3.4076 90.0 N 414 0 4
TOP 4 4.175 3.4076 90.0 N 1 3 5
TOP 5 4.20059 3.4076 90.0 N 488 1 6
#
# CMP 4
CMP 3 5.005 0.83 0.0 N U37 ??? ;0=1,1=0.047240
PRP ALT_SYMBOLS '(SOP16_173_P0256)' 
PRP PARENT_PART_TYPE 'TS3A5018PWR_TSSOP16' 
PRP PARENT_PPT 'TS3A5018PWR_TSSOP16' 
PRP PARENT_PPT_PART 'TS3A5018PWR_TSSOP16-G220-10324-01' 
PRP PART_NAME 'TS3A5018PWR_TSSOP16' 
TOP 0 4.8855 0.91957 0.0 N 512 0 1
TOP 1 4.8855 0.89398 0.0 N 508 0 2
TOP 2 4.8855 0.86839 0.0 N 506 0 3
TOP 3 4.8855 0.8428 0.0 N 287 0 4
TOP 4 4.8855 0.8172 0.0 N 509 0 5
TOP 5 4.8855 0.79161 0.0 N 504 0 6
TOP 6 4.8855 0.76602 0.0 N 289 0 7
TOP 7 4.8855 0.74043 0.0 N 2 12 8
TOP 8 5.1245 0.74043 0.0 N 308 0 9
TOP 9 5.1245 0.76602 0.0 N 506 1 10
TOP 10 5.1245 0.79161 0.0 N 510 0 11
TOP 11 5.1245 0.8172 0.0 N 309 0 12
TOP 12 5.1245 0.8428 0.0 N 504 1 13
TOP 13 5.1245 0.86839 0.0 N 511 0 14
TOP 14 5.1245 0.89398 0.0 N 513 0 15
TOP 15 5.1245 0.91957 0.0 N 1 4 16
#
# CMP 5
CMP 3 4.289 3.156 0.0 N U38 ??? ;0=1,1=0.047240
PRP ALT_SYMBOLS '(SOP16_173_P0256)' 
PRP PARENT_PART_TYPE 'TS3A5018PWR_TSSOP16' 
PRP PARENT_PPT 'TS3A5018PWR_TSSOP16' 
PRP PARENT_PPT_PART 'TS3A5018PWR_TSSOP16-G220-10324-01' 
PRP PART_NAME 'TS3A5018PWR_TSSOP16' 
TOP 0 4.1695 3.24557 0.0 N 488 2 1
TOP 1 4.1695 3.21998 0.0 N 329 0 2
TOP 2 4.1695 3.19439 0.0 N 574 0 3
TOP 3 4.1695 3.1688 0.0 N 313 0 4
TOP 4 4.1695 3.1432 0.0 N 341 0 5
TOP 5 4.1695 3.11761 0.0 N 575 0 6
TOP 6 4.1695 3.09202 0.0 N 324 0 7
TOP 7 4.1695 3.06643 0.0 N 2 13 8
TOP 8 4.4085 3.06643 0.0 N 325 0 9
TOP 9 4.4085 3.09202 0.0 N 576 0 10
TOP 10 4.4085 3.11761 0.0 N 345 0 11
TOP 11 4.4085 3.1432 0.0 N 312 0 12
TOP 12 4.4085 3.1688 0.0 N 577 0 13
TOP 13 4.4085 3.19439 0.0 N 426 0 14
TOP 14 4.4085 3.21998 0.0 N 489 0 15
TOP 15 4.4085 3.24557 0.0 N 1 5 16
#
# CMP 6
CMP 3 4.155 3.675 0.0 N U30 ??? ;0=1,1=0.047240
PRP ALT_SYMBOLS '(SOP16_173_P0256)' 
PRP PARENT_PART_TYPE 'TS3A5018PWR_TSSOP16' 
PRP PARENT_PPT 'TS3A5018PWR_TSSOP16' 
PRP PARENT_PPT_PART 'TS3A5018PWR_TSSOP16-G220-10324-01' 
PRP PART_NAME 'TS3A5018PWR_TSSOP16' 
TOP 0 4.0355 3.76457 0.0 N 482 0 1
TOP 1 4.0355 3.73898 0.0 N 141 0 2
TOP 2 4.0355 3.71339 0.0 N 574 1 3
TOP 3 4.0355 3.6878 0.0 N 497 0 4
TOP 4 4.0355 3.6622 0.0 N 140 0 5
TOP 5 4.0355 3.63661 0.0 N 575 1 6
TOP 6 4.0355 3.61102 0.0 N 499 0 7
TOP 7 4.0355 3.58543 0.0 N 2 14 8
TOP 8 4.2745 3.58543 0.0 N 500 0 9
TOP 9 4.2745 3.61102 0.0 N 576 1 10
TOP 10 4.2745 3.63661 0.0 N 142 0 11
TOP 11 4.2745 3.6622 0.0 N 502 0 12
TOP 12 4.2745 3.6878 0.0 N 577 1 13
TOP 13 4.2745 3.71339 0.0 N 139 0 14
TOP 14 4.2745 3.73898 0.0 N 246 0 15
TOP 15 4.2745 3.76457 0.0 N 1 6 16
#
# CMP 7
CMP 4 0.775 0.828 90.0 N U19 ??? ;0=1,1=0.047240
PRP REUSE_ID '11' 
PRP ALT_SYMBOLS '(SOP8_173X118_P0256)' 
PRP PARENT_PART_TYPE '24LC16BT_I_ST_TSSOP8' 
PRP PARENT_PPT '24LC16BT_I_ST_TSSOP8' 
PRP PARENT_PPT_PART '24LC16BT_I_ST_TSSOP8-G221-10176-01' 
PRP PART_NAME '24LC16BT_I_ST_TSSOP8' 
TOP 0 0.81339 0.9475 90.0 N 300 0 1
TOP 1 0.7878 0.9475 90.0 N 301 0 2
TOP 2 0.76221 0.9475 90.0 N 302 0 3
TOP 3 0.73662 0.9475 90.0 N 2 15 4
TOP 4 0.73662 0.7085 90.0 N 485 0 5
TOP 5 0.76221 0.7085 90.0 N 225 0 6
TOP 6 0.7878 0.7085 90.0 N 212 0 7
TOP 7 0.81339 0.7085 90.0 N 1 7 8
#
# CMP 8
CMP 5 1.64 3.17 180.0 N CR2 ??? ;0=1,1=0.043310
PRP ALT_SYMBOLS '(SMC_CR_067X049_V1)' 
PRP PARENT_PART_TYPE 'DIODE_2F' 
PRP PARENT_PPT 'DIODE_2F' 
PRP PARENT_PPT_PART 'DIODE_2F-G122-10186-01' 
PRP PART_NAME 'DIODE_2F' 
TOP 0 1.59669 3.17 180.0 N 132 4 A
TOP 1 1.68331 3.17 180.0 N 77 0 C
#
# CMP 9
CMP 5 1.64 3.27 180.0 N CR1 ??? ;0=1,1=0.043310
PRP REUSE_ID '3' 
PRP ALT_SYMBOLS '(SMC_CR_067X049_V1)' 
PRP PARENT_PART_TYPE 'DIODE_2F' 
PRP PARENT_PPT 'DIODE_2F' 
PRP PARENT_PPT_PART 'DIODE_2F-G122-10186-01' 
PRP PART_NAME 'DIODE_2F' 
TOP 0 1.59669 3.27 180.0 N 13 0 A
TOP 1 1.68331 3.27 180.0 N 77 1 C
#
# CMP 10
CMP 6 6.06 2.324 180.0 N L17 ??? ;0=1,1=0.037000
PRP ALT_SYMBOLS '(SMC_0603R_H037)' 
PRP PARENT_PART_TYPE 'FERRITEBEAD' 
PRP PARENT_PPT 'FERRITEBEAD' 
PRP PARENT_PPT_PART 'FERRITEBEAD-G191-10097-01,600OHM,25%' 
PRP PART_NAME 'FERRITEBEAD' 
TOP 0 6.087 2.324 180.0 N 1 8 1
TOP 1 6.033 2.324 180.0 N 71 0 2
#
# CMP 11
CMP 6 0.92548 2.632 180.0 N L18 ??? ;0=1,1=0.037000
PRP ALT_SYMBOLS '(SMC_0603R_H037)' 
PRP PARENT_PART_TYPE 'FERRITEBEAD' 
PRP PARENT_PPT 'FERRITEBEAD' 
PRP PARENT_PPT_PART 'FERRITEBEAD-G191-10097-01,600OHM,25%' 
PRP PART_NAME 'FERRITEBEAD' 
TOP 0 0.95248 2.632 180.0 N 16 0 1
TOP 1 0.89848 2.632 180.0 N 72 0 2
#
# CMP 12
CMP 6 3.491 2.536 270.0 N L19 ??? ;0=1,1=0.037000
PRP ALT_SYMBOLS '(SMC_0603R_H037)' 
PRP PARENT_PART_TYPE 'FERRITEBEAD' 
PRP PARENT_PPT 'FERRITEBEAD' 
PRP PARENT_PPT_PART 'FERRITEBEAD-G191-10097-01,600OHM,25%' 
PRP PART_NAME 'FERRITEBEAD' 
TOP 0 3.491 2.509 270.0 N 75 0 1
TOP 1 3.491 2.563 270.0 N 1 9 2
#
# CMP 13
CMP 7 1.123 3.349 90.0 N U18 ??? ;0=1,1=0.062990
PRP ALT_SYMBOLS '(QFP64_394_P0197_V1)' 
PRP PARENT_PART_TYPE 'FT4232HL_REEL_QFP64' 
PRP PARENT_PPT 'FT4232HL_REEL_QFP64' 
PRP PARENT_PPT_PART 'FT4232HL_REEL_QFP64-G223-10282-01,FT4232HL-REEL' 
PRP PART_NAME 'FT4232HL_REEL_QFP64' 
TOP 0 1.27064 3.578 90.0 N 2 16 1
TOP 1 1.25095 3.578 90.0 N 129 0 2
TOP 2 1.23127 3.578 90.0 N 130 0 3
TOP 3 1.21158 3.578 90.0 N 5 0 4
TOP 4 1.1919 3.578 90.0 N 2 17 5
TOP 5 1.17221 3.578 90.0 N 494 0 6
TOP 6 1.15253 3.578 90.0 N 274 0 7
TOP 7 1.13284 3.578 90.0 N 275 0 8
TOP 8 1.11316 3.578 90.0 N 4 0 9
TOP 9 1.09347 3.578 90.0 N 2 18 10
TOP 10 1.07379 3.578 90.0 N 2 19 11
TOP 11 1.0541 3.578 90.0 N 131 0 12
TOP 12 1.03442 3.578 90.0 N 2 20 13
TOP 13 1.01473 3.578 90.0 N 491 0 14
TOP 14 0.99505 3.578 90.0 N 2 21 15
TOP 15 0.97536 3.578 90.0 N 496 0 16
TOP 16 0.894 3.49664 90.0 N 498 0 17
TOP 17 0.894 3.47695 90.0 N 495 0 18
TOP 18 0.894 3.45727 90.0 N 501 0 19
TOP 19 0.894 3.43758 90.0 N 88 0 20
TOP 20 0.894 3.4179 90.0 N 484 0 21
TOP 21 0.894 3.39821 90.0 N 493 0 22
TOP 22 0.894 3.37853 90.0 N 515 0 23
TOP 23 0.894 3.35884 90.0 N 567 0 24
TOP 24 0.894 3.33916 90.0 N 2 22 25
TOP 25 0.894 3.31947 90.0 N 503 0 26
TOP 26 0.894 3.29979 90.0 N 505 0 27
TOP 27 0.894 3.2801 90.0 N 507 0 28
TOP 28 0.894 3.26042 90.0 N 568 0 29
TOP 29 0.894 3.24073 90.0 N 570 0 30
TOP 30 0.894 3.22105 90.0 N 88 1 31
TOP 31 0.894 3.20136 90.0 N 572 0 32
TOP 32 0.97536 3.12 90.0 N 573 0 33
TOP 33 0.99505 3.12 90.0 N 537 0 34
TOP 34 1.01473 3.12 90.0 N 2 23 35
TOP 35 1.03442 3.12 90.0 N 0 2 36
TOP 36 1.0541 3.12 90.0 N 131 1 37
TOP 37 1.07379 3.12 90.0 N 420 0 38
TOP 38 1.09347 3.12 90.0 N 418 0 39
TOP 39 1.11316 3.12 90.0 N 0 3 40
TOP 40 1.13284 3.12 90.0 N 0 4 41
TOP 41 1.15253 3.12 90.0 N 88 2 42
TOP 42 1.17221 3.12 90.0 N 0 5 43
TOP 43 1.1919 3.12 90.0 N 0 6 44
TOP 44 1.21158 3.12 90.0 N 0 7 45
TOP 45 1.23127 3.12 90.0 N 0 8 46
TOP 46 1.25095 3.12 90.0 N 2 24 47
TOP 47 1.27064 3.12 90.0 N 277 0 48
TOP 48 1.352 3.20136 90.0 N 131 2 49
TOP 49 1.352 3.22105 90.0 N 88 3 50
TOP 50 1.352 3.24073 90.0 N 2 25 51
TOP 51 1.352 3.26042 90.0 N 278 0 52
TOP 52 1.352 3.2801 90.0 N 0 9 53
TOP 53 1.352 3.29979 90.0 N 0 10 54
TOP 54 1.352 3.31947 90.0 N 0 11 55
TOP 55 1.352 3.33916 90.0 N 88 4 56
TOP 56 1.352 3.35884 90.0 N 0 12 57
TOP 57 1.352 3.37853 90.0 N 0 13 58
TOP 58 1.352 3.39821 90.0 N 0 14 59
TOP 59 1.352 3.4179 90.0 N 0 15 60
TOP 60 1.352 3.43758 90.0 N 486 0 61
TOP 61 1.352 3.45727 90.0 N 481 0 62
TOP 62 1.352 3.47695 90.0 N 480 0 63
TOP 63 1.352 3.49664 90.0 N 131 3 64
#
# CMP 14
CMP 8 5.597 1.838 90.0 N L5 ??? ;0=1,1=0.196850
PRP ALT_SYMBOLS '(SMC_L_287X260_V1_H197)' 
PRP PARENT_PART_TYPE 'INDUCTOR_2' 
PRP PARENT_PPT 'INDUCTOR_2' 
PRP PARENT_PPT_PART 'INDUCTOR_2-G190-10418-01,1.0UH,20%' 
PRP PART_NAME 'INDUCTOR_2' 
TOP 0 5.597 1.94529 90.0 N 64 0 1
TOP 1 5.597 1.73072 90.0 N 15 0 2
#
# CMP 15
CMP 9 4.435 3.575 0.0 N Q1 ??? ;0=1,1=0.043700
PRP REUSE_ID '4' 
PRP ALT_SYMBOLS '(SOT23_V1_H044)' 
PRP PARENT_PART_TYPE 'POWERMOS_3P_NCH_V1' 
PRP PARENT_PPT 'POWERMOS_3P_NCH_V1' 
PRP PARENT_PPT_PART 'POWERMOS_3P_NCH_V1-G121-10200-01' 
PRP PART_NAME 'POWERMOS_3P_NCH_V1' 
TOP 0 4.398 3.5315 0.0 N 245 0 1
TOP 1 4.472 3.5315 0.0 N 2 26 2
TOP 2 4.435 3.6185 0.0 N 246 1 3
#
# CMP 16
CMP 11 4.97 1.54 0.0 N TP62 ??? ;0=2
PRP SCH_MODIFIED_PART 'TRUE' 
PRP PARENT_PART_TYPE 'TP_PIONT' 
PRP PARENT_PPT 'TP_PIONT' 
PRP PARENT_PPT_PART 'TP_PIONT-TP010CT020B030_PTH' 
PRP PART_NAME 'TP_PIONT' 
TOP 0 4.97 1.54 0.0 N 228 0 1
#
# CMP 17
CMP 11 4.205 0.82 0.0 N TP49 ??? ;0=2
PRP SCH_MODIFIED_PART 'TRUE' 
PRP PARENT_PART_TYPE 'TP_PIONT' 
PRP PARENT_PPT 'TP_PIONT' 
PRP PARENT_PPT_PART 'TP_PIONT-TP010CT020B030_PTH' 
PRP PART_NAME 'TP_PIONT' 
TOP 0 4.205 0.82 0.0 N 342 0 1
#
# CMP 18
CMP 11 5.41 0.96 0.0 N TP46 ??? ;0=2
PRP SCH_MODIFIED_PART 'TRUE' 
PRP PARENT_PART_TYPE 'TP_PIONT' 
PRP PARENT_PPT 'TP_PIONT' 
PRP PARENT_PPT_PART 'TP_PIONT-TP010CT020B030_PTH' 
PRP PART_NAME 'TP_PIONT' 
TOP 0 5.41 0.96 0.0 N 203 0 1
#
# CMP 19
CMP 11 4.82 2.125 0.0 N TP45 ??? ;0=2
PRP SCH_MODIFIED_PART 'TRUE' 
PRP PARENT_PART_TYPE 'TP_PIONT' 
PRP PARENT_PPT 'TP_PIONT' 
PRP PARENT_PPT_PART 'TP_PIONT-TP010CT020B030_PTH' 
PRP PART_NAME 'TP_PIONT' 
TOP 0 4.82 2.125 0.0 N 314 0 1
#
# CMP 20
CMP 11 5.3 4.065 0.0 N TP44 ??? ;0=2
PRP SCH_MODIFIED_PART 'TRUE' 
PRP PARENT_PART_TYPE 'TP_PIONT' 
PRP PARENT_PPT 'TP_PIONT' 
PRP PARENT_PPT_PART 'TP_PIONT-TP010CT020B030_PTH' 
PRP PART_NAME 'TP_PIONT' 
TOP 0 5.3 4.065 0.0 N 330 0 1
#
# CMP 21
CMP 11 5.66 3.47 0.0 N TP43 ??? ;0=2
PRP SCH_MODIFIED_PART 'TRUE' 
PRP PARENT_PART_TYPE 'TP_PIONT' 
PRP PARENT_PPT 'TP_PIONT' 
PRP PARENT_PPT_PART 'TP_PIONT-TP010CT020B030_PTH' 
PRP PART_NAME 'TP_PIONT' 
TOP 0 5.66 3.47 0.0 N 83 0 1
#
# CMP 22
CMP 11 0.978 3.918 0.0 N TP42 ??? ;0=2
PRP SCH_MODIFIED_PART 'TRUE' 
PRP PARENT_PART_TYPE 'TP_PIONT' 
PRP PARENT_PPT 'TP_PIONT' 
PRP PARENT_PPT_PART 'TP_PIONT-TP010CT020B030_PTH' 
PRP PART_NAME 'TP_PIONT' 
TOP 0 0.978 3.918 0.0 N 30 0 1
#
# CMP 23
CMP 11 5.765 0.98 0.0 N TP41 ??? ;0=2
PRP SCH_MODIFIED_PART 'TRUE' 
PRP PARENT_PART_TYPE 'TP_PIONT' 
PRP PARENT_PPT 'TP_PIONT' 
PRP PARENT_PPT_PART 'TP_PIONT-TP010CT020B030_PTH' 
PRP PART_NAME 'TP_PIONT' 
TOP 0 5.765 0.98 0.0 N 285 0 1
#
# CMP 24
CMP 11 4.831 2.728 0.0 N TP40 ??? ;0=2
PRP SCH_MODIFIED_PART 'TRUE' 
PRP PARENT_PART_TYPE 'TP_PIONT' 
PRP PARENT_PPT 'TP_PIONT' 
PRP PARENT_PPT_PART 'TP_PIONT-TP010CT020B030_PTH' 
PRP PART_NAME 'TP_PIONT' 
TOP 0 4.831 2.728 0.0 N 284 0 1
#
# CMP 25
CMP 11 5.76 2.465 0.0 N TP39 ??? ;0=2
PRP SCH_MODIFIED_PART 'TRUE' 
PRP PARENT_PART_TYPE 'TP_PIONT' 
PRP PARENT_PPT 'TP_PIONT' 
PRP PARENT_PPT_PART 'TP_PIONT-TP010CT020B030_PTH' 
PRP PART_NAME 'TP_PIONT' 
TOP 0 5.76 2.465 0.0 N 283 0 1
#
# CMP 26
CMP 11 3.745 4.185 0.0 N TP38 ??? ;0=2
PRP SCH_MODIFIED_PART 'TRUE' 
PRP PARENT_PART_TYPE 'TP_PIONT' 
PRP PARENT_PPT 'TP_PIONT' 
PRP PARENT_PPT_PART 'TP_PIONT-TP010CT020B030_PTH' 
PRP PART_NAME 'TP_PIONT' 
TOP 0 3.745 4.185 0.0 N 346 0 1
#
# CMP 27
CMP 11 5.718 3.965 0.0 N TP37 ??? ;0=2
PRP SCH_MODIFIED_PART 'TRUE' 
PRP PARENT_PART_TYPE 'TP_PIONT' 
PRP PARENT_PPT 'TP_PIONT' 
PRP PARENT_PPT_PART 'TP_PIONT-TP010CT020B030_PTH' 
PRP PART_NAME 'TP_PIONT' 
TOP 0 5.718 3.965 0.0 N 293 0 1
#
# CMP 28
CMP 11 5.6 4.01 0.0 N TP36 ??? ;0=2
PRP SCH_MODIFIED_PART 'TRUE' 
PRP PARENT_PART_TYPE 'TP_PIONT' 
PRP PARENT_PPT 'TP_PIONT' 
PRP PARENT_PPT_PART 'TP_PIONT-TP010CT020B030_PTH' 
PRP PART_NAME 'TP_PIONT' 
TOP 0 5.6 4.01 0.0 N 276 0 1
#
# CMP 29
CMP 11 0.635 0.845 0.0 N TP35 ??? ;0=2
PRP SCH_MODIFIED_PART 'TRUE' 
PRP PARENT_PART_TYPE 'TP_PIONT' 
PRP PARENT_PPT 'TP_PIONT' 
PRP PARENT_PPT_PART 'TP_PIONT-TP010CT020B030_PTH' 
PRP PART_NAME 'TP_PIONT' 
TOP 0 0.635 0.845 0.0 N 431 0 1
#
# CMP 30
CMP 11 0.645 1.295 0.0 N TP34 ??? ;0=2
PRP SCH_MODIFIED_PART 'TRUE' 
PRP PARENT_PART_TYPE 'TP_PIONT' 
PRP PARENT_PPT 'TP_PIONT' 
PRP PARENT_PPT_PART 'TP_PIONT-TP010CT020B030_PTH' 
PRP PART_NAME 'TP_PIONT' 
TOP 0 0.645 1.295 0.0 N 428 0 1
#
# CMP 31
CMP 11 0.62 1.995 0.0 N TP33 ??? ;0=2
PRP SCH_MODIFIED_PART 'TRUE' 
PRP PARENT_PART_TYPE 'TP_PIONT' 
PRP PARENT_PPT 'TP_PIONT' 
PRP PARENT_PPT_PART 'TP_PIONT-TP010CT020B030_PTH' 
PRP PART_NAME 'TP_PIONT' 
TOP 0 0.62 1.995 0.0 N 400 0 1
#
# CMP 32
CMP 11 0.647 2.517 0.0 N TP32 ??? ;0=2
PRP SCH_MODIFIED_PART 'TRUE' 
PRP PARENT_PART_TYPE 'TP_PIONT' 
PRP PARENT_PPT 'TP_PIONT' 
PRP PARENT_PPT_PART 'TP_PIONT-TP010CT020B030_PTH' 
PRP PART_NAME 'TP_PIONT' 
TOP 0 0.647 2.517 0.0 N 424 0 1
#
# CMP 33
CMP 11 0.644 0.7 0.0 N TP31 ??? ;0=2
PRP SCH_MODIFIED_PART 'TRUE' 
PRP PARENT_PART_TYPE 'TP_PIONT' 
PRP PARENT_PPT 'TP_PIONT' 
PRP PARENT_PPT_PART 'TP_PIONT-TP010CT020B030_PTH' 
PRP PART_NAME 'TP_PIONT' 
TOP 0 0.644 0.7 0.0 N 444 0 1
#
# CMP 34
CMP 11 0.565 1.13 0.0 N TP30 ??? ;0=2
PRP SCH_MODIFIED_PART 'TRUE' 
PRP PARENT_PART_TYPE 'TP_PIONT' 
PRP PARENT_PPT 'TP_PIONT' 
PRP PARENT_PPT_PART 'TP_PIONT-TP010CT020B030_PTH' 
PRP PART_NAME 'TP_PIONT' 
TOP 0 0.565 1.13 0.0 N 443 0 1
#
# CMP 35
CMP 11 0.545 1.71 0.0 N TP29 ??? ;0=2
PRP SCH_MODIFIED_PART 'TRUE' 
PRP PARENT_PART_TYPE 'TP_PIONT' 
PRP PARENT_PPT 'TP_PIONT' 
PRP PARENT_PPT_PART 'TP_PIONT-TP010CT020B030_PTH' 
PRP PART_NAME 'TP_PIONT' 
TOP 0 0.545 1.71 0.0 N 446 0 1
#
# CMP 36
CMP 11 0.575 2.265 0.0 N TP28 ??? ;0=2
PRP SCH_MODIFIED_PART 'TRUE' 
PRP PARENT_PART_TYPE 'TP_PIONT' 
PRP PARENT_PPT 'TP_PIONT' 
PRP PARENT_PPT_PART 'TP_PIONT-TP010CT020B030_PTH' 
PRP PART_NAME 'TP_PIONT' 
TOP 0 0.575 2.265 0.0 N 445 0 1
#
# CMP 37
CMP 11 5.87 1.84 0.0 N TP27 ??? ;0=2
PRP SCH_MODIFIED_PART 'TRUE' 
PRP PARENT_PART_TYPE 'TP_PIONT' 
PRP PARENT_PPT 'TP_PIONT' 
PRP PARENT_PPT_PART 'TP_PIONT-TP010CT020B030_PTH' 
PRP PART_NAME 'TP_PIONT' 
TOP 0 5.87 1.84 0.0 N 376 0 1
#
# CMP 38
CMP 11 5.955 2.39 0.0 N TP26 ??? ;0=2
PRP SCH_MODIFIED_PART 'TRUE' 
PRP PARENT_PART_TYPE 'TP_PIONT' 
PRP PARENT_PPT 'TP_PIONT' 
PRP PARENT_PPT_PART 'TP_PIONT-TP010CT020B030_PTH' 
PRP PART_NAME 'TP_PIONT' 
TOP 0 5.955 2.39 0.0 N 374 0 1
#
# CMP 39
CMP 11 4.3 3.865 0.0 N TP25 ??? ;0=2
PRP SCH_MODIFIED_PART 'TRUE' 
PRP PARENT_PART_TYPE 'TP_PIONT' 
PRP PARENT_PPT 'TP_PIONT' 
PRP PARENT_PPT_PART 'TP_PIONT-TP010CT020B030_PTH' 
PRP PART_NAME 'TP_PIONT' 
TOP 0 4.3 3.865 0.0 N 93 0 1
#
# CMP 40
CMP 11 0.636 2.915 0.0 N TP24 ??? ;0=2
PRP SCH_MODIFIED_PART 'TRUE' 
PRP PARENT_PART_TYPE 'TP_PIONT' 
PRP PARENT_PPT 'TP_PIONT' 
PRP PARENT_PPT_PART 'TP_PIONT-TP010CT020B030_PTH' 
PRP PART_NAME 'TP_PIONT' 
TOP 0 0.636 2.915 0.0 N 407 0 1
#
# CMP 41
CMP 11 2.017 3.279 90.0 N TP23 ??? ;0=2
PRP SCH_MODIFIED_PART 'TRUE' 
PRP PARENT_PART_TYPE 'TP_PIONT' 
PRP PARENT_PPT 'TP_PIONT' 
PRP PARENT_PPT_PART 'TP_PIONT-TP010CT020B030_PTH' 
PRP PART_NAME 'TP_PIONT' 
TOP 0 2.017 3.279 90.0 N 472 0 1
#
# CMP 42
CMP 11 5.8 1.048 0.0 N TP22 ??? ;0=2
PRP SCH_MODIFIED_PART 'TRUE' 
PRP PARENT_PART_TYPE 'TP_PIONT' 
PRP PARENT_PPT 'TP_PIONT' 
PRP PARENT_PPT_PART 'TP_PIONT-TP010CT020B030_PTH' 
PRP PART_NAME 'TP_PIONT' 
TOP 0 5.8 1.048 0.0 N 473 0 1
#
# CMP 43
CMP 11 3.37 3.44 0.0 N TP21 ??? ;0=2
PRP SCH_MODIFIED_PART 'TRUE' 
PRP PARENT_PART_TYPE 'TP_PIONT' 
PRP PARENT_PPT 'TP_PIONT' 
PRP PARENT_PPT_PART 'TP_PIONT-TP010CT020B030_PTH' 
PRP PART_NAME 'TP_PIONT' 
TOP 0 3.37 3.44 0.0 N 291 0 1
#
# CMP 44
CMP 11 0.755 0.62 0.0 N TP20 ??? ;0=2
PRP SCH_MODIFIED_PART 'TRUE' 
PRP PARENT_PART_TYPE 'TP_PIONT' 
PRP PARENT_PPT 'TP_PIONT' 
PRP PARENT_PPT_PART 'TP_PIONT-TP010CT020B030_PTH' 
PRP PART_NAME 'TP_PIONT' 
TOP 0 0.755 0.62 0.0 N 212 1 1
#
# CMP 45
CMP 11 3.445 2.65 0.0 N TP19 ??? ;0=2
PRP SCH_MODIFIED_PART 'TRUE' 
PRP PARENT_PART_TYPE 'TP_PIONT' 
PRP PARENT_PPT 'TP_PIONT' 
PRP PARENT_PPT_PART 'TP_PIONT-TP010CT020B030_PTH' 
PRP PART_NAME 'TP_PIONT' 
TOP 0 3.445 2.65 0.0 N 211 0 1
#
# CMP 46
CMP 11 3.375 2.65 0.0 N TP18 ??? ;0=2
PRP SCH_MODIFIED_PART 'TRUE' 
PRP PARENT_PART_TYPE 'TP_PIONT' 
PRP PARENT_PPT 'TP_PIONT' 
PRP PARENT_PPT_PART 'TP_PIONT-TP010CT020B030_PTH' 
PRP PART_NAME 'TP_PIONT' 
TOP 0 3.375 2.65 0.0 N 379 0 1
#
# CMP 47
CMP 11 3.305 2.65 0.0 N TP17 ??? ;0=2
PRP SCH_MODIFIED_PART 'TRUE' 
PRP PARENT_PART_TYPE 'TP_PIONT' 
PRP PARENT_PPT 'TP_PIONT' 
PRP PARENT_PPT_PART 'TP_PIONT-TP010CT020B030_PTH' 
PRP PART_NAME 'TP_PIONT' 
TOP 0 3.305 2.65 0.0 N 533 0 1
#
# CMP 48
CMP 11 3.235 2.63 0.0 N TP16 ??? ;0=2
PRP SCH_MODIFIED_PART 'TRUE' 
PRP PARENT_PART_TYPE 'TP_PIONT' 
PRP PARENT_PPT 'TP_PIONT' 
PRP PARENT_PPT_PART 'TP_PIONT-TP010CT020B030_PTH' 
PRP PART_NAME 'TP_PIONT' 
TOP 0 3.235 2.63 0.0 N 372 0 1
#
# CMP 49
CMP 11 4.67 3.555 0.0 N TP15 ??? ;0=2
PRP SCH_MODIFIED_PART 'TRUE' 
PRP PARENT_PART_TYPE 'TP_PIONT' 
PRP PARENT_PPT 'TP_PIONT' 
PRP PARENT_PPT_PART 'TP_PIONT-TP010CT020B030_PTH' 
PRP PART_NAME 'TP_PIONT' 
TOP 0 4.67 3.555 0.0 N 241 0 1
#
# CMP 50
CMP 11 3.95 3.82 0.0 N TP14 ??? ;0=2
PRP SCH_MODIFIED_PART 'TRUE' 
PRP PARENT_PART_TYPE 'TP_PIONT' 
PRP PARENT_PPT 'TP_PIONT' 
PRP PARENT_PPT_PART 'TP_PIONT-TP010CT020B030_PTH' 
PRP PART_NAME 'TP_PIONT' 
TOP 0 3.95 3.82 0.0 N 482 1 1
#
# CMP 51
CMP 11 4.08 3.27 0.0 N TP13 ??? ;0=2
PRP SCH_MODIFIED_PART 'TRUE' 
PRP PARENT_PART_TYPE 'TP_PIONT' 
PRP PARENT_PPT 'TP_PIONT' 
PRP PARENT_PPT_PART 'TP_PIONT-TP010CT020B030_PTH' 
PRP PART_NAME 'TP_PIONT' 
TOP 0 4.08 3.27 0.0 N 488 3 1
#
# CMP 52
CMP 11 4.795 0.925 0.0 N TP12 ??? ;0=2
PRP SCH_MODIFIED_PART 'TRUE' 
PRP PARENT_PART_TYPE 'TP_PIONT' 
PRP PARENT_PPT 'TP_PIONT' 
PRP PARENT_PPT_PART 'TP_PIONT-TP010CT020B030_PTH' 
PRP PART_NAME 'TP_PIONT' 
TOP 0 4.795 0.925 0.0 N 512 1 1
#
# CMP 53
CMP 11 0.995 3.7 0.0 N TP11 ??? ;0=2
PRP SCH_MODIFIED_PART 'TRUE' 
PRP PARENT_PART_TYPE 'TP_PIONT' 
PRP PARENT_PPT 'TP_PIONT' 
PRP PARENT_PPT_PART 'TP_PIONT-TP010CT020B030_PTH' 
PRP PART_NAME 'TP_PIONT' 
TOP 0 0.995 3.7 0.0 N 245 1 1
#
# CMP 54
CMP 11 5.345 2.536 180.0 N TP56 ??? ;0=2
PRP SCH_MODIFIED_PART 'TRUE' 
PRP PARENT_PART_TYPE 'TP_PIONT' 
PRP PARENT_PPT 'TP_PIONT' 
PRP PARENT_PPT_PART 'TP_PIONT-TP010CT020B030_PTH' 
PRP PART_NAME 'TP_PIONT' 
TOP 0 5.345 2.536 180.0 N 16 1 1
#
# CMP 55
CMP 11 3.655 2.795 270.0 N TP55 ??? ;0=2
PRP SCH_MODIFIED_PART 'TRUE' 
PRP PARENT_PART_TYPE 'TP_PIONT' 
PRP PARENT_PPT 'TP_PIONT' 
PRP PARENT_PPT_PART 'TP_PIONT-TP010CT020B030_PTH' 
PRP PART_NAME 'TP_PIONT' 
TOP 0 3.655 2.795 270.0 N 14 0 1
#
# CMP 56
CMP 11 3.69 4.135 180.0 N TP59 ??? ;0=2
PRP REUSE_ID '8' 
PRP SCH_MODIFIED_PART 'TRUE' 
PRP PARENT_PART_TYPE 'TP_PIONT' 
PRP PARENT_PPT 'TP_PIONT' 
PRP PARENT_PPT_PART 'TP_PIONT-TP010CT020B030_PTH' 
PRP PART_NAME 'TP_PIONT' 
TOP 0 3.69 4.135 180.0 N 79 0 1
#
# CMP 57
CMP 11 3.58 2.615 0.0 N TP58 ??? ;0=2
PRP SCH_MODIFIED_PART 'TRUE' 
PRP PARENT_PART_TYPE 'TP_PIONT' 
PRP PARENT_PPT 'TP_PIONT' 
PRP PARENT_PPT_PART 'TP_PIONT-TP010CT020B030_PTH' 
PRP PART_NAME 'TP_PIONT' 
TOP 0 3.58 2.615 0.0 N 1 10 1
#
# CMP 58
CMP 11 4.29 2.74 0.0 N TP53 ??? ;0=2
PRP SCH_MODIFIED_PART 'TRUE' 
PRP PARENT_PART_TYPE 'TP_PIONT' 
PRP PARENT_PPT 'TP_PIONT' 
PRP PARENT_PPT_PART 'TP_PIONT-TP010CT020B030_PTH' 
PRP PART_NAME 'TP_PIONT' 
TOP 0 4.29 2.74 0.0 N 19 0 1
#
# CMP 59
CMP 11 5.445 0.795 0.0 N TP57 ??? ;0=2
PRP SCH_MODIFIED_PART 'TRUE' 
PRP PARENT_PART_TYPE 'TP_PIONT' 
PRP PARENT_PPT 'TP_PIONT' 
PRP PARENT_PPT_PART 'TP_PIONT-TP010CT020B030_PTH' 
PRP PART_NAME 'TP_PIONT' 
TOP 0 5.445 0.795 0.0 N 9 0 1
#
# CMP 60
CMP 11 4.915 1.485 0.0 N TP139 ??? ;0=2
PRP SCH_MODIFIED_PART 'TRUE' 
PRP PARENT_PART_TYPE 'TP_PIONT' 
PRP PARENT_PPT 'TP_PIONT' 
PRP PARENT_PPT_PART 'TP_PIONT-TP010CT020B030_PTH' 
PRP PART_NAME 'TP_PIONT' 
TOP 0 4.915 1.485 0.0 N 545 0 1
#
# CMP 61
CMP 11 5.035 1.49 0.0 N TP138 ??? ;0=2
PRP SCH_MODIFIED_PART 'TRUE' 
PRP PARENT_PART_TYPE 'TP_PIONT' 
PRP PARENT_PPT 'TP_PIONT' 
PRP PARENT_PPT_PART 'TP_PIONT-TP010CT020B030_PTH' 
PRP PART_NAME 'TP_PIONT' 
TOP 0 5.035 1.49 0.0 N 544 0 1
#
# CMP 62
CMP 11 4.73807 1.50879 0.0 N TP133 ??? ;0=2
PRP SCH_MODIFIED_PART 'TRUE' 
PRP PARENT_PART_TYPE 'TP_PIONT' 
PRP PARENT_PPT 'TP_PIONT' 
PRP PARENT_PPT_PART 'TP_PIONT-TP010CT020B030_PTH' 
PRP PART_NAME 'TP_PIONT' 
TOP 0 4.73807 1.50879 0.0 N 539 0 1
#
# CMP 63
CMP 11 4.61996 1.6269 0.0 N TP140 ??? ;0=2
PRP SCH_MODIFIED_PART 'TRUE' 
PRP PARENT_PART_TYPE 'TP_PIONT' 
PRP PARENT_PPT 'TP_PIONT' 
PRP PARENT_PPT_PART 'TP_PIONT-TP010CT020B030_PTH' 
PRP PART_NAME 'TP_PIONT' 
TOP 0 4.61996 1.6269 0.0 N 546 0 1
#
# CMP 64
CMP 11 4.65933 1.6269 0.0 N TP141 ??? ;0=2
PRP SCH_MODIFIED_PART 'TRUE' 
PRP PARENT_PART_TYPE 'TP_PIONT' 
PRP PARENT_PPT 'TP_PIONT' 
PRP PARENT_PPT_PART 'TP_PIONT-TP010CT020B030_PTH' 
PRP PART_NAME 'TP_PIONT' 
TOP 0 4.65933 1.6269 0.0 N 547 0 1
#
# CMP 65
CMP 11 3.385 2.135 180.0 N TP61 ??? ;0=2
PRP SCH_MODIFIED_PART 'TRUE' 
PRP PARENT_PART_TYPE 'TP_PIONT' 
PRP PARENT_PPT 'TP_PIONT' 
PRP PARENT_PPT_PART 'TP_PIONT-TP010CT020B030_PTH' 
PRP PART_NAME 'TP_PIONT' 
TOP 0 3.385 2.135 180.0 N 569 0 1
#
# CMP 66
CMP 11 0.78 3.305 0.0 N TP5 ??? ;0=2
PRP SCH_MODIFIED_PART 'TRUE' 
PRP PARENT_PART_TYPE 'TP_PIONT' 
PRP PARENT_PPT 'TP_PIONT' 
PRP PARENT_PPT_PART 'TP_PIONT-TP010CT020B030_PTH' 
PRP PART_NAME 'TP_PIONT' 
TOP 0 0.78 3.305 0.0 N 567 1 1
#
# CMP 67
CMP 11 0.71 3.305 90.0 N TP4 ??? ;0=2
PRP SCH_MODIFIED_PART 'TRUE' 
PRP PARENT_PART_TYPE 'TP_PIONT' 
PRP PARENT_PPT 'TP_PIONT' 
PRP PARENT_PPT_PART 'TP_PIONT-TP010CT020B030_PTH' 
PRP PART_NAME 'TP_PIONT' 
TOP 0 0.71 3.305 90.0 N 132 5 1
#
# CMP 68
CMP 11 0.875 2.955 0.0 N TP7 ??? ;0=2
PRP SCH_MODIFIED_PART 'TRUE' 
PRP PARENT_PART_TYPE 'TP_PIONT' 
PRP PARENT_PPT 'TP_PIONT' 
PRP PARENT_PPT_PART 'TP_PIONT-TP010CT020B030_PTH' 
PRP PART_NAME 'TP_PIONT' 
TOP 0 0.875 2.955 0.0 N 570 1 1
#
# CMP 69
CMP 11 0.95 2.915 270.0 N TP10 ??? ;0=2
PRP SCH_MODIFIED_PART 'TRUE' 
PRP PARENT_PART_TYPE 'TP_PIONT' 
PRP PARENT_PPT 'TP_PIONT' 
PRP PARENT_PPT_PART 'TP_PIONT-TP010CT020B030_PTH' 
PRP PART_NAME 'TP_PIONT' 
TOP 0 0.95 2.915 270.0 N 537 1 1
#
# CMP 70
CMP 11 4.73807 1.54816 270.0 N TP132 ??? ;0=2
PRP SCH_MODIFIED_PART 'TRUE' 
PRP PARENT_PART_TYPE 'TP_PIONT' 
PRP PARENT_PPT 'TP_PIONT' 
PRP PARENT_PPT_PART 'TP_PIONT-TP010CT020B030_PTH' 
PRP PART_NAME 'TP_PIONT' 
TOP 0 4.73807 1.54816 270.0 N 538 0 1
#
# CMP 71
CMP 11 3.32 3.015 270.0 N TP1 ??? ;0=2
PRP SCH_MODIFIED_PART 'TRUE' 
PRP PARENT_PART_TYPE 'TP_PIONT' 
PRP PARENT_PPT 'TP_PIONT' 
PRP PARENT_PPT_PART 'TP_PIONT-TP010CT020B030_PTH' 
PRP PART_NAME 'TP_PIONT' 
TOP 0 3.32 3.015 270.0 N 399 0 1
#
# CMP 72
CMP 11 3.24 3.01 90.0 N TP2 ??? ;0=2
PRP SCH_MODIFIED_PART 'TRUE' 
PRP PARENT_PART_TYPE 'TP_PIONT' 
PRP PARENT_PPT 'TP_PIONT' 
PRP PARENT_PPT_PART 'TP_PIONT-TP010CT020B030_PTH' 
PRP PART_NAME 'TP_PIONT' 
TOP 0 3.24 3.01 90.0 N 408 0 1
#
# CMP 73
CMP 11 5.58 1.615 0.0 N TP54 ??? ;0=2
PRP SCH_MODIFIED_PART 'TRUE' 
PRP PARENT_PART_TYPE 'TP_PIONT' 
PRP PARENT_PPT 'TP_PIONT' 
PRP PARENT_PPT_PART 'TP_PIONT-TP010CT020B030_PTH' 
PRP PART_NAME 'TP_PIONT' 
TOP 0 5.58 1.615 0.0 N 15 1 1
#
# CMP 74
CMP 11 4.91 1.54 0.0 N TP137 ??? ;0=2
PRP SCH_MODIFIED_PART 'TRUE' 
PRP PARENT_PART_TYPE 'TP_PIONT' 
PRP PARENT_PPT 'TP_PIONT' 
PRP PARENT_PPT_PART 'TP_PIONT-TP010CT020B030_PTH' 
PRP PART_NAME 'TP_PIONT' 
TOP 0 4.91 1.54 0.0 N 543 0 1
#
# CMP 75
CMP 11 4.975 1.485 0.0 N TP135 ??? ;0=2
PRP SCH_MODIFIED_PART 'TRUE' 
PRP PARENT_PART_TYPE 'TP_PIONT' 
PRP PARENT_PPT 'TP_PIONT' 
PRP PARENT_PPT_PART 'TP_PIONT-TP010CT020B030_PTH' 
PRP PART_NAME 'TP_PIONT' 
TOP 0 4.975 1.485 0.0 N 541 0 1
#
# CMP 76
CMP 11 4.85 1.54 0.0 N TP136 ??? ;0=2
PRP SCH_MODIFIED_PART 'TRUE' 
PRP PARENT_PART_TYPE 'TP_PIONT' 
PRP PARENT_PPT 'TP_PIONT' 
PRP PARENT_PPT_PART 'TP_PIONT-TP010CT020B030_PTH' 
PRP PART_NAME 'TP_PIONT' 
TOP 0 4.85 1.54 0.0 N 542 0 1
#
# CMP 77
CMP 11 5.03 1.55 90.0 N TP134 ??? ;0=2
PRP SCH_MODIFIED_PART 'TRUE' 
PRP PARENT_PART_TYPE 'TP_PIONT' 
PRP PARENT_PPT 'TP_PIONT' 
PRP PARENT_PPT_PART 'TP_PIONT-TP010CT020B030_PTH' 
PRP PART_NAME 'TP_PIONT' 
TOP 0 5.03 1.55 90.0 N 540 0 1
#
# CMP 78
CMP 11 0.795 3.085 0.0 N TP6 ??? ;0=2
PRP SCH_MODIFIED_PART 'TRUE' 
PRP PARENT_PART_TYPE 'TP_PIONT' 
PRP PARENT_PPT 'TP_PIONT' 
PRP PARENT_PPT_PART 'TP_PIONT-TP010CT020B030_PTH' 
PRP PART_NAME 'TP_PIONT' 
TOP 0 0.795 3.085 0.0 N 568 1 1
#
# CMP 79
CMP 11 0.885 3.03 270.0 N TP8 ??? ;0=2
PRP SCH_MODIFIED_PART 'TRUE' 
PRP PARENT_PART_TYPE 'TP_PIONT' 
PRP PARENT_PPT 'TP_PIONT' 
PRP PARENT_PPT_PART 'TP_PIONT-TP010CT020B030_PTH' 
PRP PART_NAME 'TP_PIONT' 
TOP 0 0.885 3.03 270.0 N 572 1 1
#
# CMP 80
CMP 11 1.535 3.105 90.0 N TP3 ??? ;0=2
PRP SCH_MODIFIED_PART 'TRUE' 
PRP PARENT_PART_TYPE 'TP_PIONT' 
PRP PARENT_PPT 'TP_PIONT' 
PRP PARENT_PPT_PART 'TP_PIONT-TP010CT020B030_PTH' 
PRP PART_NAME 'TP_PIONT' 
TOP 0 1.535 3.105 90.0 N 88 5 1
#
# CMP 81
CMP 11 0.945 2.99 0.0 N TP9 ??? ;0=2
PRP SCH_MODIFIED_PART 'TRUE' 
PRP PARENT_PART_TYPE 'TP_PIONT' 
PRP PARENT_PPT 'TP_PIONT' 
PRP PARENT_PPT_PART 'TP_PIONT-TP010CT020B030_PTH' 
PRP PART_NAME 'TP_PIONT' 
TOP 0 0.945 2.99 0.0 N 573 1 1
#
# CMP 82
CMP 11 3.9 2.325 270.0 N TP78 ??? ;0=2
PRP SCH_MODIFIED_PART 'TRUE' 
PRP PARENT_PART_TYPE 'TP_PIONT' 
PRP PARENT_PPT 'TP_PIONT' 
PRP PARENT_PPT_PART 'TP_PIONT-TP010CT020B030_PTH' 
PRP PART_NAME 'TP_PIONT' 
TOP 0 3.9 2.325 270.0 N 571 0 1
#
# CMP 83
CMP 11 3.83 2.325 270.0 N TP180 ??? ;0=2
PRP SCH_MODIFIED_PART 'TRUE' 
PRP PARENT_PART_TYPE 'TP_PIONT' 
PRP PARENT_PPT 'TP_PIONT' 
PRP PARENT_PPT_PART 'TP_PIONT-TP010CT020B030_PTH' 
PRP PART_NAME 'TP_PIONT' 
TOP 0 3.83 2.325 270.0 N 548 0 1
#
# CMP 84
CMP 11 3.75 2.1 0.0 N TP181 ??? ;0=2
PRP SCH_MODIFIED_PART 'TRUE' 
PRP PARENT_PART_TYPE 'TP_PIONT' 
PRP PARENT_PPT 'TP_PIONT' 
PRP PARENT_PPT_PART 'TP_PIONT-TP010CT020B030_PTH' 
PRP PART_NAME 'TP_PIONT' 
TOP 0 3.75 2.1 0.0 N 549 0 1
#
# CMP 85
CMP 11 3.8 2.1 0.0 N TP182 ??? ;0=2
PRP SCH_MODIFIED_PART 'TRUE' 
PRP PARENT_PART_TYPE 'TP_PIONT' 
PRP PARENT_PPT 'TP_PIONT' 
PRP PARENT_PPT_PART 'TP_PIONT-TP010CT020B030_PTH' 
PRP PART_NAME 'TP_PIONT' 
TOP 0 3.8 2.1 0.0 N 550 0 1
#
# CMP 86
CMP 11 4.149 2.298 0.0 N TP183 ??? ;0=2
PRP SCH_MODIFIED_PART 'TRUE' 
PRP PARENT_PART_TYPE 'TP_PIONT' 
PRP PARENT_PPT 'TP_PIONT' 
PRP PARENT_PPT_PART 'TP_PIONT-TP010CT020B030_PTH' 
PRP PART_NAME 'TP_PIONT' 
TOP 0 4.149 2.298 0.0 N 551 0 1
#
# CMP 87
CMP 11 4.161 2.354 0.0 N TP184 ??? ;0=2
PRP SCH_MODIFIED_PART 'TRUE' 
PRP PARENT_PART_TYPE 'TP_PIONT' 
PRP PARENT_PPT 'TP_PIONT' 
PRP PARENT_PPT_PART 'TP_PIONT-TP010CT020B030_PTH' 
PRP PART_NAME 'TP_PIONT' 
TOP 0 4.161 2.354 0.0 N 552 0 1
#
# CMP 88
CMP 11 4.23 2.354 0.0 N TP185 ??? ;0=2
PRP SCH_MODIFIED_PART 'TRUE' 
PRP PARENT_PART_TYPE 'TP_PIONT' 
PRP PARENT_PPT 'TP_PIONT' 
PRP PARENT_PPT_PART 'TP_PIONT-TP010CT020B030_PTH' 
PRP PART_NAME 'TP_PIONT' 
TOP 0 4.23 2.354 0.0 N 553 0 1
#
# CMP 89
CMP 11 3.94 2.235 0.0 N TP186 ??? ;0=2
PRP SCH_MODIFIED_PART 'TRUE' 
PRP PARENT_PART_TYPE 'TP_PIONT' 
PRP PARENT_PPT 'TP_PIONT' 
PRP PARENT_PPT_PART 'TP_PIONT-TP010CT020B030_PTH' 
PRP PART_NAME 'TP_PIONT' 
TOP 0 3.94 2.235 0.0 N 554 0 1
#
# CMP 90
CMP 11 4.205 2.295 0.0 N TP187 ??? ;0=2
PRP SCH_MODIFIED_PART 'TRUE' 
PRP PARENT_PART_TYPE 'TP_PIONT' 
PRP PARENT_PPT 'TP_PIONT' 
PRP PARENT_PPT_PART 'TP_PIONT-TP010CT020B030_PTH' 
PRP PART_NAME 'TP_PIONT' 
TOP 0 4.205 2.295 0.0 N 555 0 1
#
# CMP 91
CMP 11 4.254 2.296 0.0 N TP188 ??? ;0=2
PRP SCH_MODIFIED_PART 'TRUE' 
PRP PARENT_PART_TYPE 'TP_PIONT' 
PRP PARENT_PPT 'TP_PIONT' 
PRP PARENT_PPT_PART 'TP_PIONT-TP010CT020B030_PTH' 
PRP PART_NAME 'TP_PIONT' 
TOP 0 4.254 2.296 0.0 N 556 0 1
#
# CMP 92
CMP 11 4.768 1.207 270.0 N TP193 ??? ;0=2
PRP SCH_MODIFIED_PART 'TRUE' 
PRP PARENT_PART_TYPE 'TP_PIONT' 
PRP PARENT_PPT 'TP_PIONT' 
PRP PARENT_PPT_PART 'TP_PIONT-TP010CT020B030_PTH' 
PRP PART_NAME 'TP_PIONT' 
TOP 0 4.768 1.207 270.0 N 557 0 1
#
# CMP 93
CMP 11 4.828 1.103 270.0 N TP194 ??? ;0=2
PRP SCH_MODIFIED_PART 'TRUE' 
PRP PARENT_PART_TYPE 'TP_PIONT' 
PRP PARENT_PPT 'TP_PIONT' 
PRP PARENT_PPT_PART 'TP_PIONT-TP010CT020B030_PTH' 
PRP PART_NAME 'TP_PIONT' 
TOP 0 4.828 1.103 270.0 N 558 0 1
#
# CMP 94
CMP 11 4.15 1.235 270.0 N TP195 ??? ;0=2
PRP SCH_MODIFIED_PART 'TRUE' 
PRP PARENT_PART_TYPE 'TP_PIONT' 
PRP PARENT_PPT 'TP_PIONT' 
PRP PARENT_PPT_PART 'TP_PIONT-TP010CT020B030_PTH' 
PRP PART_NAME 'TP_PIONT' 
TOP 0 4.15 1.235 270.0 N 559 0 1
#
# CMP 95
CMP 11 4.185 1.17 270.0 N TP196 ??? ;0=2
PRP SCH_MODIFIED_PART 'TRUE' 
PRP PARENT_PART_TYPE 'TP_PIONT' 
PRP PARENT_PPT 'TP_PIONT' 
PRP PARENT_PPT_PART 'TP_PIONT-TP010CT020B030_PTH' 
PRP PART_NAME 'TP_PIONT' 
TOP 0 4.185 1.17 270.0 N 560 0 1
#
# CMP 96
CMP 11 4.83 1.33 270.0 N TP199 ??? ;0=2
PRP SCH_MODIFIED_PART 'TRUE' 
PRP PARENT_PART_TYPE 'TP_PIONT' 
PRP PARENT_PPT 'TP_PIONT' 
PRP PARENT_PPT_PART 'TP_PIONT-TP010CT020B030_PTH' 
PRP PART_NAME 'TP_PIONT' 
TOP 0 4.83 1.33 270.0 N 561 0 1
#
# CMP 97
CMP 11 4.22 1.235 270.0 N TP200 ??? ;0=2
PRP SCH_MODIFIED_PART 'TRUE' 
PRP PARENT_PART_TYPE 'TP_PIONT' 
PRP PARENT_PPT 'TP_PIONT' 
PRP PARENT_PPT_PART 'TP_PIONT-TP010CT020B030_PTH' 
PRP PART_NAME 'TP_PIONT' 
TOP 0 4.22 1.235 270.0 N 562 0 1
#
# CMP 98
CMP 11 4.816 1.258 270.0 N TP201 ??? ;0=2
PRP SCH_MODIFIED_PART 'TRUE' 
PRP PARENT_PART_TYPE 'TP_PIONT' 
PRP PARENT_PPT 'TP_PIONT' 
PRP PARENT_PPT_PART 'TP_PIONT-TP010CT020B030_PTH' 
PRP PART_NAME 'TP_PIONT' 
TOP 0 4.816 1.258 270.0 N 563 0 1
#
# CMP 99
CMP 11 4.665 1.104 270.0 N TP202 ??? ;0=2
PRP SCH_MODIFIED_PART 'TRUE' 
PRP PARENT_PART_TYPE 'TP_PIONT' 
PRP PARENT_PPT 'TP_PIONT' 
PRP PARENT_PPT_PART 'TP_PIONT-TP010CT020B030_PTH' 
PRP PART_NAME 'TP_PIONT' 
TOP 0 4.665 1.104 270.0 N 564 0 1
#
# CMP 100
CMP 11 4.712 1.157 270.0 N TP203 ??? ;0=2
PRP SCH_MODIFIED_PART 'TRUE' 
PRP PARENT_PART_TYPE 'TP_PIONT' 
PRP PARENT_PPT 'TP_PIONT' 
PRP PARENT_PPT_PART 'TP_PIONT-TP010CT020B030_PTH' 
PRP PART_NAME 'TP_PIONT' 
TOP 0 4.712 1.157 270.0 N 565 0 1
#
# CMP 101
CMP 11 4.29 1.235 270.0 N TP204 ??? ;0=2
PRP SCH_MODIFIED_PART 'TRUE' 
PRP PARENT_PART_TYPE 'TP_PIONT' 
PRP PARENT_PPT 'TP_PIONT' 
PRP PARENT_PPT_PART 'TP_PIONT-TP010CT020B030_PTH' 
PRP PART_NAME 'TP_PIONT' 
TOP 0 4.29 1.235 270.0 N 566 0 1
#
# CMP 102
CMP 11 2.25 3.96 0.0 N TP60 ??? ;0=2
PRP REUSE_ID '1' 
PRP SCH_MODIFIED_PART 'TRUE' 
PRP PARENT_PART_TYPE 'TP_PIONT' 
PRP PARENT_PPT 'TP_PIONT' 
PRP PARENT_PPT_PART 'TP_PIONT-TP010CT020B030_PTH' 
PRP PART_NAME 'TP_PIONT' 
TOP 0 2.25 3.96 0.0 N 13 1 1
#
# CMP 103
CMP 11 5.406 2.346 180.0 N TP52 ??? ;0=2
PRP SCH_MODIFIED_PART 'TRUE' 
PRP PARENT_PART_TYPE 'TP_PIONT' 
PRP PARENT_PPT 'TP_PIONT' 
PRP PARENT_PPT_PART 'TP_PIONT-TP010CT020B030_PTH' 
PRP PART_NAME 'TP_PIONT' 
TOP 0 5.406 2.346 180.0 N 3 0 1
#
# CMP 104
CMP 12 0.755 1.525 180.0 N J9 ??? ;0=1,1=0.383070
PRP HARD_LOCATION 'YES' 
PRP ALT_SYMBOLS '(S_M_H_2X2_S_P100_V3)' 
PRP PARENT_PART_TYPE 'CONN_HDR_2X2_M_S_SMT' 
PRP PARENT_PPT 'CONN_HDR_2X2_M_S_SMT' 
PRP PARENT_PPT_PART 'CONN_HDR_2X2_M_S_SMT-G200-10686-01' 
PRP PART_NAME 'CONN_HDR_2X2_M_S_SMT' 
TOP 0 0.805 1.62756 180.0 N 222 0 1
TOP 1 0.805 1.42244 180.0 N 223 0 2
TOP 2 0.705 1.62756 180.0 N 224 0 3
TOP 3 0.705 1.42244 180.0 N 225 1 4
#
# CMP 105
CMP 12 3.34 2.815 270.0 N J17 ??? ;0=1,1=0.383070
PRP HARD_LOCATION 'YES' 
PRP ALT_SYMBOLS '(S_M_H_2X2_S_P100_V3)' 
PRP PARENT_PART_TYPE 'CONN_HDR_2X2_M_S_SMT' 
PRP PARENT_PPT 'CONN_HDR_2X2_M_S_SMT' 
PRP PARENT_PPT_PART 'CONN_HDR_2X2_M_S_SMT-G200-10686-01' 
PRP PART_NAME 'CONN_HDR_2X2_M_S_SMT' 
TOP 0 3.44256 2.765 270.0 N 211 1 1
TOP 1 3.23744 2.765 270.0 N 2 27 2
TOP 2 3.44256 2.865 270.0 N 212 2 3
TOP 3 3.23744 2.865 270.0 N 2 28 4
#
# CMP 106
CMP 14 0.16039 1.28346 0.0 N J1 ??? ;0=2,1=0.415350
PRP HARD_LOCATION 'YES' 
PRP ALT_SYMBOLS '(P_F_JACK_1P_GH4_RA_P200)' 
PRP PARENT_PART_TYPE 'CONN_JACK_1P_GH4_S_TH' 
PRP PARENT_PPT 'CONN_JACK_1P_GH4_S_TH' 
PRP PARENT_PPT_PART 'CONN_JACK_1P_GH4_S_TH-G200-13091-01,2081680-1' 
PRP PART_NAME 'CONN_JACK_1P_GH4_S_TH' 
TOP 0 0.16039 1.28346 0.0 N 138 0 1
TOP 1 0.06039 1.38346 0.0 N 2 29 GH1
TOP 2 0.26039 1.38346 0.0 N 2 30 GH2
TOP 3 0.06039 1.18346 0.0 N 2 31 GH3
TOP 4 0.26039 1.18346 0.0 N 2 32 GH4
#
# CMP 107
CMP 14 0.16039 0.7126 0.0 N J2 ??? ;0=2,1=0.415350
PRP HARD_LOCATION 'YES' 
PRP ALT_SYMBOLS '(P_F_JACK_1P_GH4_RA_P200)' 
PRP PARENT_PART_TYPE 'CONN_JACK_1P_GH4_S_TH' 
PRP PARENT_PPT 'CONN_JACK_1P_GH4_S_TH' 
PRP PARENT_PPT_PART 'CONN_JACK_1P_GH4_S_TH-G200-13091-01,2081680-1' 
PRP PART_NAME 'CONN_JACK_1P_GH4_S_TH' 
TOP 0 0.16039 0.7126 0.0 N 137 0 1
TOP 1 0.06039 0.8126 0.0 N 2 33 GH1
TOP 2 0.26039 0.8126 0.0 N 2 34 GH2
TOP 3 0.06039 0.6126 0.0 N 2 35 GH3
TOP 4 0.26039 0.6126 0.0 N 2 36 GH4
#
# CMP 108
CMP 14 0.16039 2.4252 0.0 N J3 ??? ;0=2,1=0.415350
PRP HARD_LOCATION 'YES' 
PRP ALT_SYMBOLS '(P_F_JACK_1P_GH4_RA_P200)' 
PRP PARENT_PART_TYPE 'CONN_JACK_1P_GH4_S_TH' 
PRP PARENT_PPT 'CONN_JACK_1P_GH4_S_TH' 
PRP PARENT_PPT_PART 'CONN_JACK_1P_GH4_S_TH-G200-13091-01,2081680-1' 
PRP PART_NAME 'CONN_JACK_1P_GH4_S_TH' 
TOP 0 0.16039 2.4252 0.0 N 136 0 1
TOP 1 0.06039 2.5252 0.0 N 2 37 GH1
TOP 2 0.26039 2.5252 0.0 N 2 38 GH2
TOP 3 0.06039 2.3252 0.0 N 2 39 GH3
TOP 4 0.26039 2.3252 0.0 N 2 40 GH4
#
# CMP 109
CMP 14 0.16039 1.85433 0.0 N J4 ??? ;0=2,1=0.415350
PRP HARD_LOCATION 'YES' 
PRP ALT_SYMBOLS '(P_F_JACK_1P_GH4_RA_P200)' 
PRP PARENT_PART_TYPE 'CONN_JACK_1P_GH4_S_TH' 
PRP PARENT_PPT 'CONN_JACK_1P_GH4_S_TH' 
PRP PARENT_PPT_PART 'CONN_JACK_1P_GH4_S_TH-G200-13091-01,2081680-1' 
PRP PART_NAME 'CONN_JACK_1P_GH4_S_TH' 
TOP 0 0.16039 1.85433 0.0 N 135 0 1
TOP 1 0.06039 1.95433 0.0 N 2 41 GH1
TOP 2 0.26039 1.95433 0.0 N 2 42 GH2
TOP 3 0.06039 1.75433 0.0 N 2 43 GH3
TOP 4 0.26039 1.75433 0.0 N 2 44 GH4
#
# CMP 110
CMP 15 0.05906 1.53937 270.0 N DS14 ??? ;0=1,1=0.033460
PRP HARD_LOCATION 'YES' 
PRP ALT_SYMBOLS '(SMC_DS4_098X039)' 
PRP PARENT_PART_TYPE 'LED_4P_V14' 
PRP PARENT_PPT 'LED_4P_V14' 
PRP PARENT_PPT_PART 'LED_4P_V14-G170-10189-01' 
PRP PART_NAME 'LED_4P_V14' 
TOP 0 0.06874 1.4872 270.0 N 150 0 1
TOP 1 0.08252 1.52264 270.0 N 1 11 2
TOP 2 0.08252 1.5561 270.0 N 151 0 3
TOP 3 0.06874 1.59154 270.0 N 152 0 4
#
# CMP 111
CMP 15 0.05906 2.11024 270.0 N DS17 ??? ;0=1,1=0.033460
PRP HARD_LOCATION 'YES' 
PRP ALT_SYMBOLS '(SMC_DS4_098X039)' 
PRP PARENT_PART_TYPE 'LED_4P_V14' 
PRP PARENT_PPT 'LED_4P_V14' 
PRP PARENT_PPT_PART 'LED_4P_V14-G170-10189-01' 
PRP PART_NAME 'LED_4P_V14' 
TOP 0 0.06874 2.05807 270.0 N 159 0 1
TOP 1 0.08252 2.09351 270.0 N 1 12 2
TOP 2 0.08252 2.12697 270.0 N 160 0 3
TOP 3 0.06874 2.16241 270.0 N 161 0 4
#
# CMP 112
CMP 15 0.05906 0.9685 270.0 N DS15 ??? ;0=1,1=0.033460
PRP HARD_LOCATION 'YES' 
PRP REUSE_ID '3' 
PRP ALT_SYMBOLS '(SMC_DS4_098X039)' 
PRP PARENT_PART_TYPE 'LED_4P_V14' 
PRP PARENT_PPT 'LED_4P_V14' 
PRP PARENT_PPT_PART 'LED_4P_V14-G170-10189-01' 
PRP PART_NAME 'LED_4P_V14' 
TOP 0 0.06874 0.91633 270.0 N 153 0 1
TOP 1 0.08252 0.95177 270.0 N 1 13 2
TOP 2 0.08252 0.98523 270.0 N 154 0 3
TOP 3 0.06874 1.02067 270.0 N 155 0 4
#
# CMP 113
CMP 15 0.05906 3.25197 270.0 N DS18 ??? ;0=1,1=0.033460
PRP HARD_LOCATION 'YES' 
PRP ALT_SYMBOLS '(SMC_DS4_098X039)' 
PRP PARENT_PART_TYPE 'LED_4P_V14' 
PRP PARENT_PPT 'LED_4P_V14' 
PRP PARENT_PPT_PART 'LED_4P_V14-G170-10189-01' 
PRP PART_NAME 'LED_4P_V14' 
TOP 0 0.06874 3.1998 270.0 N 162 0 1
TOP 1 0.08252 3.23524 270.0 N 1 14 2
TOP 2 0.08252 3.2687 270.0 N 163 0 3
TOP 3 0.06874 3.30414 270.0 N 164 0 4
#
# CMP 114
CMP 15 0.05906 2.6811 270.0 N DS16 ??? ;0=1,1=0.033460
PRP HARD_LOCATION 'YES' 
PRP ALT_SYMBOLS '(SMC_DS4_098X039)' 
PRP PARENT_PART_TYPE 'LED_4P_V14' 
PRP PARENT_PPT 'LED_4P_V14' 
PRP PARENT_PPT_PART 'LED_4P_V14-G170-10189-01' 
PRP PART_NAME 'LED_4P_V14' 
TOP 0 0.06874 2.62893 270.0 N 156 0 1
TOP 1 0.08252 2.66437 270.0 N 1 15 2
TOP 2 0.08252 2.69783 270.0 N 157 0 3
TOP 3 0.06874 2.73327 270.0 N 158 0 4
#
# CMP 115
CMP 16 1.68 3.015 0.0 N U41 ??? ;0=1,1=0.039370
PRP ALT_SYMBOLS '(DFN11_118_P0197_TR057X071_VIA,DFN11_118_P0197_TR065X080_AWS)' 
PRP PARENT_PART_TYPE 'ISL80101IRAJZ_DFN10' 
PRP PARENT_PPT 'ISL80101IRAJZ_DFN10' 
PRP PARENT_PPT_PART 'ISL80101IRAJZ_DFN10-G222-10136-01' 
PRP PART_NAME 'ISL80101IRAJZ_DFN10' 
TOP 0 1.62033 3.05438 0.0 N 88 6 1
TOP 1 1.62033 3.03469 0.0 N 88 7 2
TOP 2 1.62033 3.015 0.0 N 516 0 3
TOP 3 1.62033 2.99531 0.0 N 487 0 4
TOP 4 1.62033 2.97562 0.0 N 2 45 5
TOP 5 1.73967 2.97562 0.0 N 87 0 6
TOP 6 1.73967 2.99531 0.0 N 86 0 7
TOP 7 1.73967 3.015 0.0 N 0 16 8
TOP 8 1.73967 3.03469 0.0 N 85 0 9
TOP 9 1.73967 3.05438 0.0 N 85 1 10
TOP 10 1.68 3.015 0.0 N 2 46 11
#
# CMP 116
CMP 16 5.108 2.707 180.0 N U21 ??? ;0=1,1=0.039370
PRP ALT_SYMBOLS '(DFN11_118_P0197_TR057X071_VIA,DFN11_118_P0197_TR065X080_AWS)' 
PRP PARENT_PART_TYPE 'ISL80101IRAJZ_DFN10' 
PRP PARENT_PPT 'ISL80101IRAJZ_DFN10' 
PRP PARENT_PPT_PART 'ISL80101IRAJZ_DFN10-G222-10136-01' 
PRP PART_NAME 'ISL80101IRAJZ_DFN10' 
TOP 0 5.16767 2.66762 180.0 N 16 2 1
TOP 1 5.16767 2.68731 180.0 N 16 3 2
TOP 2 5.16767 2.707 180.0 N 311 0 3
TOP 3 5.16767 2.72669 180.0 N 29 0 4
TOP 4 5.16767 2.74638 180.0 N 2 47 5
TOP 5 5.04833 2.74638 180.0 N 27 0 6
TOP 6 5.04833 2.72669 180.0 N 23 0 7
TOP 7 5.04833 2.707 180.0 N 0 17 8
TOP 8 5.04833 2.68731 180.0 N 22 0 9
TOP 9 5.04833 2.66762 180.0 N 22 1 10
TOP 10 5.108 2.707 180.0 N 2 48 11
#
# CMP 117
CMP 16 5.625 0.679 0.0 N U25 ??? ;0=1,1=0.039370
PRP REUSE_ID '6' 
PRP ALT_SYMBOLS '(DFN11_118_P0197_TR057X071_VIA,DFN11_118_P0197_TR065X080_AWS)' 
PRP PARENT_PART_TYPE 'ISL80101IRAJZ_DFN10' 
PRP PARENT_PPT 'ISL80101IRAJZ_DFN10' 
PRP PARENT_PPT_PART 'ISL80101IRAJZ_DFN10-G222-10136-01' 
PRP PART_NAME 'ISL80101IRAJZ_DFN10' 
TOP 0 5.56533 0.71838 0.0 N 9 1 1
TOP 1 5.56533 0.69869 0.0 N 9 2 2
TOP 2 5.56533 0.679 0.0 N 339 0 3
TOP 3 5.56533 0.65931 0.0 N 37 0 4
TOP 4 5.56533 0.63962 0.0 N 2 49 5
TOP 5 5.68467 0.63962 0.0 N 36 0 6
TOP 6 5.68467 0.65931 0.0 N 31 0 7
TOP 7 5.68467 0.679 0.0 N 0 18 8
TOP 8 5.68467 0.69869 0.0 N 32 0 9
TOP 9 5.68467 0.71838 0.0 N 32 1 10
TOP 10 5.625 0.679 0.0 N 2 50 11
#
# CMP 118
CMP 16 3.912 2.945 270.0 N U20 ??? ;0=1,1=0.039370
PRP REUSE_ID '6' 
PRP ALT_SYMBOLS '(DFN11_118_P0197_TR057X071_VIA,DFN11_118_P0197_TR065X080_AWS)' 
PRP PARENT_PART_TYPE 'ISL80101IRAJZ_DFN10' 
PRP PARENT_PPT 'ISL80101IRAJZ_DFN10' 
PRP PARENT_PPT_PART 'ISL80101IRAJZ_DFN10-G222-10136-01' 
PRP PART_NAME 'ISL80101IRAJZ_DFN10' 
TOP 0 3.87262 2.88533 270.0 N 14 1 1
TOP 1 3.89231 2.88533 270.0 N 14 2 2
TOP 2 3.912 2.88533 270.0 N 310 0 3
TOP 3 3.93169 2.88533 270.0 N 28 0 4
TOP 4 3.95138 2.88533 270.0 N 2 51 5
TOP 5 3.95138 3.00467 270.0 N 26 0 6
TOP 6 3.93169 3.00467 270.0 N 20 0 7
TOP 7 3.912 3.00467 270.0 N 0 19 8
TOP 8 3.89231 3.00467 270.0 N 21 0 9
TOP 9 3.87262 3.00467 270.0 N 21 1 10
TOP 10 3.912 2.945 270.0 N 2 52 11
#
# CMP 119
CMP 17 4.356 2.876 180.0 N U22 ??? ;0=1,1=0.039370
PRP ALT_SYMBOLS '(DFN13_118_P0197_TR071X096_AWS,DFN13_118_P0197_TR071X096_VIA)' 
PRP PARENT_PART_TYPE 'NCP45560IMNTWG_H_DFN12' 
PRP PARENT_PPT 'NCP45560IMNTWG_H_DFN12' 
PRP PARENT_PPT_PART 'NCP45560IMNTWG_H_DFN12-G222-10203-01' 
PRP PART_NAME 'NCP45560IMNTWG_H_DFN12' 
TOP 0 4.41975 2.82429 180.0 N 19 1 1
TOP 1 4.41975 2.84647 180.0 N 33 0 2
TOP 2 4.41975 2.86616 180.0 N 19 2 3
TOP 3 4.41975 2.88584 180.0 N 2 53 4
TOP 4 4.41975 2.90553 180.0 N 38 0 5
TOP 5 4.41975 2.92521 180.0 N 286 0 6
TOP 6 4.29225 2.92521 180.0 N 1 16 7
TOP 7 4.29225 2.90553 180.0 N 1 17 8
TOP 8 4.29225 2.88584 180.0 N 1 18 9
TOP 9 4.29225 2.86616 180.0 N 1 19 10
TOP 10 4.29225 2.84647 180.0 N 1 20 11
TOP 11 4.29225 2.82679 180.0 N 1 21 12
TOP 12 4.356 2.876 180.0 N 19 3 13
#
# CMP 120
CMP 18 4.144 3.992 180.0 N U33 ??? ;0=1,1=0.031500
PRP ALT_SYMBOLS '(QFN29_197_P0197_TR115SQ_V1)' 
PRP PARENT_PART_TYPE 'IS32FL3207_QWLA3_TR_QFN29' 
PRP PARENT_PPT 'IS32FL3207_QWLA3_TR_QFN29' 
PRP PARENT_PPT_PART 'IS32FL3207_QWLA3_TR_QFN29-A223-00002-FB,IS32FL3207-QWLA3-TR' 
PRP PART_NAME 'IS32FL3207_QWLA3_TR_QFN29' 
TOP 0 4.2406 3.93294 180.0 N 93 1 1
TOP 1 4.2391 3.95263 180.0 N 395 0 2
TOP 2 4.2391 3.97231 180.0 N 1 22 3
TOP 3 4.2391 3.992 180.0 N 2 54 4
TOP 4 4.2391 4.01169 180.0 N 394 0 5
TOP 5 4.2391 4.03137 180.0 N 389 0 6
TOP 6 4.2406 4.05106 180.0 N 390 0 7
TOP 7 4.20306 4.0886 180.0 N 448 0 8
TOP 8 4.18337 4.0871 180.0 N 449 0 9
TOP 9 4.16369 4.0871 180.0 N 447 0 10
TOP 10 4.144 4.0871 180.0 N 2 55 11
TOP 11 4.12431 4.0871 180.0 N 451 0 12
TOP 12 4.10463 4.0871 180.0 N 452 0 13
TOP 13 4.08494 4.0886 180.0 N 450 0 14
TOP 14 4.0474 4.05106 180.0 N 454 0 15
TOP 15 4.0489 4.03137 180.0 N 455 0 16
TOP 16 4.0489 4.01169 180.0 N 453 0 17
TOP 17 4.0489 3.992 180.0 N 2 56 18
TOP 18 4.0489 3.97231 180.0 N 457 0 19
TOP 19 4.0489 3.95263 180.0 N 458 0 20
TOP 20 4.0474 3.93294 180.0 N 456 0 21
TOP 21 4.08494 3.8954 180.0 N 460 0 22
TOP 22 4.10463 3.8969 180.0 N 461 0 23
TOP 23 4.12431 3.8969 180.0 N 459 0 24
TOP 24 4.144 3.8969 180.0 N 2 57 25
TOP 25 4.16369 3.8969 180.0 N 0 20 26
TOP 26 4.18337 3.8969 180.0 N 0 21 27
TOP 27 4.20306 3.8954 180.0 N 0 22 28
TOP 28 4.144 3.992 180.0 N 2 58 29
#
# CMP 121
CMP 21 2.68567 1.12143 0.0 N ME8 ??? ;0=2,1=0.000010
PRP SCH_MODIFIED_PART 'TRUE' 
PRP PARENT_PART_TYPE 'MEC_NPTH' 
PRP PARENT_PPT 'MEC_NPTH' 
PRP PARENT_PPT_PART 'MEC_NPTH-MTH100C240N' 
PRP PART_NAME 'MEC_NPTH' 
TOP 0 2.68567 1.12143 0.0 N 0 23 un_1
#
# CMP 122
CMP 21 2.68567 2.55943 0.0 N ME6 ??? ;0=2,1=0.000010
PRP SCH_MODIFIED_PART 'TRUE' 
PRP PARENT_PART_TYPE 'MEC_NPTH' 
PRP PARENT_PPT 'MEC_NPTH' 
PRP PARENT_PPT_PART 'MEC_NPTH-MTH100C240N' 
PRP PART_NAME 'MEC_NPTH' 
TOP 0 2.68567 2.55943 0.0 N 0 24 un_1
#
# CMP 123
CMP 21 1.46067 2.68043 0.0 N ME5 ??? ;0=2,1=0.000010
PRP SCH_MODIFIED_PART 'TRUE' 
PRP PARENT_PART_TYPE 'MEC_NPTH' 
PRP PARENT_PPT 'MEC_NPTH' 
PRP PARENT_PPT_PART 'MEC_NPTH-MTH100C240N' 
PRP PART_NAME 'MEC_NPTH' 
TOP 0 1.46067 2.68043 0.0 N 0 25 un_1
#
# CMP 124
CMP 21 1.43567 1.06043 0.0 N ME7 ??? ;0=2,1=0.000010
PRP SCH_MODIFIED_PART 'TRUE' 
PRP PARENT_PART_TYPE 'MEC_NPTH' 
PRP PARENT_PPT 'MEC_NPTH' 
PRP PARENT_PPT_PART 'MEC_NPTH-MTH100C240N' 
PRP PART_NAME 'MEC_NPTH' 
TOP 0 1.43567 1.06043 0.0 N 0 26 un_1
#
# CMP 125
CMP 22 0.54724 2.4252 90.0 N U15 ??? ;0=1,1=0.035430
PRP HARD_LOCATION 'YES' 
PRP REUSE_ID '5' 
PRP ALT_SYMBOLS '(SOP8_091_P0197_H035)' 
PRP PARENT_PART_TYPE '74HCT2G125DP_TSSOP8' 
PRP PARENT_PPT '74HCT2G125DP_TSSOP8' 
PRP PARENT_PPT_PART '74HCT2G125DP_TSSOP8-G220-00055-01' 
PRP PART_NAME '74HCT2G125DP_TSSOP8' 
TOP 0 0.57676 2.49174 90.0 N 424 1 1
TOP 1 0.55708 2.49174 90.0 N 265 0 2
TOP 2 0.5374 2.49174 90.0 N 435 0 3
TOP 3 0.51772 2.49174 90.0 N 2 59 4
TOP 4 0.51772 2.35866 90.0 N 273 0 5
TOP 5 0.5374 2.35866 90.0 N 273 1 6
TOP 6 0.55708 2.35866 90.0 N 445 1 7
TOP 7 0.57676 2.35866 90.0 N 1 23 8
#
# CMP 126
CMP 22 0.54724 1.85433 90.0 N U16 ??? ;0=1,1=0.035430
PRP HARD_LOCATION 'YES' 
PRP ALT_SYMBOLS '(SOP8_091_P0197_H035)' 
PRP PARENT_PART_TYPE '74HCT2G125DP_TSSOP8' 
PRP PARENT_PPT '74HCT2G125DP_TSSOP8' 
PRP PARENT_PPT_PART '74HCT2G125DP_TSSOP8-G220-00055-01' 
PRP PART_NAME '74HCT2G125DP_TSSOP8' 
TOP 0 0.57676 1.92087 90.0 N 400 1 1
TOP 1 0.55708 1.92087 90.0 N 267 0 2
TOP 2 0.5374 1.92087 90.0 N 437 0 3
TOP 3 0.51772 1.92087 90.0 N 2 60 4
TOP 4 0.51772 1.78779 90.0 N 272 0 5
TOP 5 0.5374 1.78779 90.0 N 272 1 6
TOP 6 0.55708 1.78779 90.0 N 446 1 7
TOP 7 0.57676 1.78779 90.0 N 1 24 8
#
# CMP 127
CMP 22 0.54724 1.28346 90.0 N U13 ??? ;0=1,1=0.035430
PRP HARD_LOCATION 'YES' 
PRP REUSE_ID '8' 
PRP ALT_SYMBOLS '(SOP8_091_P0197_H035)' 
PRP PARENT_PART_TYPE '74HCT2G125DP_TSSOP8' 
PRP PARENT_PPT '74HCT2G125DP_TSSOP8' 
PRP PARENT_PPT_PART '74HCT2G125DP_TSSOP8-G220-00055-01' 
PRP PART_NAME '74HCT2G125DP_TSSOP8' 
TOP 0 0.57676 1.35 90.0 N 428 1 1
TOP 1 0.55708 1.35 90.0 N 297 0 2
TOP 2 0.5374 1.35 90.0 N 429 0 3
TOP 3 0.51772 1.35 90.0 N 2 61 4
TOP 4 0.51772 1.21692 90.0 N 268 0 5
TOP 5 0.5374 1.21692 90.0 N 268 1 6
TOP 6 0.55708 1.21692 90.0 N 443 1 7
TOP 7 0.57676 1.21692 90.0 N 1 25 8
#
# CMP 128
CMP 22 0.54724 0.7126 90.0 N U14 ??? ;0=1,1=0.035430
PRP HARD_LOCATION 'YES' 
PRP REUSE_ID '3' 
PRP ALT_SYMBOLS '(SOP8_091_P0197_H035)' 
PRP PARENT_PART_TYPE '74HCT2G125DP_TSSOP8' 
PRP PARENT_PPT '74HCT2G125DP_TSSOP8' 
PRP PARENT_PPT_PART '74HCT2G125DP_TSSOP8-G220-00055-01' 
PRP PART_NAME '74HCT2G125DP_TSSOP8' 
TOP 0 0.57676 0.77914 90.0 N 431 1 1
TOP 1 0.55708 0.77914 90.0 N 299 0 2
TOP 2 0.5374 0.77914 90.0 N 433 0 3
TOP 3 0.51772 0.77914 90.0 N 2 62 4
TOP 4 0.51772 0.64606 90.0 N 269 0 5
TOP 5 0.5374 0.64606 90.0 N 269 1 6
TOP 6 0.55708 0.64606 90.0 N 444 1 7
TOP 7 0.57676 0.64606 90.0 N 1 26 8
#
# CMP 129
CMP 23 6.40039 0.65354 0.0 N ME12 ??? ;0=2,1=0.000010
PRP SCH_MODIFIED_PART 'TRUE' 
PRP PARENT_PART_TYPE 'MEC_MTH8' 
PRP PARENT_PPT 'MEC_MTH8' 
PRP PARENT_PPT_PART 'MEC_MTH8-MTH125C236N_V8' 
PRP PART_NAME 'MEC_MTH8' 
TOP 0 6.40039 0.75004 0.0 N 2 63 1
TOP 1 6.46863 0.72178 0.0 N 2 64 2
TOP 2 6.49689 0.65354 0.0 N 2 65 3
TOP 3 6.46863 0.5853 0.0 N 2 66 4
TOP 4 6.40039 0.55704 0.0 N 2 67 5
TOP 5 6.33215 0.5853 0.0 N 2 68 6
TOP 6 6.30389 0.65354 0.0 N 2 69 7
TOP 7 6.33215 0.72178 0.0 N 2 70 8
TOP 8 6.40039 0.65354 0.0 N 0 27 un_1
#
# CMP 130
CMP 23 0.29528 3.73031 0.0 N ME9 ??? ;0=2,1=0.000010
PRP SCH_MODIFIED_PART 'TRUE' 
PRP PARENT_PART_TYPE 'MEC_MTH8' 
PRP PARENT_PPT 'MEC_MTH8' 
PRP PARENT_PPT_PART 'MEC_MTH8-MTH125C236N_V8' 
PRP PART_NAME 'MEC_MTH8' 
TOP 0 0.29528 3.82681 0.0 N 2 71 1
TOP 1 0.36352 3.79855 0.0 N 2 72 2
TOP 2 0.39178 3.73031 0.0 N 2 73 3
TOP 3 0.36352 3.66207 0.0 N 2 74 4
TOP 4 0.29528 3.63381 0.0 N 2 75 5
TOP 5 0.22704 3.66207 0.0 N 2 76 6
TOP 6 0.19878 3.73031 0.0 N 2 77 7
TOP 7 0.22704 3.79855 0.0 N 2 78 8
TOP 8 0.29528 3.73031 0.0 N 0 28 un_1
#
# CMP 131
CMP 23 0.29528 0.36811 0.0 N ME10 ??? ;0=2,1=0.000010
PRP SCH_MODIFIED_PART 'TRUE' 
PRP PARENT_PART_TYPE 'MEC_MTH8' 
PRP PARENT_PPT 'MEC_MTH8' 
PRP PARENT_PPT_PART 'MEC_MTH8-MTH125C236N_V8' 
PRP PART_NAME 'MEC_MTH8' 
TOP 0 0.29528 0.46461 0.0 N 2 79 1
TOP 1 0.36352 0.43635 0.0 N 2 80 2
TOP 2 0.39178 0.36811 0.0 N 2 81 3
TOP 3 0.36352 0.29987 0.0 N 2 82 4
TOP 4 0.29528 0.27161 0.0 N 2 83 5
TOP 5 0.22704 0.29987 0.0 N 2 84 6
TOP 6 0.19878 0.36811 0.0 N 2 85 7
TOP 7 0.22704 0.43635 0.0 N 2 86 8
TOP 8 0.29528 0.36811 0.0 N 0 29 un_1
#
# CMP 132
CMP 23 6.40039 4.17835 0.0 N ME11 ??? ;0=2,1=0.000010
PRP SCH_MODIFIED_PART 'TRUE' 
PRP PARENT_PART_TYPE 'MEC_MTH8' 
PRP PARENT_PPT 'MEC_MTH8' 
PRP PARENT_PPT_PART 'MEC_MTH8-MTH125C236N_V8' 
PRP PART_NAME 'MEC_MTH8' 
TOP 0 6.40039 4.27485 0.0 N 2 87 1
TOP 1 6.46863 4.24659 0.0 N 2 88 2
TOP 2 6.49689 4.17835 0.0 N 2 89 3
TOP 3 6.46863 4.11011 0.0 N 2 90 4
TOP 4 6.40039 4.08185 0.0 N 2 91 5
TOP 5 6.33215 4.11011 0.0 N 2 92 6
TOP 6 6.30389 4.17835 0.0 N 2 93 7
TOP 7 6.33215 4.24659 0.0 N 2 94 8
TOP 8 6.40039 4.17835 0.0 N 0 30 un_1
#
# CMP 133
CMP 24 1.014 0.691 0.0 N U7 ??? ;0=1,1=0.039370
PRP HARD_LOCATION 'YES' 
PRP ALT_SYMBOLS '(SOT23_5_H039)' 
PRP PARENT_PART_TYPE 'AT24MAC402_SOT23_5' 
PRP PARENT_PPT 'AT24MAC402_SOT23_5' 
PRP PARENT_PPT_PART 'AT24MAC402_SOT23_5-A221-00002-FB,AT24MAC602-STUM-T' 
PRP PART_NAME 'AT24MAC402_SOT23_5' 
TOP 0 0.9575 0.7284 0.0 N 225 2 1
TOP 1 0.9575 0.691 0.0 N 2 95 2
TOP 2 0.9575 0.6536 0.0 N 410 0 3
TOP 3 1.0705 0.6536 0.0 N 1 27 4
TOP 4 1.0705 0.7284 0.0 N 211 2 5
#
# CMP 134
CMP 25 2.86067 1.04043 0.0 N MAC_PIN4 ??? ;0=2,1=0.023000
PRP ALT_SYMBOLS '(P_NUT_079C100)' 
PRP PARENT_PART_TYPE 'NUT' 
PRP PARENT_PPT 'NUT' 
PRP PARENT_PPT_PART 'NUT-A200-00029-FB' 
PRP PART_NAME 'NUT' 
TOP 0 2.86067 1.04043 0.0 N 2 96 1
#
# CMP 135
CMP 25 2.77867 0.93443 0.0 N MAC_PIN6 ??? ;0=2,1=0.023000
PRP ALT_SYMBOLS '(P_NUT_079C100)' 
PRP PARENT_PART_TYPE 'NUT' 
PRP PARENT_PPT 'NUT' 
PRP PARENT_PPT_PART 'NUT-A200-00029-FB' 
PRP PART_NAME 'NUT' 
TOP 0 2.77867 0.93443 0.0 N 228 1 1
#
# CMP 136
CMP 25 2.65967 0.93443 0.0 N MAC_PIN7 ??? ;0=2,1=0.023000
PRP ALT_SYMBOLS '(P_NUT_079C100)' 
PRP PARENT_PART_TYPE 'NUT' 
PRP PARENT_PPT 'NUT' 
PRP PARENT_PPT_PART 'NUT-A200-00029-FB' 
PRP PART_NAME 'NUT' 
TOP 0 2.65967 0.93443 0.0 N 229 0 1
#
# CMP 137
CMP 25 2.53967 0.93443 0.0 N MAC_PIN8 ??? ;0=2,1=0.023000
PRP ALT_SYMBOLS '(P_NUT_079C100)' 
PRP PARENT_PART_TYPE 'NUT' 
PRP PARENT_PPT 'NUT' 
PRP PARENT_PPT_PART 'NUT-A200-00029-FB' 
PRP PART_NAME 'NUT' 
TOP 0 2.53967 0.93443 0.0 N 230 0 1
#
# CMP 138
CMP 25 1.26067 1.04043 0.0 N MAC_PIN3 ??? ;0=2,1=0.023000
PRP ALT_SYMBOLS '(P_NUT_079C100)' 
PRP PARENT_PART_TYPE 'NUT' 
PRP PARENT_PPT 'NUT' 
PRP PARENT_PPT_PART 'NUT-A200-00029-FB' 
PRP PART_NAME 'NUT' 
TOP 0 1.26067 1.04043 0.0 N 227 0 1
#
# CMP 139
CMP 25 2.86067 2.64043 0.0 N MAC_PIN5 ??? ;0=2,1=0.023000
PRP ALT_SYMBOLS '(P_NUT_079C100)' 
PRP PARENT_PART_TYPE 'NUT' 
PRP PARENT_PPT 'NUT' 
PRP PARENT_PPT_PART 'NUT-A200-00029-FB' 
PRP PART_NAME 'NUT' 
TOP 0 2.86067 2.64043 0.0 N 76 0 1
#
# CMP 140
CMP 25 1.26067 2.64043 0.0 N MAC_PIN1 ??? ;0=2,1=0.023000
PRP ALT_SYMBOLS '(P_NUT_079C100)' 
PRP PARENT_PART_TYPE 'NUT' 
PRP PARENT_PPT 'NUT' 
PRP PARENT_PPT_PART 'NUT-A200-00029-FB' 
PRP PART_NAME 'NUT' 
TOP 0 1.26067 2.64043 0.0 N 226 0 1
#
# CMP 141
CMP 25 1.26067 1.84043 0.0 N MAC_PIN2 ??? ;0=2,1=0.023000
PRP ALT_SYMBOLS '(P_NUT_079C100)' 
PRP PARENT_PART_TYPE 'NUT' 
PRP PARENT_PPT 'NUT' 
PRP PARENT_PPT_PART 'NUT-A200-00029-FB' 
PRP PART_NAME 'NUT' 
TOP 0 1.26067 1.84043 0.0 N 2 97 1
#
# CMP 142
CMP 26 5.99 2.094 270.0 N U27 ??? ;0=1,1=0.039370
PRP ALT_SYMBOLS '(DFN9_098_P0197_TR039X071)' 
PRP PARENT_PART_TYPE 'SHT31A_DIS_B10KS_DFN8' 
PRP PARENT_PPT 'SHT31A_DIS_B10KS_DFN8' 
PRP PARENT_PPT_PART 'SHT31A_DIS_B10KS_DFN8-A222-00001-FB,SHT31A-DIS-B10KS' 
PRP PART_NAME 'SHT31A_DIS_B10KS_DFN8' 
TOP 0 5.96047 2.04418 270.0 N 522 0 1
TOP 1 5.98016 2.04418 270.0 N 524 0 2
TOP 2 5.99984 2.04418 270.0 N 376 1 3
TOP 3 6.01953 2.04418 270.0 N 523 0 4
TOP 4 6.01953 2.14382 270.0 N 71 1 5
TOP 5 5.99984 2.14382 270.0 N 374 1 6
TOP 6 5.98016 2.14382 270.0 N 2 98 7
TOP 7 5.96047 2.14382 270.0 N 2 99 8
TOP 8 5.99 2.094 270.0 N 2 100 9
#
# CMP 143
CMP 27 6.34055 3.50984 90.0 N P3 ??? ;0=2,1=0.459060
PRP HARD_LOCATION 'YES' 
PRP ALT_SYMBOLS '(P_M_H_2X3_NP2_RA_P165_V1)' 
PRP PARENT_PART_TYPE 'CONN_HDR_2X3_M_RA_TH' 
PRP PARENT_PPT 'CONN_HDR_2X3_M_RA_TH' 
PRP PARENT_PPT_PART 'CONN_HDR_2X3_M_RA_TH-G200-12517-01' 
PRP PART_NAME 'CONN_HDR_2X3_M_RA_TH' 
TOP 0 6.05315 3.67519 90.0 N 134 0 1
TOP 1 6.05315 3.50984 90.0 N 134 1 2
TOP 2 6.05315 3.34449 90.0 N 134 2 3
TOP 3 5.88779 3.67519 90.0 N 2 101 4
TOP 4 5.88779 3.50984 90.0 N 2 102 5
TOP 5 5.88779 3.34449 90.0 N 2 103 6
TOP 6 6.34055 3.34449 90.0 N 0 31 un_1
TOP 7 6.34055 3.67519 90.0 N 0 32 un_2
#
# CMP 144
CMP 28 4.94094 4.12008 0.0 N ME3 ??? ;0=2,1=0.380000
PRP HARD_LOCATION 'YES' 
PRP ALT_SYMBOLS '(P_NUT_166CT244CB198_V1_H380)' 
PRP PARENT_PART_TYPE 'NUT' 
PRP PARENT_PPT 'NUT' 
PRP PARENT_PPT_PART 'NUT-G340-10437-01' 
PRP PART_NAME 'NUT' 
TOP 0 4.94094 4.12008 0.0 N 2 104 1
#
# CMP 145
CMP 28 4.94094 3.09646 0.0 N ME4 ??? ;0=2,1=0.380000
PRP HARD_LOCATION 'YES' 
PRP ALT_SYMBOLS '(P_NUT_166CT244CB198_V1_H380)' 
PRP PARENT_PART_TYPE 'NUT' 
PRP PARENT_PPT 'NUT' 
PRP PARENT_PPT_PART 'NUT-G340-10437-01' 
PRP PART_NAME 'NUT' 
TOP 0 4.94094 3.09646 0.0 N 2 105 1
#
# CMP 146
CMP 28 2.55906 4.12008 0.0 N ME1 ??? ;0=2,1=0.380000
PRP HARD_LOCATION 'YES' 
PRP ALT_SYMBOLS '(P_NUT_166CT244CB198_V1_H380)' 
PRP PARENT_PART_TYPE 'NUT' 
PRP PARENT_PPT 'NUT' 
PRP PARENT_PPT_PART 'NUT-G340-10437-01' 
PRP PART_NAME 'NUT' 
TOP 0 2.55906 4.12008 0.0 N 2 106 1
#
# CMP 147
CMP 28 2.55906 3.09646 0.0 N ME2 ??? ;0=2,1=0.380000
PRP HARD_LOCATION 'YES' 
PRP ALT_SYMBOLS '(P_NUT_166CT244CB198_V1_H380)' 
PRP PARENT_PART_TYPE 'NUT' 
PRP PARENT_PPT 'NUT' 
PRP PARENT_PPT_PART 'NUT-G340-10437-01' 
PRP PART_NAME 'NUT' 
TOP 0 2.55906 3.09646 0.0 N 2 107 1
#
# CMP 148
CMP 29 0.78948 2.661 180.0 N U28 ??? ;0=1,1=0.031500
PRP ALT_SYMBOLS '(LGA10_079_P0197)' 
PRP PARENT_PART_TYPE 'ICP_10100_LGA10' 
PRP PARENT_PPT 'ICP_10100_LGA10' 
PRP PARENT_PPT_PART 'ICP_10100_LGA10-A222-00002-FB,ICP-10100' 
PRP PART_NAME 'ICP_10100_LGA10' 
TOP 0 0.79932 2.69151 180.0 N 409 0 1
TOP 1 0.77964 2.69151 180.0 N 527 0 2
TOP 2 0.75897 2.68069 180.0 N 411 0 3
TOP 3 0.75897 2.661 180.0 N 526 0 4
TOP 4 0.75897 2.64131 180.0 N 412 0 5
TOP 5 0.77964 2.63049 180.0 N 416 0 6
TOP 6 0.79932 2.63049 180.0 N 417 0 7
TOP 7 0.81999 2.64131 180.0 N 2 108 8
TOP 8 0.81999 2.661 180.0 N 2 109 9
TOP 9 0.81999 2.68069 180.0 N 72 1 10
#
# CMP 149
CMP 30 3.39 2.314 0.0 N U29 ??? ;0=1,1=0.046460
PRP ALT_SYMBOLS '(LGA28_205X150_P0197)' 
PRP PARENT_PART_TYPE 'BNO080_LGA_28' 
PRP PARENT_PPT 'BNO080_LGA_28' 
PRP PARENT_PPT_PART 'BNO080_LGA_28-A246-00002-FB,BNO085' 
PRP PART_NAME 'BNO080_LGA_28' 
TOP 0 3.45152 2.40258 0.0 N 0 33 1
TOP 1 3.41953 2.40504 0.0 N 2 110 2
TOP 2 3.39984 2.40504 0.0 N 75 1 3
TOP 3 3.38016 2.40504 0.0 N 379 1 4
TOP 4 3.36047 2.40504 0.0 N 378 0 5
TOP 5 3.32848 2.40258 0.0 N 380 0 6
TOP 6 3.32848 2.3829 0.0 N 0 34 7
TOP 7 3.32848 2.36321 0.0 N 0 35 8
TOP 8 3.32848 2.34353 0.0 N 78 0 9
TOP 9 3.32848 2.32384 0.0 N 381 0 10
TOP 10 3.32848 2.30416 0.0 N 372 1 11
TOP 11 3.32848 2.28447 0.0 N 0 36 12
TOP 12 3.32848 2.26479 0.0 N 0 37 13
TOP 13 3.32848 2.2451 0.0 N 533 1 14
TOP 14 3.32848 2.22542 0.0 N 427 0 15
TOP 15 3.36047 2.22296 0.0 N 398 0 16
TOP 16 3.38016 2.22296 0.0 N 371 0 17
TOP 17 3.39984 2.22296 0.0 N 569 1 18
TOP 18 3.41953 2.22296 0.0 N 531 0 19
TOP 19 3.45152 2.22542 0.0 N 530 0 20
TOP 20 3.45152 2.2451 0.0 N 0 38 21
TOP 21 3.45152 2.26479 0.0 N 0 39 22
TOP 22 3.45152 2.28447 0.0 N 0 40 23
TOP 23 3.45152 2.30416 0.0 N 0 41 24
TOP 24 3.45152 2.32384 0.0 N 2 111 25
TOP 25 3.45152 2.34353 0.0 N 109 0 26
TOP 26 3.45152 2.36321 0.0 N 114 0 27
TOP 27 3.45152 2.3829 0.0 N 75 2 28
#
# CMP 150
CMP 31 3.645 1.47 180.0 N L34 ??? ;0=1,1=0.029530
PRP ALT_SYMBOLS '(SMC_0603R_H030)' 
PRP PARENT_PART_TYPE 'FERRITEBEAD' 
PRP PARENT_PPT 'FERRITEBEAD' 
PRP PARENT_PPT_PART 'FERRITEBEAD-G191-10100-01,120OHM,25%' 
PRP PART_NAME 'FERRITEBEAD' 
TOP 0 3.672 1.47 180.0 N 7 0 1
TOP 1 3.618 1.47 180.0 N 15 2 2
#
# CMP 151
CMP 31 1.76 3.16 90.0 N L23 ??? ;0=1,1=0.029530
PRP ALT_SYMBOLS '(SMC_0603R_H030)' 
PRP PARENT_PART_TYPE 'FERRITEBEAD' 
PRP PARENT_PPT 'FERRITEBEAD' 
PRP PARENT_PPT_PART 'FERRITEBEAD-G191-10101-01,26OHM,25%' 
PRP PART_NAME 'FERRITEBEAD' 
TOP 0 1.76 3.187 90.0 N 77 2 1
TOP 1 1.76 3.133 90.0 N 85 2 2
#
# CMP 152
CMP 31 1.455 3.165 90.0 N L24 ??? ;0=1,1=0.029530
PRP ALT_SYMBOLS '(SMC_0603R_H030)' 
PRP PARENT_PART_TYPE 'FERRITEBEAD' 
PRP PARENT_PPT 'FERRITEBEAD' 
PRP PARENT_PPT_PART 'FERRITEBEAD-G191-10100-01,120OHM,25%' 
PRP PART_NAME 'FERRITEBEAD' 
TOP 0 1.455 3.192 90.0 N 1 28 1
TOP 1 1.455 3.138 90.0 N 88 8 2
#
# CMP 153
CMP 31 5.21 1.725 0.0 N L12 ??? ;0=1,1=0.029530
PRP REUSE_ID '22' 
PRP ALT_SYMBOLS '(SMC_0603R_H030)' 
PRP PARENT_PART_TYPE 'FERRITEBEAD' 
PRP PARENT_PPT 'FERRITEBEAD' 
PRP PARENT_PPT_PART 'FERRITEBEAD-G191-10100-01,120OHM,25%' 
PRP PART_NAME 'FERRITEBEAD' 
TOP 0 5.183 1.725 0.0 N 10 0 1
TOP 1 5.237 1.725 0.0 N 15 3 2
#
# CMP 154
CMP 31 5.12 3.88 270.0 N L15 ??? ;0=1,1=0.029530
PRP HARD_LOCATION 'YES' 
PRP ALT_SYMBOLS '(SMC_0603R_H030)' 
PRP PARENT_PART_TYPE 'FERRITEBEAD' 
PRP PARENT_PPT 'FERRITEBEAD' 
PRP PARENT_PPT_PART 'FERRITEBEAD-G191-10100-01,120OHM,25%' 
PRP PART_NAME 'FERRITEBEAD' 
TOP 0 5.12 3.853 270.0 N 13 2 1
TOP 1 5.12 3.907 270.0 N 125 0 2
#
# CMP 155
CMP 31 4.625 3.86 180.0 N L16 ??? ;0=1,1=0.029530
PRP HARD_LOCATION 'YES' 
PRP REUSE_ID '4' 
PRP ALT_SYMBOLS '(SMC_0603R_H030)' 
PRP PARENT_PART_TYPE 'FERRITEBEAD' 
PRP PARENT_PPT 'FERRITEBEAD' 
PRP PARENT_PPT_PART 'FERRITEBEAD-G191-10100-01,120OHM,25%' 
PRP PART_NAME 'FERRITEBEAD' 
TOP 0 4.652 3.86 180.0 N 70 0 1
TOP 1 4.598 3.86 180.0 N 1 29 2
#
# CMP 156
CMP 31 3.655 2.205 180.0 N L33 ??? ;0=1,1=0.029530
PRP ALT_SYMBOLS '(SMC_0603R_H030)' 
PRP PARENT_PART_TYPE 'FERRITEBEAD' 
PRP PARENT_PPT 'FERRITEBEAD' 
PRP PARENT_PPT_PART 'FERRITEBEAD-G191-10100-01,120OHM,25%' 
PRP PART_NAME 'FERRITEBEAD' 
TOP 0 3.682 2.205 180.0 N 8 0 1
TOP 1 3.628 2.205 180.0 N 16 4 2
#
# CMP 157
CMP 31 1.561 3.776 0.0 N L7 ??? ;0=1,1=0.029530
PRP REUSE_ID '16' 
PRP ALT_SYMBOLS '(SMC_0603R_H030)' 
PRP PARENT_PART_TYPE 'FERRITEBEAD' 
PRP PARENT_PPT 'FERRITEBEAD' 
PRP PARENT_PPT_PART 'FERRITEBEAD-G191-10101-01,26OHM,25%' 
PRP PART_NAME 'FERRITEBEAD' 
TOP 0 1.534 3.776 0.0 N 3 1 1
TOP 1 1.588 3.776 0.0 N 84 0 2
#
# CMP 158
CMP 31 3.438 4.202 180.0 N L8 ??? ;0=1,1=0.029530
PRP REUSE_ID '10' 
PRP ALT_SYMBOLS '(SMC_0603R_H030)' 
PRP PARENT_PART_TYPE 'FERRITEBEAD' 
PRP PARENT_PPT 'FERRITEBEAD' 
PRP PARENT_PPT_PART 'FERRITEBEAD-G191-10101-01,26OHM,25%' 
PRP PART_NAME 'FERRITEBEAD' 
TOP 0 3.465 4.202 180.0 N 3 2 1
TOP 1 3.411 4.202 180.0 N 110 0 2
#
# CMP 159
CMP 31 5.395 2.256 90.0 N L9 ??? ;0=1,1=0.029530
PRP ALT_SYMBOLS '(SMC_0603R_H030)' 
PRP PARENT_PART_TYPE 'FERRITEBEAD' 
PRP PARENT_PPT 'FERRITEBEAD' 
PRP PARENT_PPT_PART 'FERRITEBEAD-G191-10101-01,26OHM,25%' 
PRP PART_NAME 'FERRITEBEAD' 
TOP 0 5.395 2.283 90.0 N 3 3 1
TOP 1 5.395 2.229 90.0 N 55 0 2
#
# CMP 160
CMP 31 0.571 3.872 270.0 N L20 ??? ;0=1,1=0.029530
PRP HARD_LOCATION 'YES' 
PRP ALT_SYMBOLS '(SMC_0603R_H030)' 
PRP PARENT_PART_TYPE 'FERRITEBEAD' 
PRP PARENT_PPT 'FERRITEBEAD' 
PRP PARENT_PPT_PART 'FERRITEBEAD-G191-10101-01,26OHM,25%' 
PRP PART_NAME 'FERRITEBEAD' 
TOP 0 0.571 3.845 270.0 N 133 0 1
TOP 1 0.571 3.899 270.0 N 30 1 2
#
# CMP 161
CMP 31 4.933 2.493 270.0 N L6 ??? ;0=1,1=0.029530
PRP ALT_SYMBOLS '(SMC_0603R_H030)' 
PRP PARENT_PART_TYPE 'FERRITEBEAD' 
PRP PARENT_PPT 'FERRITEBEAD' 
PRP PARENT_PPT_PART 'FERRITEBEAD-G191-10101-01,26OHM,25%' 
PRP PART_NAME 'FERRITEBEAD' 
TOP 0 4.933 2.466 270.0 N 19 4 1
TOP 1 4.933 2.52 270.0 N 22 2 2
#
# CMP 162
CMP 31 5.7 0.96 90.0 N L13 ??? ;0=1,1=0.029530
PRP REUSE_ID '1' 
PRP ALT_SYMBOLS '(SMC_0603R_H030)' 
PRP PARENT_PART_TYPE 'FERRITEBEAD' 
PRP PARENT_PPT 'FERRITEBEAD' 
PRP PARENT_PPT_PART 'FERRITEBEAD-G191-10101-01,26OHM,25%' 
PRP PART_NAME 'FERRITEBEAD' 
TOP 0 5.7 0.987 90.0 N 19 5 1
TOP 1 5.7 0.933 90.0 N 32 2 2
#
# CMP 163
CMP 31 3.681 3.099 0.0 N L11 ??? ;0=1,1=0.029530
PRP REUSE_ID '14' 
PRP ALT_SYMBOLS '(SMC_0603R_H030)' 
PRP PARENT_PART_TYPE 'FERRITEBEAD' 
PRP PARENT_PPT 'FERRITEBEAD' 
PRP PARENT_PPT_PART 'FERRITEBEAD-G191-10101-01,26OHM,25%' 
PRP PART_NAME 'FERRITEBEAD' 
TOP 0 3.654 3.099 0.0 N 19 6 1
TOP 1 3.708 3.099 0.0 N 21 2 2
#
# CMP 164
CMP 32 0.783 3.941 0.0 N CR12 ??? ;0=1,1=0.099000
PRP HARD_LOCATION 'YES' 
PRP ALT_SYMBOLS '(DPAK_3_V3)' 
PRP PARENT_PART_TYPE 'DIODE_3F' 
PRP PARENT_PPT 'DIODE_3F' 
PRP PARENT_PPT_PART 'DIODE_3F-G122-10080-01' 
PRP PART_NAME 'DIODE_3F' 
TOP 0 0.693 3.736 0.0 N 133 1 1
TOP 1 0.873 3.736 0.0 N 134 3 2
TOP 2 0.783 4.018 0.0 N 30 2 3
#
# CMP 165
CMP 33 3.98 0.825 270.0 N Y4 ??? ;0=1,1=0.045280
PRP ALT_SYMBOLS '(SMC_Y6_197X276)' 
PRP PARENT_PART_TYPE 'OSC6P_V2' 
PRP PARENT_PPT 'OSC6P_V2' 
PRP PARENT_PPT_PART 'OSC6P_V2-A130-00004-AW' 
PRP PART_NAME 'OSC6P_V2' 
TOP 0 3.88 0.75217 270.0 N 343 0 1
TOP 1 3.98 0.75217 270.0 N 0 42 2
TOP 2 4.08 0.75217 270.0 N 2 112 3
TOP 3 4.08 0.89783 270.0 N 50 0 4
TOP 4 3.98 0.89783 270.0 N 52 0 5
TOP 5 3.88 0.89783 270.0 N 42 0 6
#
# CMP 166
CMP 34 4.364 0.865 270.0 N Y3 ??? ;0=1,1=0.043310
PRP ALT_SYMBOLS '(SMC_Y6_126X197)' 
PRP PARENT_PART_TYPE 'OSC6P_V2' 
PRP PARENT_PPT 'OSC6P_V2' 
PRP PARENT_PPT_PART 'OSC6P_V2-A130-00003-AW' 
PRP PART_NAME 'OSC6P_V2' 
TOP 0 4.314 0.82366 270.0 N 342 1 1
TOP 1 4.364 0.82366 270.0 N 0 43 2
TOP 2 4.414 0.82366 270.0 N 2 113 3
TOP 3 4.414 0.90634 270.0 N 46 0 4
TOP 4 4.364 0.90634 270.0 N 48 0 5
TOP 5 4.314 0.90634 270.0 N 41 0 6
#
# CMP 167
CMP 35 4.85102 3.79016 270.0 N P2 ??? ;0=1,1=0.305120
PRP HARD_LOCATION 'YES' 
PRP ALT_SYMBOLS '(S_F_H_2X4_S_P0787_V1)' 
PRP PARENT_PART_TYPE 'CONN_HDR_2X4_F_S_SMT' 
PRP PARENT_PPT 'CONN_HDR_2X4_F_S_SMT' 
PRP PARENT_PPT_PART 'CONN_HDR_2X4_F_S_SMT-G200-13079-01' 
PRP PART_NAME 'CONN_HDR_2X4_F_S_SMT' 
TOP 0 4.91549 3.90827 270.0 N 125 1 1
TOP 1 4.78656 3.90827 270.0 N 70 1 2
TOP 2 4.91549 3.82953 270.0 N 240 0 3
TOP 3 4.78656 3.82953 270.0 N 241 1 4
TOP 4 4.91549 3.75079 270.0 N 242 0 5
TOP 5 4.78656 3.75079 270.0 N 243 0 6
TOP 6 4.91549 3.67205 270.0 N 244 0 7
TOP 7 4.78656 3.67205 270.0 N 2 114 8
#
# CMP 168
CMP 36 3.625 3.31 180.0 N U23 ??? ;0=1,1=0.085040
PRP ALT_SYMBOLS '(SOP8_208_P050_V2)' 
PRP PARENT_PART_TYPE 'MT25QL128ABA1ESE_SOP8' 
PRP PARENT_PPT 'MT25QL128ABA1ESE_SOP8' 
PRP PARENT_PPT_PART 'MT25QL128ABA1ESE_SOP8-G221-10224-01,MT25QL128ABA1ESE-0SIT' 
PRP PART_NAME 'MT25QL128ABA1ESE_SOP8' 
TOP 0 3.769 3.235 180.0 N 312 1 1
TOP 1 3.769 3.285 180.0 N 321 0 2
TOP 2 3.769 3.335 180.0 N 322 0 3
TOP 3 3.769 3.385 180.0 N 2 115 4
TOP 4 3.481 3.385 180.0 N 318 0 5
TOP 5 3.481 3.335 180.0 N 313 1 6
TOP 6 3.481 3.285 180.0 N 323 0 7
TOP 7 3.481 3.235 180.0 N 1 30 8
#
# CMP 169
CMP 37 2.8486 1.84042 90.0 N P1 ??? ;0=1,1=0.097240
PRP ALT_SYMBOLS '(S_M_H_2X10_S_P0197)' 
PRP PARENT_PART_TYPE 'CONN_HDR_2X10_M_S_SMT' 
PRP PARENT_PPT 'CONN_HDR_2X10_M_S_SMT' 
PRP PARENT_PPT_PART 'CONN_HDR_2X10_M_S_SMT-G200-13077-01' 
PRP PART_NAME 'CONN_HDR_2X10_M_S_SMT' 
TOP 0 2.76986 1.929 90.0 N 231 0 1
TOP 1 2.92734 1.929 90.0 N 232 0 2
TOP 2 2.76986 1.90932 90.0 N 233 0 3
TOP 3 2.92734 1.90932 90.0 N 234 0 4
TOP 4 2.76986 1.88963 90.0 N 235 0 5
TOP 5 2.92734 1.88963 90.0 N 122 0 6
TOP 6 2.76986 1.86995 90.0 N 236 0 7
TOP 7 2.92734 1.86995 90.0 N 2 116 8
TOP 8 2.76986 1.85026 90.0 N 2 117 9
TOP 9 2.92734 1.85026 90.0 N 0 44 10
TOP 10 2.76986 1.83058 90.0 N 0 45 11
TOP 11 2.92734 1.83058 90.0 N 0 46 12
TOP 12 2.76986 1.81089 90.0 N 0 47 13
TOP 13 2.92734 1.81089 90.0 N 0 48 14
TOP 14 2.76986 1.79121 90.0 N 2 118 15
TOP 15 2.92734 1.79121 90.0 N 0 49 16
TOP 16 2.76986 1.77152 90.0 N 237 0 17
TOP 17 2.92734 1.77152 90.0 N 0 50 18
TOP 18 2.76986 1.75184 90.0 N 238 0 19
TOP 19 2.92734 1.75184 90.0 N 239 0 20
#
# CMP 170
CMP 38 4.305 1.745 270.0 N U24 ??? ;0=1,1=0.102360
PRP ALT_SYMBOLS '(BGA484_906_P0394_V3)' 
PRP PARENT_PART_TYPE 'XC7A200T_2FBG484C_FBG484' 
PRP PARENT_PPT 'XC7A200T_2FBG484C_FBG484' 
PRP PARENT_PPT_PART 'XC7A200T_2FBG484C_FBG484-G240-10069-01' 
PRP PART_NAME 'XC7A200T_2FBG484C_FBG484' 
TOP 0 3.89161 1.33161 270.0 N 0 51 A1
TOP 1 3.89161 1.37098 270.0 N 2 119 A2
TOP 2 3.89161 1.41035 270.0 N 2 120 A3
TOP 3 3.89161 1.44973 270.0 N 44 0 A4
TOP 4 3.89161 1.4891 270.0 N 2 121 A5
TOP 5 3.89161 1.52847 270.0 N 97 0 A6
TOP 6 3.89161 1.56784 270.0 N 2 122 A7
TOP 7 3.89161 1.60721 270.0 N 188 0 A8
TOP 8 3.89161 1.64658 270.0 N 2 123 A9
TOP 9 3.89161 1.68595 270.0 N 193 0 A10
TOP 10 3.89161 1.72532 270.0 N 2 124 A11
TOP 11 3.89161 1.76469 270.0 N 2 125 A12
TOP 12 3.89161 1.80406 270.0 N 146 0 A13
TOP 13 3.89161 1.84343 270.0 N 148 0 A14
TOP 14 3.89161 1.8828 270.0 N 0 52 A15
TOP 15 3.89161 1.92217 270.0 N 0 53 A16
TOP 16 3.89161 1.96154 270.0 N 1 31 A17
TOP 17 3.89161 2.00091 270.0 N 477 0 A18
TOP 18 3.89161 2.04028 270.0 N 0 54 A19
TOP 19 3.89161 2.07965 270.0 N 476 0 A20
TOP 20 3.89161 2.11902 270.0 N 550 1 A21
TOP 21 3.89161 2.15839 270.0 N 2 126 A22
TOP 22 4.67902 1.33161 270.0 N 0 55 AA1
TOP 23 4.67902 1.37098 270.0 N 2 127 AA2
TOP 24 4.67902 1.41035 270.0 N 0 56 AA3
TOP 25 4.67902 1.44973 270.0 N 0 57 AA4
TOP 26 4.67902 1.4891 270.0 N 361 0 AA5
TOP 27 4.67902 1.52847 270.0 N 0 58 AA6
TOP 28 4.67902 1.56784 270.0 N 9 3 AA7
TOP 29 4.67902 1.60721 270.0 N 542 1 AA8
TOP 30 4.67902 1.64658 270.0 N 368 0 AA9
TOP 31 4.67902 1.68595 270.0 N 0 59 AA10
TOP 32 4.67902 1.72532 270.0 N 0 60 AA11
TOP 33 4.67902 1.76469 270.0 N 2 128 AA12
TOP 34 4.67902 1.80406 270.0 N 248 0 AA13
TOP 35 4.67902 1.84343 270.0 N 0 61 AA14
TOP 36 4.67902 1.8828 270.0 N 478 0 AA15
TOP 37 4.67902 1.92217 270.0 N 0 62 AA16
TOP 38 4.67902 1.96154 270.0 N 1 32 AA17
TOP 39 4.67902 2.00091 270.0 N 536 0 AA18
TOP 40 4.67902 2.04028 270.0 N 0 63 AA19
TOP 41 4.67902 2.07965 270.0 N 438 0 AA20
TOP 42 4.67902 2.11902 270.0 N 436 0 AA21
TOP 43 4.67902 2.15839 270.0 N 2 129 AA22
TOP 44 4.71839 1.33161 270.0 N 0 64 AB1
TOP 45 4.71839 1.37098 270.0 N 360 0 AB2
TOP 46 4.71839 1.41035 270.0 N 359 0 AB3
TOP 47 4.71839 1.44973 270.0 N 9 4 AB4
TOP 48 4.71839 1.4891 270.0 N 362 0 AB5
TOP 49 4.71839 1.52847 270.0 N 539 1 AB6
TOP 50 4.71839 1.56784 270.0 N 538 1 AB7
TOP 51 4.71839 1.60721 270.0 N 543 1 AB8
TOP 52 4.71839 1.64658 270.0 N 2 130 AB9
TOP 53 4.71839 1.68595 270.0 N 367 0 AB10
TOP 54 4.71839 1.72532 270.0 N 0 65 AB11
TOP 55 4.71839 1.76469 270.0 N 0 66 AB12
TOP 56 4.71839 1.80406 270.0 N 319 0 AB13
TOP 57 4.71839 1.84343 270.0 N 1 33 AB14
TOP 58 4.71839 1.8828 270.0 N 0 67 AB15
TOP 59 4.71839 1.92217 270.0 N 511 1 AB16
TOP 60 4.71839 1.96154 270.0 N 510 1 AB17
TOP 61 4.71839 2.00091 270.0 N 351 0 AB18
TOP 62 4.71839 2.04028 270.0 N 2 131 AB19
TOP 63 4.71839 2.07965 270.0 N 0 68 AB20
TOP 64 4.71839 2.11902 270.0 N 0 69 AB21
TOP 65 4.71839 2.15839 270.0 N 0 70 AB22
TOP 66 3.93098 1.33161 270.0 N 0 71 B1
TOP 67 3.93098 1.37098 270.0 N 0 72 B2
TOP 68 3.93098 1.41035 270.0 N 2 132 B3
TOP 69 3.93098 1.44973 270.0 N 40 0 B4
TOP 70 3.93098 1.4891 270.0 N 6 0 B5
TOP 71 3.93098 1.52847 270.0 N 74 0 B6
TOP 72 3.93098 1.56784 270.0 N 6 1 B7
TOP 73 3.93098 1.60721 270.0 N 187 0 B8
TOP 74 3.93098 1.64658 270.0 N 6 2 B9
TOP 75 3.93098 1.68595 270.0 N 192 0 B10
TOP 76 3.93098 1.72532 270.0 N 6 3 B11
TOP 77 3.93098 1.76469 270.0 N 2 133 B12
TOP 78 3.93098 1.80406 270.0 N 172 0 B13
TOP 79 3.93098 1.84343 270.0 N 1 34 B14
TOP 80 3.93098 1.8828 270.0 N 0 73 B15
TOP 81 3.93098 1.92217 270.0 N 0 74 B16
TOP 82 3.93098 1.96154 270.0 N 0 75 B17
TOP 83 3.93098 2.00091 270.0 N 0 76 B18
TOP 84 3.93098 2.04028 270.0 N 2 134 B19
TOP 85 3.93098 2.07965 270.0 N 475 0 B20
TOP 86 3.93098 2.11902 270.0 N 549 1 B21
TOP 87 3.93098 2.15839 270.0 N 548 1 B22
TOP 88 3.97035 1.33161 270.0 N 9 5 C1
TOP 89 3.97035 1.37098 270.0 N 0 77 C2
TOP 90 3.97035 1.41035 270.0 N 2 135 C3
TOP 91 3.97035 1.44973 270.0 N 6 4 C4
TOP 92 3.97035 1.4891 270.0 N 69 0 C5
TOP 93 3.97035 1.52847 270.0 N 2 136 C6
TOP 94 3.97035 1.56784 270.0 N 101 0 C7
TOP 95 3.97035 1.60721 270.0 N 6 5 C8
TOP 96 3.97035 1.64658 270.0 N 195 0 C9
TOP 97 3.97035 1.68595 270.0 N 2 137 C10
TOP 98 3.97035 1.72532 270.0 N 191 0 C11
TOP 99 3.97035 1.76469 270.0 N 2 138 C12
TOP 100 3.97035 1.80406 270.0 N 170 0 C13
TOP 101 3.97035 1.84343 270.0 N 355 0 C14
TOP 102 3.97035 1.8828 270.0 N 356 0 C15
TOP 103 3.97035 1.92217 270.0 N 2 139 C16
TOP 104 3.97035 1.96154 270.0 N 441 0 C17
TOP 105 3.97035 2.00091 270.0 N 442 0 C18
TOP 106 3.97035 2.04028 270.0 N 0 78 C19
TOP 107 3.97035 2.07965 270.0 N 0 79 C20
TOP 108 3.97035 2.11902 270.0 N 1 35 C21
TOP 109 3.97035 2.15839 270.0 N 571 1 C22
TOP 110 4.00973 1.33161 270.0 N 0 80 D1
TOP 111 4.00973 1.37098 270.0 N 0 81 D2
TOP 112 4.00973 1.41035 270.0 N 2 140 D3
TOP 113 4.00973 1.44973 270.0 N 2 141 D4
TOP 114 4.00973 1.4891 270.0 N 60 0 D5
TOP 115 4.00973 1.52847 270.0 N 7 1 D6
TOP 116 4.00973 1.56784 270.0 N 99 0 D7
TOP 117 4.00973 1.60721 270.0 N 2 142 D8
TOP 118 4.00973 1.64658 270.0 N 194 0 D9
TOP 119 4.00973 1.68595 270.0 N 7 2 D10
TOP 120 4.00973 1.72532 270.0 N 190 0 D11
TOP 121 4.00973 1.76469 270.0 N 2 143 D12
TOP 122 4.00973 1.80406 270.0 N 2 144 D13
TOP 123 4.00973 1.84343 270.0 N 167 0 D14
TOP 124 4.00973 1.8828 270.0 N 144 0 D15
TOP 125 4.00973 1.92217 270.0 N 0 82 D16
TOP 126 4.00973 1.96154 270.0 N 440 0 D17
TOP 127 4.00973 2.00091 270.0 N 1 36 D18
TOP 128 4.00973 2.04028 270.0 N 463 0 D19
TOP 129 4.00973 2.07965 270.0 N 0 83 D20
TOP 130 4.00973 2.11902 270.0 N 554 1 D21
TOP 131 4.00973 2.15839 270.0 N 552 1 D22
TOP 132 4.0491 1.33161 270.0 N 0 84 E1
TOP 133 4.0491 1.37098 270.0 N 0 85 E2
TOP 134 4.0491 1.41035 270.0 N 0 86 E3
TOP 135 4.0491 1.44973 270.0 N 2 145 E4
TOP 136 4.0491 1.4891 270.0 N 2 146 E5
TOP 137 4.0491 1.52847 270.0 N 53 0 E6
TOP 138 4.0491 1.56784 270.0 N 2 147 E7
TOP 139 4.0491 1.60721 270.0 N 7 3 E8
TOP 140 4.0491 1.64658 270.0 N 2 148 E9
TOP 141 4.0491 1.68595 270.0 N 35 0 E10
TOP 142 4.0491 1.72532 270.0 N 2 149 E11
TOP 143 4.0491 1.76469 270.0 N 8 1 E12
TOP 144 4.0491 1.80406 270.0 N 439 0 E13
TOP 145 4.0491 1.84343 270.0 N 0 87 E14
TOP 146 4.0491 1.8828 270.0 N 1 37 E15
TOP 147 4.0491 1.92217 270.0 N 0 88 E16
TOP 148 4.0491 1.96154 270.0 N 0 89 E17
TOP 149 4.0491 2.00091 270.0 N 0 90 E18
TOP 150 4.0491 2.04028 270.0 N 462 0 E19
TOP 151 4.0491 2.07965 270.0 N 2 150 E20
TOP 152 4.0491 2.11902 270.0 N 553 1 E21
TOP 153 4.0491 2.15839 270.0 N 551 1 E22
TOP 154 4.08847 1.33161 270.0 N 0 91 F1
TOP 155 4.08847 1.37098 270.0 N 9 6 F2
TOP 156 4.08847 1.41035 270.0 N 0 92 F3
TOP 157 4.08847 1.44973 270.0 N 0 93 F4
TOP 158 4.08847 1.4891 270.0 N 2 151 F5
TOP 159 4.08847 1.52847 270.0 N 51 0 F6
TOP 160 4.08847 1.56784 270.0 N 7 4 F7
TOP 161 4.08847 1.60721 270.0 N 317 0 F8
TOP 162 4.08847 1.64658 270.0 N 7 5 F9
TOP 163 4.08847 1.68595 270.0 N 25 0 F10
TOP 164 4.08847 1.72532 270.0 N 2 152 F11
TOP 165 4.08847 1.76469 270.0 N 1 38 F12
TOP 166 4.08847 1.80406 270.0 N 270 0 F13
TOP 167 4.08847 1.84343 270.0 N 271 0 F14
TOP 168 4.08847 1.8828 270.0 N 0 94 F15
TOP 169 4.08847 1.92217 270.0 N 354 0 F16
TOP 170 4.08847 1.96154 270.0 N 2 153 F17
TOP 171 4.08847 2.00091 270.0 N 474 0 F18
TOP 172 4.08847 2.04028 270.0 N 0 95 F19
TOP 173 4.08847 2.07965 270.0 N 0 96 F20
TOP 174 4.08847 2.11902 270.0 N 0 97 F21
TOP 175 4.08847 2.15839 270.0 N 1 39 F22
TOP 176 4.12784 1.33161 270.0 N 0 98 G1
TOP 177 4.12784 1.37098 270.0 N 0 99 G2
TOP 178 4.12784 1.41035 270.0 N 0 100 G3
TOP 179 4.12784 1.44973 270.0 N 0 101 G4
TOP 180 4.12784 1.4891 270.0 N 2 154 G5
TOP 181 4.12784 1.52847 270.0 N 2 155 G6
TOP 182 4.12784 1.56784 270.0 N 2 156 G7
TOP 183 4.12784 1.60721 270.0 N 2 157 G8
TOP 184 4.12784 1.64658 270.0 N 2 158 G9
TOP 185 4.12784 1.68595 270.0 N 2 159 G10
TOP 186 4.12784 1.72532 270.0 N 330 1 G11
TOP 187 4.12784 1.76469 270.0 N 2 160 G12
TOP 188 4.12784 1.80406 270.0 N 492 0 G13
TOP 189 4.12784 1.84343 270.0 N 2 161 G14
TOP 190 4.12784 1.8828 270.0 N 514 0 G15
TOP 191 4.12784 1.92217 270.0 N 0 102 G16
TOP 192 4.12784 1.96154 270.0 N 0 103 G17
TOP 193 4.12784 2.00091 270.0 N 0 104 G18
TOP 194 4.12784 2.04028 270.0 N 1 40 G19
TOP 195 4.12784 2.07965 270.0 N 366 0 G20
TOP 196 4.12784 2.11902 270.0 N 555 1 G21
TOP 197 4.12784 2.15839 270.0 N 556 1 G22
TOP 198 4.16721 1.33161 270.0 N 2 162 H1
TOP 199 4.16721 1.37098 270.0 N 0 105 H2
TOP 200 4.16721 1.41035 270.0 N 0 106 H3
TOP 201 4.16721 1.44973 270.0 N 0 107 H4
TOP 202 4.16721 1.4891 270.0 N 0 108 H5
TOP 203 4.16721 1.52847 270.0 N 9 7 H6
TOP 204 4.16721 1.56784 270.0 N 2 163 H7
TOP 205 4.16721 1.60721 270.0 N 10 1 H8
TOP 206 4.16721 1.64658 270.0 N 2 164 H9
TOP 207 4.16721 1.68595 270.0 N 10 2 H10
TOP 208 4.16721 1.72532 270.0 N 2 165 H11
TOP 209 4.16721 1.76469 270.0 N 8 2 H12
TOP 210 4.16721 1.80406 270.0 N 483 0 H13
TOP 211 4.16721 1.84343 270.0 N 431 2 H14
TOP 212 4.16721 1.8828 270.0 N 443 2 H15
TOP 213 4.16721 1.92217 270.0 N 1 41 H16
TOP 214 4.16721 1.96154 270.0 N 0 109 H17
TOP 215 4.16721 2.00091 270.0 N 0 110 H18
TOP 216 4.16721 2.04028 270.0 N 375 0 H19
TOP 217 4.16721 2.07965 270.0 N 365 0 H20
TOP 218 4.16721 2.11902 270.0 N 2 166 H21
TOP 219 4.16721 2.15839 270.0 N 305 0 H22
TOP 220 4.20658 1.33161 270.0 N 0 111 J1
TOP 221 4.20658 1.37098 270.0 N 0 112 J2
TOP 222 4.20658 1.41035 270.0 N 9 8 J3
TOP 223 4.20658 1.44973 270.0 N 0 113 J4
TOP 224 4.20658 1.4891 270.0 N 0 114 J5
TOP 225 4.20658 1.52847 270.0 N 0 115 J6
TOP 226 4.20658 1.56784 270.0 N 10 3 J7
TOP 227 4.20658 1.60721 270.0 N 2 167 J8
TOP 228 4.20658 1.64658 270.0 N 10 4 J9
TOP 229 4.20658 1.68595 270.0 N 2 168 J10
TOP 230 4.20658 1.72532 270.0 N 10 5 J11
TOP 231 4.20658 1.76469 270.0 N 2 169 J12
TOP 232 4.20658 1.80406 270.0 N 1 42 J13
TOP 233 4.20658 1.84343 270.0 N 444 2 J14
TOP 234 4.20658 1.8828 270.0 N 428 2 J15
TOP 235 4.20658 1.92217 270.0 N 0 116 J16
TOP 236 4.20658 1.96154 270.0 N 532 0 J17
TOP 237 4.20658 2.00091 270.0 N 2 170 J18
TOP 238 4.20658 2.04028 270.0 N 377 0 J19
TOP 239 4.20658 2.07965 270.0 N 303 0 J20
TOP 240 4.20658 2.11902 270.0 N 0 117 J21
TOP 241 4.20658 2.15839 270.0 N 304 0 J22
TOP 242 4.24595 1.33161 270.0 N 0 118 K1
TOP 243 4.24595 1.37098 270.0 N 0 119 K2
TOP 244 4.24595 1.41035 270.0 N 0 120 K3
TOP 245 4.24595 1.44973 270.0 N 0 121 K4
TOP 246 4.24595 1.4891 270.0 N 2 171 K5
TOP 247 4.24595 1.52847 270.0 N 0 122 K6
TOP 248 4.24595 1.56784 270.0 N 2 172 K7
TOP 249 4.24595 1.60721 270.0 N 10 6 K8
TOP 250 4.24595 1.64658 270.0 N 2 173 K9
TOP 251 4.24595 1.68595 270.0 N 8 3 K10
TOP 252 4.24595 1.72532 270.0 N 2 174 K11
TOP 253 4.24595 1.76469 270.0 N 8 4 K12
TOP 254 4.24595 1.80406 270.0 N 424 2 K13
TOP 255 4.24595 1.84343 270.0 N 445 2 K14
TOP 256 4.24595 1.8828 270.0 N 2 175 K15
TOP 257 4.24595 1.92217 270.0 N 422 0 K16
TOP 258 4.24595 1.96154 270.0 N 0 123 K17
TOP 259 4.24595 2.00091 270.0 N 0 124 K18
TOP 260 4.24595 2.04028 270.0 N 0 125 K19
TOP 261 4.24595 2.07965 270.0 N 1 43 K20
TOP 262 4.24595 2.11902 270.0 N 373 0 K21
TOP 263 4.24595 2.15839 270.0 N 382 0 K22
TOP 264 4.28532 1.33161 270.0 N 0 126 L1
TOP 265 4.28532 1.37098 270.0 N 2 176 L2
TOP 266 4.28532 1.41035 270.0 N 0 127 L3
TOP 267 4.28532 1.44973 270.0 N 0 128 L4
TOP 268 4.28532 1.4891 270.0 N 0 129 L5
TOP 269 4.28532 1.52847 270.0 N 0 130 L6
TOP 270 4.28532 1.56784 270.0 N 10 7 L7
TOP 271 4.28532 1.60721 270.0 N 2 177 L8
TOP 272 4.28532 1.64658 270.0 N 2 178 L9
TOP 273 4.28532 1.68595 270.0 N 2 179 L10
TOP 274 4.28532 1.72532 270.0 N 10 8 L11
TOP 275 4.28532 1.76469 270.0 N 328 0 L12
TOP 276 4.28532 1.80406 270.0 N 446 2 L13
TOP 277 4.28532 1.84343 270.0 N 369 0 L14
TOP 278 4.28532 1.8828 270.0 N 535 0 L15
TOP 279 4.28532 1.92217 270.0 N 0 131 L16
TOP 280 4.28532 1.96154 270.0 N 1 44 L17
TOP 281 4.28532 2.00091 270.0 N 0 132 L18
TOP 282 4.28532 2.04028 270.0 N 0 133 L19
TOP 283 4.28532 2.07965 270.0 N 0 134 L20
TOP 284 4.28532 2.11902 270.0 N 397 0 L21
TOP 285 4.28532 2.15839 270.0 N 2 180 L22
TOP 286 4.32469 1.33161 270.0 N 0 135 M1
TOP 287 4.32469 1.37098 270.0 N 0 136 M2
TOP 288 4.32469 1.41035 270.0 N 0 137 M3
TOP 289 4.32469 1.44973 270.0 N 9 9 M4
TOP 290 4.32469 1.4891 270.0 N 560 1 M5
TOP 291 4.32469 1.52847 270.0 N 559 1 M6
TOP 292 4.32469 1.56784 270.0 N 2 181 M7
TOP 293 4.32469 1.60721 270.0 N 10 9 M8
TOP 294 4.32469 1.64658 270.0 N 2 182 M9
TOP 295 4.32469 1.68595 270.0 N 2 183 M10
TOP 296 4.32469 1.72532 270.0 N 2 184 M11
TOP 297 4.32469 1.76469 270.0 N 8 5 M12
TOP 298 4.32469 1.80406 270.0 N 400 2 M13
TOP 299 4.32469 1.84343 270.0 N 1 45 M14
TOP 300 4.32469 1.8828 270.0 N 257 0 M15
TOP 301 4.32469 1.92217 270.0 N 352 0 M16
TOP 302 4.32469 1.96154 270.0 N 0 138 M17
TOP 303 4.32469 2.00091 270.0 N 473 1 M18
TOP 304 4.32469 2.04028 270.0 N 2 185 M19
TOP 305 4.32469 2.07965 270.0 N 0 139 M20
TOP 306 4.32469 2.11902 270.0 N 396 0 M21
TOP 307 4.32469 2.15839 270.0 N 472 1 M22
TOP 308 4.36406 1.33161 270.0 N 9 10 N1
TOP 309 4.36406 1.37098 270.0 N 564 1 N2
TOP 310 4.36406 1.41035 270.0 N 0 140 N3
TOP 311 4.36406 1.44973 270.0 N 0 141 N4
TOP 312 4.36406 1.4891 270.0 N 566 1 N5
TOP 313 4.36406 1.52847 270.0 N 2 186 N6
TOP 314 4.36406 1.56784 270.0 N 10 10 N7
TOP 315 4.36406 1.60721 270.0 N 2 187 N8
TOP 316 4.36406 1.64658 270.0 N 2 188 N9
TOP 317 4.36406 1.68595 270.0 N 2 189 N10
TOP 318 4.36406 1.72532 270.0 N 10 11 N11
TOP 319 4.36406 1.76469 270.0 N 314 1 N12
TOP 320 4.36406 1.80406 270.0 N 0 142 N13
TOP 321 4.36406 1.84343 270.0 N 0 143 N14
TOP 322 4.36406 1.8828 270.0 N 259 0 N15
TOP 323 4.36406 1.92217 270.0 N 2 190 N16
TOP 324 4.36406 1.96154 270.0 N 509 1 N17
TOP 325 4.36406 2.00091 270.0 N 333 0 N18
TOP 326 4.36406 2.04028 270.0 N 334 0 N19
TOP 327 4.36406 2.07965 270.0 N 336 0 N20
TOP 328 4.36406 2.11902 270.0 N 1 46 N21
TOP 329 4.36406 2.15839 270.0 N 407 1 N22
TOP 330 4.40343 1.33161 270.0 N 562 1 P1
TOP 331 4.40343 1.37098 270.0 N 563 1 P2
TOP 332 4.40343 1.41035 270.0 N 2 191 P3
TOP 333 4.40343 1.44973 270.0 N 558 1 P4
TOP 334 4.40343 1.4891 270.0 N 557 1 P5
TOP 335 4.40343 1.52847 270.0 N 565 1 P6
TOP 336 4.40343 1.56784 270.0 N 2 192 P7
TOP 337 4.40343 1.60721 270.0 N 10 12 P8
TOP 338 4.40343 1.64658 270.0 N 2 193 P9
TOP 339 4.40343 1.68595 270.0 N 10 13 P10
TOP 340 4.40343 1.72532 270.0 N 2 194 P11
TOP 341 4.40343 1.76469 270.0 N 8 6 P12
TOP 342 4.40343 1.80406 270.0 N 2 195 P13
TOP 343 4.40343 1.84343 270.0 N 256 0 P14
TOP 344 4.40343 1.8828 270.0 N 419 0 P15
TOP 345 4.40343 1.92217 270.0 N 421 0 P16
TOP 346 4.40343 1.96154 270.0 N 0 144 P17
TOP 347 4.40343 2.00091 270.0 N 1 47 P18
TOP 348 4.40343 2.04028 270.0 N 0 145 P19
TOP 349 4.40343 2.07965 270.0 N 260 0 P20
TOP 350 4.40343 2.11902 270.0 N 405 0 P21
TOP 351 4.40343 2.15839 270.0 N 340 0 P22
TOP 352 4.4428 1.33161 270.0 N 561 1 R1
TOP 353 4.4428 1.37098 270.0 N 0 146 R2
TOP 354 4.4428 1.41035 270.0 N 0 147 R3
TOP 355 4.4428 1.44973 270.0 N 47 0 R4
TOP 356 4.4428 1.4891 270.0 N 9 11 R5
TOP 357 4.4428 1.52847 270.0 N 0 148 R6
TOP 358 4.4428 1.56784 270.0 N 10 14 R7
TOP 359 4.4428 1.60721 270.0 N 2 196 R8
TOP 360 4.4428 1.64658 270.0 N 10 15 R9
TOP 361 4.4428 1.68595 270.0 N 2 197 R10
TOP 362 4.4428 1.72532 270.0 N 8 7 R11
TOP 363 4.4428 1.76469 270.0 N 2 198 R12
TOP 364 4.4428 1.80406 270.0 N 282 0 R13
TOP 365 4.4428 1.84343 270.0 N 254 0 R14
TOP 366 4.4428 1.8828 270.0 N 1 48 R15
TOP 367 4.4428 1.92217 270.0 N 0 149 R16
TOP 368 4.4428 1.96154 270.0 N 0 150 R17
TOP 369 4.4428 2.00091 270.0 N 0 151 R18
TOP 370 4.4428 2.04028 270.0 N 0 152 R19
TOP 371 4.4428 2.07965 270.0 N 2 199 R20
TOP 372 4.4428 2.11902 270.0 N 413 0 R21
TOP 373 4.4428 2.15839 270.0 N 344 0 R22
TOP 374 4.48217 1.33161 270.0 N 0 153 T1
TOP 375 4.48217 1.37098 270.0 N 9 12 T2
TOP 376 4.48217 1.41035 270.0 N 0 154 T3
TOP 377 4.48217 1.44973 270.0 N 49 0 T4
TOP 378 4.48217 1.4891 270.0 N 0 155 T5
TOP 379 4.48217 1.52847 270.0 N 0 156 T6
TOP 380 4.48217 1.56784 270.0 N 2 200 T7
TOP 381 4.48217 1.60721 270.0 N 10 16 T8
TOP 382 4.48217 1.64658 270.0 N 2 201 T9
TOP 383 4.48217 1.68595 270.0 N 10 17 T10
TOP 384 4.48217 1.72532 270.0 N 2 202 T11
TOP 385 4.48217 1.76469 270.0 N 1 49 T12
TOP 386 4.48217 1.80406 270.0 N 281 0 T13
TOP 387 4.48217 1.84343 270.0 N 0 157 T14
TOP 388 4.48217 1.8828 270.0 N 0 158 T15
TOP 389 4.48217 1.92217 270.0 N 508 1 T16
TOP 390 4.48217 1.96154 270.0 N 2 203 T17
TOP 391 4.48217 2.00091 270.0 N 0 159 T18
TOP 392 4.48217 2.04028 270.0 N 425 0 T19
TOP 393 4.48217 2.07965 270.0 N 0 160 T20
TOP 394 4.48217 2.11902 270.0 N 0 161 T21
TOP 395 4.48217 2.15839 270.0 N 1 50 T22
TOP 396 4.52154 1.33161 270.0 N 0 162 U1
TOP 397 4.52154 1.37098 270.0 N 0 163 U2
TOP 398 4.52154 1.41035 270.0 N 0 164 U3
TOP 399 4.52154 1.44973 270.0 N 2 204 U4
TOP 400 4.52154 1.4891 270.0 N 0 165 U5
TOP 401 4.52154 1.52847 270.0 N 0 166 U6
TOP 402 4.52154 1.56784 270.0 N 0 167 U7
TOP 403 4.52154 1.60721 270.0 N 315 0 U8
TOP 404 4.52154 1.64658 270.0 N 337 0 U9
TOP 405 4.52154 1.68595 270.0 N 335 0 U10
TOP 406 4.52154 1.72532 270.0 N 332 0 U11
TOP 407 4.52154 1.76469 270.0 N 203 1 U12
TOP 408 4.52154 1.80406 270.0 N 316 0 U13
TOP 409 4.52154 1.84343 270.0 N 2 205 U14
TOP 410 4.52154 1.8828 270.0 N 0 168 U15
TOP 411 4.52154 1.92217 270.0 N 519 0 U16
TOP 412 4.52154 1.96154 270.0 N 0 169 U17
TOP 413 4.52154 2.00091 270.0 N 0 170 U18
TOP 414 4.52154 2.04028 270.0 N 1 51 U19
TOP 415 4.52154 2.07965 270.0 N 0 171 U20
TOP 416 4.52154 2.11902 270.0 N 0 172 U21
TOP 417 4.52154 2.15839 270.0 N 338 0 U22
TOP 418 4.56091 1.33161 270.0 N 2 206 V1
TOP 419 4.56091 1.37098 270.0 N 0 173 V2
TOP 420 4.56091 1.41035 270.0 N 0 174 V3
TOP 421 4.56091 1.44973 270.0 N 0 175 V4
TOP 422 4.56091 1.4891 270.0 N 0 176 V5
TOP 423 4.56091 1.52847 270.0 N 9 13 V6
TOP 424 4.56091 1.56784 270.0 N 0 177 V7
TOP 425 4.56091 1.60721 270.0 N 541 1 V8
TOP 426 4.56091 1.64658 270.0 N 540 1 V9
TOP 427 4.56091 1.68595 270.0 N 264 0 V10
TOP 428 4.56091 1.72532 270.0 N 2 207 V11
TOP 429 4.56091 1.76469 270.0 N 279 0 V12
TOP 430 4.56091 1.80406 270.0 N 517 0 V13
TOP 431 4.56091 1.84343 270.0 N 0 178 V14
TOP 432 4.56091 1.8828 270.0 N 249 0 V15
TOP 433 4.56091 1.92217 270.0 N 1 52 V16
TOP 434 4.56091 1.96154 270.0 N 0 179 V17
TOP 435 4.56091 2.00091 270.0 N 0 180 V18
TOP 436 4.56091 2.04028 270.0 N 0 181 V19
TOP 437 4.56091 2.07965 270.0 N 0 182 V20
TOP 438 4.56091 2.11902 270.0 N 2 208 V21
TOP 439 4.56091 2.15839 270.0 N 0 183 V22
TOP 440 4.60028 1.33161 270.0 N 357 0 W1
TOP 441 4.60028 1.37098 270.0 N 0 184 W2
TOP 442 4.60028 1.41035 270.0 N 9 14 W3
TOP 443 4.60028 1.44973 270.0 N 0 185 W4
TOP 444 4.60028 1.4891 270.0 N 0 186 W5
TOP 445 4.60028 1.52847 270.0 N 0 187 W6
TOP 446 4.60028 1.56784 270.0 N 0 188 W7
TOP 447 4.60028 1.60721 270.0 N 2 209 W8
TOP 448 4.60028 1.64658 270.0 N 546 1 W9
TOP 449 4.60028 1.68595 270.0 N 266 0 W10
TOP 450 4.60028 1.72532 270.0 N 296 0 W11
TOP 451 4.60028 1.76469 270.0 N 298 0 W12
TOP 452 4.60028 1.80406 270.0 N 1 53 W13
TOP 453 4.60028 1.84343 270.0 N 263 0 W14
TOP 454 4.60028 1.8828 270.0 N 0 189 W15
TOP 455 4.60028 1.92217 270.0 N 0 190 W16
TOP 456 4.60028 1.96154 270.0 N 0 191 W17
TOP 457 4.60028 2.00091 270.0 N 2 210 W18
TOP 458 4.60028 2.04028 270.0 N 392 0 W19
TOP 459 4.60028 2.07965 270.0 N 393 0 W20
TOP 460 4.60028 2.11902 270.0 N 0 192 W21
TOP 461 4.60028 2.15839 270.0 N 0 193 W22
TOP 462 4.63965 1.33161 270.0 N 358 0 Y1
TOP 463 4.63965 1.37098 270.0 N 0 194 Y2
TOP 464 4.63965 1.41035 270.0 N 0 195 Y3
TOP 465 4.63965 1.44973 270.0 N 0 196 Y4
TOP 466 4.63965 1.4891 270.0 N 2 211 Y5
TOP 467 4.63965 1.52847 270.0 N 0 197 Y6
TOP 468 4.63965 1.56784 270.0 N 545 1 Y7
TOP 469 4.63965 1.60721 270.0 N 544 1 Y8
TOP 470 4.63965 1.64658 270.0 N 547 1 Y9
TOP 471 4.63965 1.68595 270.0 N 1 54 Y10
TOP 472 4.63965 1.72532 270.0 N 430 0 Y11
TOP 473 4.63965 1.76469 270.0 N 434 0 Y12
TOP 474 4.63965 1.80406 270.0 N 0 198 Y13
TOP 475 4.63965 1.84343 270.0 N 261 0 Y14
TOP 476 4.63965 1.8828 270.0 N 2 212 Y15
TOP 477 4.63965 1.92217 270.0 N 262 0 Y16
TOP 478 4.63965 1.96154 270.0 N 0 199 Y17
TOP 479 4.63965 2.00091 270.0 N 391 0 Y18
TOP 480 4.63965 2.04028 270.0 N 0 200 Y19
TOP 481 4.63965 2.07965 270.0 N 1 55 Y20
TOP 482 4.63965 2.11902 270.0 N 0 201 Y21
TOP 483 4.63965 2.15839 270.0 N 0 202 Y22
#
# CMP 171
CMP 39 5.245 1.595 0.0 N C175 ??? ;0=1,1=0.110000
PRP REUSE_ID '21' 
PRP ALT_SYMBOLS '(SMC_1210R_H110)' 
PRP PARENT_PART_TYPE 'CAPACITOR' 
PRP PARENT_PPT 'CAPACITOR' 
PRP PARENT_PPT_PART 'CAPACITOR-G109-0G107-BM,100UF,20%' 
PRP PART_NAME 'CAPACITOR' 
TOP 0 5.1925 1.595 0.0 N 10 18 1
TOP 1 5.2975 1.595 0.0 N 2 213 2
#
# CMP 172
CMP 39 5.245 1.345 0.0 N C176 ??? ;0=1,1=0.110000
PRP REUSE_ID '19' 
PRP ALT_SYMBOLS '(SMC_1210R_H110)' 
PRP PARENT_PART_TYPE 'CAPACITOR' 
PRP PARENT_PPT 'CAPACITOR' 
PRP PARENT_PPT_PART 'CAPACITOR-G109-0G107-BM,100UF,20%' 
PRP PART_NAME 'CAPACITOR' 
TOP 0 5.1925 1.345 0.0 N 10 19 1
TOP 1 5.2975 1.345 0.0 N 2 214 2
#
# CMP 173
CMP 39 5.245 1.47 0.0 N C177 ??? ;0=1,1=0.110000
PRP REUSE_ID '20' 
PRP ALT_SYMBOLS '(SMC_1210R_H110)' 
PRP PARENT_PART_TYPE 'CAPACITOR' 
PRP PARENT_PPT 'CAPACITOR' 
PRP PARENT_PPT_PART 'CAPACITOR-G109-0G107-BM,100UF,20%' 
PRP PART_NAME 'CAPACITOR' 
TOP 0 5.1925 1.47 0.0 N 10 20 1
TOP 1 5.2975 1.47 0.0 N 2 215 2
#
# CMP 174
CMP 39 4.74 2.489 270.0 N C174 ??? ;0=1,1=0.110000
PRP ALT_SYMBOLS '(SMC_1210R_H110)' 
PRP PARENT_PART_TYPE 'CAPACITOR' 
PRP PARENT_PPT 'CAPACITOR' 
PRP PARENT_PPT_PART 'CAPACITOR-G109-0G107-BM,100UF,20%' 
PRP PART_NAME 'CAPACITOR' 
TOP 0 4.74 2.4365 270.0 N 1 56 1
TOP 1 4.74 2.5415 270.0 N 2 216 2
#
# CMP 175
CMP 40 3.582 2.782 90.0 N C198 ??? ;0=1,1=0.025590
PRP ALT_SYMBOLS '(SMC_0402R_C_H026,C0402_BGA,C0402-0P8MM-45DG,C0402-1MM-TRIANGLE-S0)' 
PRP PARENT_PART_TYPE 'CAPACITOR' 
PRP PARENT_PPT 'CAPACITOR' 
PRP PARENT_PPT_PART 'CAPACITOR-G105-0F475-BM,4.7UF,20%' 
PRP PART_NAME 'CAPACITOR' 
TOP 0 3.582 2.803 90.0 N 1 57 1
TOP 1 3.582 2.761 90.0 N 2 217 2
#
# CMP 176
CMP 42 5.506 3.569 180.0 N FU1 ??? ;0=1,1=0.021650
PRP REUSE_ID '25' 
PRP ALT_SYMBOLS '(SMC_0603R_H022)' 
PRP PARENT_PART_TYPE 'FUSE' 
PRP PARENT_PPT 'FUSE' 
PRP PARENT_PPT_PART 'FUSE-G280-10012-01,2.5A' 
PRP PART_NAME 'FUSE' 
TOP 0 5.533 3.569 180.0 N 30 3 1
TOP 1 5.479 3.569 180.0 N 3 4 2
#
# CMP 177
CMP 42 5.341 3.902 0.0 N R9 ??? ;0=1,1=0.021650
PRP REUSE_ID '6' 
PRP ALT_SYMBOLS '(SMC_0603R_H022)' 
PRP PARENT_PART_TYPE 'RESISTOR' 
PRP PARENT_PPT 'RESISTOR' 
PRP PARENT_PPT_PART 'RESISTOR-G156-049R9-01,49.9OHM,1%' 
PRP PART_NAME 'RESISTOR' 
TOP 0 5.314 3.902 0.0 N 30 4 1
TOP 1 5.368 3.902 0.0 N 120 0 2
#
# CMP 178
CMP 43 5.421 3.306 0.0 N CR10 ??? ;0=1,1=0.103150
PRP REUSE_ID '32' 
PRP ALT_SYMBOLS '(SMC_CR_270X232_V1)' 
PRP PARENT_PART_TYPE 'DIODE_2E' 
PRP PARENT_PPT 'DIODE_2E' 
PRP PARENT_PPT_PART 'DIODE_2E-G122-10190-01' 
PRP PART_NAME 'DIODE_2E' 
TOP 0 5.29108 3.306 0.0 N 2 218 A
TOP 1 5.55092 3.306 0.0 N 30 5 C
#
# CMP 179
CMP 46 3.54401 1.91549 270.0 N U11 ??? ;0=1,1=0.031500
PRP ALT_SYMBOLS '(QFN12_071_P0157)' 
PRP PARENT_PART_TYPE 'TS3USB3031RMGR_WQFN12' 
PRP PARENT_PPT 'TS3USB3031RMGR_WQFN12' 
PRP PARENT_PPT_PART 'TS3USB3031RMGR_WQFN12-G220-10368-01,TS3USB3031RMGR' 
PRP PART_NAME 'TS3USB3031RMGR_WQFN12' 
TOP 0 3.53614 1.88543 270.0 N 250 0 1
TOP 1 3.55189 1.88543 270.0 N 252 0 2
TOP 2 3.58207 1.89187 270.0 N 256 1 3
TOP 3 3.58207 1.90762 270.0 N 254 1 4
TOP 4 3.58207 1.92336 270.0 N 205 0 5
TOP 5 3.58207 1.93911 270.0 N 204 0 6
TOP 6 3.55189 1.94555 270.0 N 0 203 7
TOP 7 3.53614 1.94555 270.0 N 0 204 8
TOP 8 3.50595 1.93911 270.0 N 2 219 9
TOP 9 3.50595 1.92336 270.0 N 253 0 10
TOP 10 3.50595 1.90762 270.0 N 255 0 11
TOP 11 3.50595 1.89187 270.0 N 1 58 12
#
# CMP 180
CMP 47 1.646 3.966 270.0 N U5 ??? ;0=1,1=0.039370
PRP REUSE_ID '9' 
PRP ALT_SYMBOLS '(QFN18_138_P0197_V1)' 
PRP PARENT_PART_TYPE 'TPS54824RNVR_VQFN18' 
PRP PARENT_PPT 'TPS54824RNVR_VQFN18' 
PRP PARENT_PPT_PART 'TPS54824RNVR_VQFN18-G220-10657-01,TPS54424RNVT' 
PRP PART_NAME 'TPS54824RNVR_VQFN18' 
TOP 0 1.6086 3.90104 270.0 N 383 0 1
TOP 1 1.63222 3.91187 270.0 N 84 1 2
TOP 2 1.65781 3.91187 270.0 N 2 220 3
TOP 3 1.67946 3.91187 270.0 N 2 221 4
TOP 4 1.70112 3.91187 270.0 N 2 222 5
TOP 5 1.66962 3.9532 270.0 N 107 0 6
TOP 6 1.66962 3.9788 270.0 N 107 1 7
TOP 7 1.70112 4.02013 270.0 N 2 223 8
TOP 8 1.67946 4.02013 270.0 N 2 224 9
TOP 9 1.65781 4.02013 270.0 N 2 225 10
TOP 10 1.63222 4.02013 270.0 N 84 2 11
TOP 11 1.6086 4.03096 270.0 N 90 0 12
TOP 12 1.58104 4.02013 270.0 N 370 0 13
TOP 13 1.58104 3.99553 270.0 N 12 0 14
TOP 14 1.58104 3.97584 270.0 N 105 0 15
TOP 15 1.58104 3.95616 270.0 N 89 0 16
TOP 16 1.58104 3.93647 270.0 N 82 0 17
TOP 17 1.58104 3.91187 270.0 N 126 0 18
#
# CMP 181
CMP 47 3.353 4.012 90.0 N U6 ??? ;0=1,1=0.039370
PRP REUSE_ID '5' 
PRP ALT_SYMBOLS '(QFN18_138_P0197_V1)' 
PRP PARENT_PART_TYPE 'TPS54824RNVR_VQFN18' 
PRP PARENT_PPT 'TPS54824RNVR_VQFN18' 
PRP PARENT_PPT_PART 'TPS54824RNVR_VQFN18-G220-10657-01,TPS54424RNVT' 
PRP PART_NAME 'TPS54824RNVR_VQFN18' 
TOP 0 3.3904 4.07696 90.0 N 432 0 1
TOP 1 3.36678 4.06613 90.0 N 110 1 2
TOP 2 3.34119 4.06613 90.0 N 2 226 3
TOP 3 3.31954 4.06613 90.0 N 2 227 4
TOP 4 3.29788 4.06613 90.0 N 2 228 5
TOP 5 3.32938 4.0248 90.0 N 118 0 6
TOP 6 3.32938 3.9992 90.0 N 118 1 7
TOP 7 3.29788 3.95787 90.0 N 2 229 8
TOP 8 3.31954 3.95787 90.0 N 2 230 9
TOP 9 3.34119 3.95787 90.0 N 2 231 10
TOP 10 3.36678 3.95787 90.0 N 110 2 11
TOP 11 3.3904 3.94704 90.0 N 112 0 12
TOP 12 3.41796 3.95787 90.0 N 415 0 13
TOP 13 3.41796 3.98247 90.0 N 18 0 14
TOP 14 3.41796 4.00216 90.0 N 116 0 15
TOP 15 3.41796 4.02184 90.0 N 111 0 16
TOP 16 3.41796 4.04153 90.0 N 79 1 17
TOP 17 3.41796 4.06613 90.0 N 127 0 18
#
# CMP 182
CMP 47 5.575 2.155 0.0 N U26 ??? ;0=1,1=0.039370
PRP ALT_SYMBOLS '(QFN18_138_P0197_V1)' 
PRP PARENT_PART_TYPE 'TPS54824RNVR_VQFN18' 
PRP PARENT_PPT 'TPS54824RNVR_VQFN18' 
PRP PARENT_PPT_PART 'TPS54824RNVR_VQFN18-G220-10657-01,TPS54424RNVT' 
PRP PART_NAME 'TPS54824RNVR_VQFN18' 
TOP 0 5.51004 2.1924 0.0 N 349 0 1
TOP 1 5.52087 2.16878 0.0 N 55 1 2
TOP 2 5.52087 2.14319 0.0 N 2 232 3
TOP 3 5.52087 2.12154 0.0 N 2 233 4
TOP 4 5.52087 2.09988 0.0 N 2 234 5
TOP 5 5.5622 2.13138 0.0 N 64 1 6
TOP 6 5.5878 2.13138 0.0 N 64 2 7
TOP 7 5.62913 2.09988 0.0 N 2 235 8
TOP 8 5.62913 2.12154 0.0 N 2 236 9
TOP 9 5.62913 2.14319 0.0 N 2 237 10
TOP 10 5.62913 2.16878 0.0 N 55 2 11
TOP 11 5.63996 2.1924 0.0 N 58 0 12
TOP 12 5.62913 2.21996 0.0 N 347 0 13
TOP 13 5.60453 2.21996 0.0 N 67 0 14
TOP 14 5.58484 2.21996 0.0 N 62 0 15
TOP 15 5.56516 2.21996 0.0 N 57 0 16
TOP 16 5.54547 2.21996 0.0 N 54 0 17
TOP 17 5.52087 2.21996 0.0 N 56 0 18
#
# CMP 183
CMP 48 1.7727 0.665 180.0 N U2 ??? ;0=1,1=0.068900
PRP ALT_SYMBOLS '(SOP8_154_P050_V1)' 
PRP PARENT_PART_TYPE 'G220_10198_01' 
PRP PARENT_PPT 'G220_10198_01' 
PRP PARENT_PPT_PART 'G220_10198_01-G223-10197-01' 
PRP PART_NAME 'G220_10198_01' 
TOP 0 1.8832 0.59 180.0 N 348 0 1
TOP 1 1.8832 0.64 180.0 N 307 0 2
TOP 2 1.8832 0.69 180.0 N 185 0 3
TOP 3 1.8832 0.74 180.0 N 2 238 4
TOP 4 1.6622 0.74 180.0 N 0 205 5
TOP 5 1.6622 0.69 180.0 N 186 0 6
TOP 6 1.6622 0.64 180.0 N 306 0 7
TOP 7 1.6622 0.59 180.0 N 1 59 8
#
# CMP 184
CMP 49 1.961 3.976 0.0 N L1 ??? ;0=1,1=0.118110
PRP REUSE_ID '3' 
PRP ALT_SYMBOLS '(SMC_L_287X268_V3)' 
PRP PARENT_PART_TYPE 'INDUCTOR_2' 
PRP PARENT_PPT 'INDUCTOR_2' 
PRP PARENT_PPT_PART 'INDUCTOR_2-G190-10424-01,4.7UH,20%' 
PRP PART_NAME 'INDUCTOR_2' 
TOP 0 1.84387 3.976 0.0 N 107 2 1
TOP 1 2.07813 3.976 0.0 N 13 3 2
#
# CMP 185
CMP 49 3.05 3.865 90.0 N L2 ??? ;0=1,1=0.118110
PRP REUSE_ID '1' 
PRP ALT_SYMBOLS '(SMC_L_287X268_V3)' 
PRP PARENT_PART_TYPE 'INDUCTOR_2' 
PRP PARENT_PPT 'INDUCTOR_2' 
PRP PARENT_PPT_PART 'INDUCTOR_2-G190-10424-01,4.7UH,20%' 
PRP PART_NAME 'INDUCTOR_2' 
TOP 0 3.05 3.98213 90.0 N 118 2 1
TOP 1 3.05 3.74787 90.0 N 19 7 2
#
# CMP 186
CMP 50 2.135 3.175 90.0 N U35 ??? ;0=1,1=0.043700
PRP REUSE_ID '1' 
PRP ALT_SYMBOLS '(SOP8_118_P0256_V2)' 
PRP PARENT_PART_TYPE 'LM75BDP_TSSOP8' 
PRP PARENT_PPT 'LM75BDP_TSSOP8' 
PRP PARENT_PPT_PART 'LM75BDP_TSSOP8-G220-10215-01' 
PRP PART_NAME 'LM75BDP_TSSOP8' 
TOP 0 2.1734 3.2655 90.0 N 464 0 1
TOP 1 2.1478 3.2655 90.0 N 331 0 2
TOP 2 2.1222 3.2655 90.0 N 472 2 3
TOP 3 2.0966 3.2655 90.0 N 2 239 4
TOP 4 2.0966 3.0845 90.0 N 466 0 5
TOP 5 2.1222 3.0845 90.0 N 468 0 6
TOP 6 2.1478 3.0845 90.0 N 470 0 7
TOP 7 2.1734 3.0845 90.0 N 1 60 8
#
# CMP 187
CMP 50 0.821 2.337 270.0 N U32 ??? ;0=1,1=0.043700
PRP ALT_SYMBOLS '(SOP8_118_P0256_V2)' 
PRP PARENT_PART_TYPE 'PCA9508DP_TSSOP8' 
PRP PARENT_PPT 'PCA9508DP_TSSOP8' 
PRP PARENT_PPT_PART 'PCA9508DP_TSSOP8-G223-10278-01' 
PRP PART_NAME 'PCA9508DP_TSSOP8' 
TOP 0 0.7826 2.2465 270.0 N 72 2 1
TOP 1 0.8082 2.2465 270.0 N 387 0 2
TOP 2 0.8338 2.2465 270.0 N 388 0 3
TOP 3 0.8594 2.2465 270.0 N 2 240 4
TOP 4 0.8594 2.4275 270.0 N 386 0 5
TOP 5 0.8338 2.4275 270.0 N 363 0 6
TOP 6 0.8082 2.4275 270.0 N 364 0 7
TOP 7 0.7826 2.4275 270.0 N 19 8 8
#
# CMP 188
CMP 50 6.175 1.045 0.0 N U36 ??? ;0=1,1=0.043700
PRP REUSE_ID '3' 
PRP ALT_SYMBOLS '(SOP8_118_P0256_V2)' 
PRP PARENT_PART_TYPE 'LM75BDP_TSSOP8' 
PRP PARENT_PPT 'LM75BDP_TSSOP8' 
PRP PARENT_PPT_PART 'LM75BDP_TSSOP8-G220-10215-01' 
PRP PART_NAME 'LM75BDP_TSSOP8' 
TOP 0 6.0845 1.0834 0.0 N 465 0 1
TOP 1 6.0845 1.0578 0.0 N 331 1 2
TOP 2 6.0845 1.0322 0.0 N 473 2 3
TOP 3 6.0845 1.0066 0.0 N 2 241 4
TOP 4 6.2655 1.0066 0.0 N 467 0 5
TOP 5 6.2655 1.0322 0.0 N 469 0 6
TOP 6 6.2655 1.0578 0.0 N 471 0 7
TOP 7 6.2655 1.0834 0.0 N 1 61 8
#
# CMP 189
CMP 51 5.536 3.737 180.0 N U1 ??? ;0=1,1=0.039370
PRP REUSE_ID '12' 
PRP ALT_SYMBOLS '(QFN26_118X197_P197_TR049X010)' 
PRP PARENT_PART_TYPE 'MP5022CGQV_Z_QFN22' 
PRP PARENT_PPT 'MP5022CGQV_Z_QFN22' 
PRP PARENT_PPT_PART 'MP5022CGQV_Z_QFN22-G220-10510-01' 
PRP PART_NAME 'MP5022CGQV_Z_QFN22' 
TOP 0 5.59271 3.65826 180.0 N 83 1 1
TOP 1 5.59271 3.67794 180.0 N 525 0 2
TOP 2 5.59271 3.69763 180.0 N 534 0 3
TOP 3 5.59271 3.71731 180.0 N 103 0 4
TOP 4 5.59271 3.737 180.0 N 490 0 5
TOP 5 5.59271 3.75669 180.0 N 113 0 6
TOP 6 5.59271 3.77637 180.0 N 2 242 7
TOP 7 5.59271 3.79606 180.0 N 124 0 8
TOP 8 5.59271 3.81574 180.0 N 293 1 9
TOP 9 5.55569 3.83456 180.0 N 276 1 10
TOP 10 5.51631 3.83456 180.0 N 128 0 11
TOP 11 5.47929 3.81574 180.0 N 120 1 12
TOP 12 5.47929 3.79606 180.0 N 3 5 13
TOP 13 5.47929 3.77637 180.0 N 3 6 14
TOP 14 5.47929 3.75669 180.0 N 3 7 15
TOP 15 5.47929 3.737 180.0 N 3 8 16
TOP 16 5.47929 3.71731 180.0 N 3 9 17
TOP 17 5.47929 3.69763 180.0 N 3 10 18
TOP 18 5.47929 3.67794 180.0 N 3 11 19
TOP 19 5.47929 3.65826 180.0 N 3 12 20
TOP 20 5.536 3.65813 180.0 N 30 6 21
TOP 21 5.55607 3.63305 180.0 N 30 7 22
TOP 22 5.536 3.69369 180.0 N 30 8 23
TOP 23 5.536 3.72913 180.0 N 30 9 24
TOP 24 5.536 3.76456 180.0 N 30 10 25
TOP 25 5.536 3.79999 180.0 N 30 11 26
#
# CMP 190
CMP 52 3.837 2.725 0.0 N R189 ??? ;0=1,1=0.013780
PRP REUSE_ID '7' 
PRP ALT_SYMBOLS '(SMC_0402R_C_H014)' 
PRP PARENT_PART_TYPE 'RESISTOR' 
PRP PARENT_PPT 'RESISTOR' 
PRP PARENT_PPT_PART 'RESISTOR-G155-03241-01,3.24KOHM,1%' 
PRP PART_NAME 'RESISTOR' 
TOP 0 3.816 2.725 0.0 N 2 243 1
TOP 1 3.858 2.725 0.0 N 310 1 2
#
# CMP 191
CMP 52 5.328 2.632 270.0 N R190 ??? ;0=1,1=0.013780
PRP ALT_SYMBOLS '(SMC_0402R_C_H014)' 
PRP PARENT_PART_TYPE 'RESISTOR' 
PRP PARENT_PPT 'RESISTOR' 
PRP PARENT_PPT_PART 'RESISTOR-G155-03241-01,3.24KOHM,1%' 
PRP PART_NAME 'RESISTOR' 
TOP 0 5.328 2.611 270.0 N 2 244 1
TOP 1 5.328 2.653 270.0 N 311 1 2
#
# CMP 192
CMP 55 3.57 2.359 270.0 N Y1 ??? ;0=1,1=0.023620
PRP ALT_SYMBOLS '(SMC_Y2_079X047)' 
PRP PARENT_PART_TYPE 'XTAL_2' 
PRP PARENT_PPT 'XTAL_2' 
PRP PARENT_PPT_PART 'XTAL_2-G131-10075-01' 
PRP PART_NAME 'XTAL_2' 
TOP 0 3.57 2.33243 270.0 N 109 1 1
TOP 1 3.57 2.38557 270.0 N 114 1 2
#
# CMP 193
CMP 56 3.985 0.97 180.0 N R240 ??? ;0=1,1=0.016000
PRP ALT_SYMBOLS '(SMC_0402R_C_H016)' 
PRP PARENT_PART_TYPE 'RESISTOR' 
PRP PARENT_PPT 'RESISTOR' 
PRP PARENT_PPT_PART 'RESISTOR-G155-11500-01,150OHM,1%' 
PRP PART_NAME 'RESISTOR' 
TOP 0 4.006 0.97 180.0 N 52 1 1
TOP 1 3.964 0.97 180.0 N 2 245 2
#
# CMP 194
CMP 56 4.08 0.97 0.0 N R242 ??? ;0=1,1=0.016000
PRP ALT_SYMBOLS '(SMC_0402R_C_H016)' 
PRP PARENT_PART_TYPE 'RESISTOR' 
PRP PARENT_PPT 'RESISTOR' 
PRP PARENT_PPT_PART 'RESISTOR-G155-11500-01,150OHM,1%' 
PRP PART_NAME 'RESISTOR' 
TOP 0 4.059 0.97 0.0 N 50 1 1
TOP 1 4.101 0.97 0.0 N 2 246 2
#
# CMP 195
CMP 56 3.77 0.895 90.0 N R236 ??? ;0=1,1=0.016000
PRP SIGNAL_MODEL 'RESISTOR-G155-100R0-J0_0OHM_-' 
PRP ALT_SYMBOLS '(SMC_0402R_C_H016)' 
PRP PARENT_PART_TYPE 'RESISTOR' 
PRP PARENT_PPT 'RESISTOR' 
PRP PARENT_PPT_PART 'RESISTOR-G155-14701-01,4.7KOHM,1%' 
PRP PART_NAME 'RESISTOR' 
TOP 0 3.77 0.916 90.0 N 42 1 1
TOP 1 3.77 0.874 90.0 N 343 1 2
#
# CMP 196
CMP 56 3.144 1.75 180.0 N R88 ??? ;0=1,1=0.016000
PRP SIGNAL_MODEL 'RESISTOR-G155-100R0-J0_0OHM_-' 
PRP ALT_SYMBOLS '(SMC_0402R_C_H016,C0402-0P8MM-45DG)' 
PRP PARENT_PART_TYPE 'RESISTOR' 
PRP PARENT_PPT 'RESISTOR' 
PRP PARENT_PPT_PART 'RESISTOR-G155-100R0-J0,0OHM,-' 
PRP PART_NAME 'RESISTOR' 
TOP 0 3.165 1.75 180.0 N 358 1 1
TOP 1 3.123 1.75 180.0 N 238 1 2
#
# CMP 197
CMP 56 3.145 1.695 0.0 N R96 ??? ;0=1,1=0.016000
PRP SIGNAL_MODEL 'DEFAULT_RESISTOR_33OHM_2_1' 
PRP ALT_SYMBOLS '(SMC_0402R_C_H016)' 
PRP PARENT_PART_TYPE 'RESISTOR' 
PRP PARENT_PPT 'RESISTOR' 
PRP PARENT_PPT_PART 'RESISTOR-G155-133R0-01,33OHM,1%' 
PRP PART_NAME 'RESISTOR' 
TOP 0 3.124 1.695 0.0 N 239 1 1
TOP 1 3.166 1.695 0.0 N 367 1 2
#
# CMP 198
CMP 56 3.145 1.645 180.0 N R287 ??? ;0=1,1=0.016000
PRP SIGNAL_MODEL 'RESISTOR-G155-100R0-J0_0OHM_-' 
PRP ALT_SYMBOLS '(SMC_0402R_C_H016)' 
PRP PARENT_PART_TYPE 'RESISTOR' 
PRP PARENT_PPT 'RESISTOR' 
PRP PARENT_PPT_PART 'RESISTOR-G155-14701-01,4.7KOHM,1%' 
PRP PART_NAME 'RESISTOR' 
TOP 0 3.166 1.645 180.0 N 367 2 1
TOP 1 3.124 1.645 180.0 N 1 62 2
#
# CMP 199
CMP 56 2.976 0.621 0.0 N R63 ??? ;0=1,1=0.016000
PRP SIGNAL_MODEL 'RESISTOR-G155-100R0-J0_0OHM_-' 
PRP ALT_SYMBOLS '(SMC_0402R_C_H016)' 
PRP PARENT_PART_TYPE 'RESISTOR' 
PRP PARENT_PPT 'RESISTOR' 
PRP PARENT_PPT_PART 'RESISTOR-G155-14701-01,4.7KOHM,1%' 
PRP PART_NAME 'RESISTOR' 
TOP 0 2.955 0.621 0.0 N 1 63 1
TOP 1 2.997 0.621 0.0 N 518 0 2
#
# CMP 200
CMP 56 2.975 0.57441 0.0 N R57 ??? ;0=1,1=0.016000
PRP SIGNAL_MODEL 'DEFAULT_RESISTOR_33OHM_2_1' 
PRP ALT_SYMBOLS '(SMC_0402R_C_H016)' 
PRP PARENT_PART_TYPE 'RESISTOR' 
PRP PARENT_PPT 'RESISTOR' 
PRP PARENT_PPT_PART 'RESISTOR-G155-133R0-01,33OHM,1%' 
PRP PART_NAME 'RESISTOR' 
TOP 0 2.954 0.57441 0.0 N 423 0 1
TOP 1 2.996 0.57441 0.0 N 518 1 2
#
# CMP 201
CMP 56 2.616 0.655 180.0 N R55 ??? ;0=1,1=0.016000
PRP SIGNAL_MODEL 'RESISTOR-G155-100R0-J0_0OHM_-' 
PRP ALT_SYMBOLS '(SMC_0402R_C_H016)' 
PRP PARENT_PART_TYPE 'RESISTOR' 
PRP PARENT_PPT 'RESISTOR' 
PRP PARENT_PPT_PART 'RESISTOR-G155-14701-01,4.7KOHM,1%' 
PRP PART_NAME 'RESISTOR' 
TOP 0 2.637 0.655 180.0 N 184 0 1
TOP 1 2.595 0.655 180.0 N 2 247 2
#
# CMP 202
CMP 56 2.616 0.605 0.0 N R56 ??? ;0=1,1=0.016000
PRP SIGNAL_MODEL 'RESISTOR-G155-100R0-J0_0OHM_-' 
PRP ALT_SYMBOLS '(SMC_0402R_C_H016)' 
PRP PARENT_PART_TYPE 'RESISTOR' 
PRP PARENT_PPT 'RESISTOR' 
PRP PARENT_PPT_PART 'RESISTOR-G155-14701-01,4.7KOHM,1%' 
PRP PART_NAME 'RESISTOR' 
TOP 0 2.595 0.605 0.0 N 19 9 1
TOP 1 2.637 0.605 0.0 N 184 1 2
#
# CMP 203
CMP 56 2.51122 0.605 90.0 N R22 ??? ;0=1,1=0.016000
PRP SIGNAL_MODEL 'RESISTOR-G155-100R0-J0_0OHM_-' 
PRP ALT_SYMBOLS '(SMC_0402R_C_H016,C0402-0P8MM-45DG)' 
PRP PARENT_PART_TYPE 'RESISTOR' 
PRP PARENT_PPT 'RESISTOR' 
PRP PARENT_PPT_PART 'RESISTOR-G155-100R0-J0,0OHM,-' 
PRP PART_NAME 'RESISTOR' 
TOP 0 2.51122 0.626 90.0 N 179 0 1
TOP 1 2.51122 0.584 90.0 N 189 0 2
#
# CMP 204
CMP 56 2.0477 0.611 90.0 N R25 ??? ;0=1,1=0.016000
PRP SIGNAL_MODEL 'RESISTOR-G155-100R0-J0_0OHM_-' 
PRP ALT_SYMBOLS '(SMC_0402R_C_H016)' 
PRP PARENT_PART_TYPE 'RESISTOR' 
PRP PARENT_PPT 'RESISTOR' 
PRP PARENT_PPT_PART 'RESISTOR-G155-14701-01,4.7KOHM,1%' 
PRP PART_NAME 'RESISTOR' 
TOP 0 2.0477 0.632 90.0 N 1 64 1
TOP 1 2.0477 0.59 90.0 N 348 1 2
#
# CMP 205
CMP 56 1.9977 0.611 90.0 N R354 ??? ;0=1,1=0.016000
PRP SIGNAL_MODEL 'DEFAULT_RESISTOR_33OHM_2_1' 
PRP ALT_SYMBOLS '(SMC_0402R_C_H016)' 
PRP PARENT_PART_TYPE 'RESISTOR' 
PRP PARENT_PPT 'RESISTOR' 
PRP PARENT_PPT_PART 'RESISTOR-G155-133R0-01,33OHM,1%' 
PRP PART_NAME 'RESISTOR' 
TOP 0 1.9977 0.632 90.0 N 422 1 1
TOP 1 1.9977 0.59 90.0 N 348 2 2
#
# CMP 206
CMP 56 3.604 1.76649 90.0 N R104 ??? ;0=1,1=0.016000
PRP SIGNAL_MODEL 'RESISTOR-G155-100R0-J0_0OHM_-' 
PRP ALT_SYMBOLS '(SMC_0402R_C_H016)' 
PRP PARENT_PART_TYPE 'RESISTOR' 
PRP PARENT_PPT 'RESISTOR' 
PRP PARENT_PPT_PART 'RESISTOR-G155-14701-01,4.7KOHM,1%' 
PRP PART_NAME 'RESISTOR' 
TOP 0 3.604 1.78749 90.0 N 252 1 1
TOP 1 3.604 1.74549 90.0 N 2 248 2
#
# CMP 207
CMP 56 3.554 1.76649 270.0 N R266 ??? ;0=1,1=0.016000
PRP SIGNAL_MODEL 'DEFAULT_RESISTOR_33OHM_2_1' 
PRP ALT_SYMBOLS '(SMC_0402R_C_H016)' 
PRP PARENT_PART_TYPE 'RESISTOR' 
PRP PARENT_PPT 'RESISTOR' 
PRP PARENT_PPT_PART 'RESISTOR-G155-133R0-01,33OHM,1%' 
PRP PART_NAME 'RESISTOR' 
TOP 0 3.554 1.74549 270.0 N 352 1 1
TOP 1 3.554 1.78749 270.0 N 250 1 2
#
# CMP 208
CMP 56 3.14 1.85 0.0 N R98 ??? ;0=1,1=0.016000
PRP SIGNAL_MODEL 'RESISTOR-G155-100R0-J0_0OHM_-' 
PRP ALT_SYMBOLS '(SMC_0402R_C_H016,C0402-0P8MM-45DG)' 
PRP PARENT_PART_TYPE 'RESISTOR' 
PRP PARENT_PPT 'RESISTOR' 
PRP PARENT_PPT_PART 'RESISTOR-G155-100R0-J0,0OHM,-' 
PRP PART_NAME 'RESISTOR' 
TOP 0 3.119 1.85 0.0 N 234 1 1
TOP 1 3.161 1.85 0.0 N 253 1 2
#
# CMP 209
CMP 56 3.14 1.895 0.0 N R97 ??? ;0=1,1=0.016000
PRP SIGNAL_MODEL 'RESISTOR-G155-100R0-J0_0OHM_-' 
PRP ALT_SYMBOLS '(SMC_0402R_C_H016,C0402-0P8MM-45DG)' 
PRP PARENT_PART_TYPE 'RESISTOR' 
PRP PARENT_PPT 'RESISTOR' 
PRP PARENT_PPT_PART 'RESISTOR-G155-100R0-J0,0OHM,-' 
PRP PART_NAME 'RESISTOR' 
TOP 0 3.119 1.895 0.0 N 232 1 1
TOP 1 3.161 1.895 0.0 N 255 1 2
#
# CMP 210
CMP 56 3.144 1.8 180.0 N R87 ??? ;0=1,1=0.016000
PRP SIGNAL_MODEL 'RESISTOR-G155-100R0-J0_0OHM_-' 
PRP ALT_SYMBOLS '(SMC_0402R_C_H016,C0402-0P8MM-45DG)' 
PRP PARENT_PART_TYPE 'RESISTOR' 
PRP PARENT_PPT 'RESISTOR' 
PRP PARENT_PPT_PART 'RESISTOR-G155-100R0-J0,0OHM,-' 
PRP PART_NAME 'RESISTOR' 
TOP 0 3.165 1.8 180.0 N 357 1 1
TOP 1 3.123 1.8 180.0 N 237 1 2
#
# CMP 211
CMP 56 4.375 4.115 180.0 N R366 ??? ;0=1,1=0.016000
PRP SIGNAL_MODEL 'DEFAULT_RESISTOR_33OHM_2_1' 
PRP ALT_SYMBOLS '(SMC_0402R_C_H016)' 
PRP PARENT_PART_TYPE 'RESISTOR' 
PRP PARENT_PPT 'RESISTOR' 
PRP PARENT_PPT_PART 'RESISTOR-G155-133R0-01,33OHM,1%' 
PRP PART_NAME 'RESISTOR' 
TOP 0 4.396 4.115 180.0 N 385 0 1
TOP 1 4.354 4.115 180.0 N 390 1 2
#
# CMP 212
CMP 56 4.375 4.065 180.0 N R364 ??? ;0=1,1=0.016000
PRP SIGNAL_MODEL 'DEFAULT_RESISTOR_33OHM_2_1' 
PRP ALT_SYMBOLS '(SMC_0402R_C_H016)' 
PRP PARENT_PART_TYPE 'RESISTOR' 
PRP PARENT_PPT 'RESISTOR' 
PRP PARENT_PPT_PART 'RESISTOR-G155-133R0-01,33OHM,1%' 
PRP PART_NAME 'RESISTOR' 
TOP 0 4.396 4.065 180.0 N 384 0 1
TOP 1 4.354 4.065 180.0 N 389 1 2
#
# CMP 213
CMP 56 4.65 2.32 270.0 N R362 ??? ;0=1,1=0.016000
PRP SIGNAL_MODEL 'RESISTOR-G155-133R0-01_33OHM_1%' 
PRP ALT_SYMBOLS '(SMC_0402R_C_H016)' 
PRP PARENT_PART_TYPE 'RESISTOR' 
PRP PARENT_PPT 'RESISTOR' 
PRP PARENT_PPT_PART 'RESISTOR-G155-133R0-01,33OHM,1%' 
PRP PART_NAME 'RESISTOR' 
TOP 0 4.65 2.299 270.0 N 425 1 1
TOP 1 4.65 2.341 270.0 N 426 1 2
#
# CMP 214
CMP 56 4.62 2.44 270.0 N R348 ??? ;0=1,1=0.016000
PRP ALT_SYMBOLS '(SMC_0402R_C_H016)' 
PRP PARENT_PART_TYPE 'RESISTOR' 
PRP PARENT_PPT 'RESISTOR' 
PRP PARENT_PPT_PART 'RESISTOR-G155-133R0-01,33OHM,1%' 
PRP PART_NAME 'RESISTOR' 
TOP 0 4.62 2.419 270.0 N 413 1 1
TOP 1 4.62 2.461 270.0 N 414 1 2
#
# CMP 215
CMP 56 4.53 2.44 270.0 N R339 ??? ;0=1,1=0.016000
PRP ALT_SYMBOLS '(SMC_0402R_C_H016)' 
PRP PARENT_PART_TYPE 'RESISTOR' 
PRP PARENT_PPT 'RESISTOR' 
PRP PARENT_PPT_PART 'RESISTOR-G155-133R0-01,33OHM,1%' 
PRP PART_NAME 'RESISTOR' 
TOP 0 4.53 2.419 270.0 N 405 1 1
TOP 1 4.53 2.461 270.0 N 406 1 2
#
# CMP 216
CMP 56 4.535 2.345 270.0 N R238 ??? ;0=1,1=0.016000
PRP SIGNAL_MODEL 'RESISTOR-G155-133R0-01_33OHM_1%' 
PRP ALT_SYMBOLS '(SMC_0402R_C_H016)' 
PRP PARENT_PART_TYPE 'RESISTOR' 
PRP PARENT_PPT 'RESISTOR' 
PRP PARENT_PPT_PART 'RESISTOR-G155-133R0-01,33OHM,1%' 
PRP PART_NAME 'RESISTOR' 
TOP 0 4.535 2.324 270.0 N 344 1 1
TOP 1 4.535 2.366 270.0 N 345 1 2
#
# CMP 217
CMP 56 4.485 2.44 270.0 N R234 ??? ;0=1,1=0.016000
PRP SIGNAL_MODEL 'RESISTOR-G155-133R0-01_33OHM_1%' 
PRP ALT_SYMBOLS '(SMC_0402R_C_H016)' 
PRP PARENT_PART_TYPE 'RESISTOR' 
PRP PARENT_PPT 'RESISTOR' 
PRP PARENT_PPT_PART 'RESISTOR-G155-133R0-01,33OHM,1%' 
PRP PART_NAME 'RESISTOR' 
TOP 0 4.485 2.419 270.0 N 340 1 1
TOP 1 4.485 2.461 270.0 N 341 1 2
#
# CMP 218
CMP 56 3.71 2.71 0.0 N R167 ??? ;0=1,1=0.016000
PRP SIGNAL_MODEL 'RESISTOR-G155-100R0-J0_0OHM_-' 
PRP ALT_SYMBOLS '(SMC_0402R_C_H016)' 
PRP PARENT_PART_TYPE 'RESISTOR' 
PRP PARENT_PPT 'RESISTOR' 
PRP PARENT_PPT_PART 'RESISTOR-G155-14701-01,4.7KOHM,1%' 
PRP PART_NAME 'RESISTOR' 
TOP 0 3.689 2.71 0.0 N 1 65 1
TOP 1 3.731 2.71 0.0 N 303 1 2
#
# CMP 219
CMP 56 3.76 2.405 270.0 N R164 ??? ;0=1,1=0.016000
PRP ALT_SYMBOLS '(SMC_0402R_C_H016)' 
PRP PARENT_PART_TYPE 'RESISTOR' 
PRP PARENT_PPT 'RESISTOR' 
PRP PARENT_PPT_PART 'RESISTOR-G155-11003-01,100KOHM,1%' 
PRP PART_NAME 'RESISTOR' 
TOP 0 3.76 2.384 270.0 N 1 66 1
TOP 1 3.76 2.426 270.0 N 45 0 2
#
# CMP 220
CMP 56 0.455 1.199 90.0 N R496 ??? ;0=1,1=0.016000
PRP ALT_SYMBOLS '(SMC_0402R_C_H016)' 
PRP PARENT_PART_TYPE 'RESISTOR' 
PRP PARENT_PPT 'RESISTOR' 
PRP PARENT_PPT_PART 'RESISTOR-G155-11004-01,1MOHM,1%' 
PRP PART_NAME 'RESISTOR' 
TOP 0 0.455 1.22 90.0 N 2 249 1
TOP 1 0.455 1.178 90.0 N 268 2 2
#
# CMP 221
CMP 56 0.443 0.668 90.0 N R497 ??? ;0=1,1=0.016000
PRP ALT_SYMBOLS '(SMC_0402R_C_H016)' 
PRP PARENT_PART_TYPE 'RESISTOR' 
PRP PARENT_PPT 'RESISTOR' 
PRP PARENT_PPT_PART 'RESISTOR-G155-11004-01,1MOHM,1%' 
PRP PART_NAME 'RESISTOR' 
TOP 0 0.443 0.689 90.0 N 2 250 1
TOP 1 0.443 0.647 90.0 N 269 2 2
#
# CMP 222
CMP 56 0.452 2.347 90.0 N R498 ??? ;0=1,1=0.016000
PRP ALT_SYMBOLS '(SMC_0402R_C_H016)' 
PRP PARENT_PART_TYPE 'RESISTOR' 
PRP PARENT_PPT 'RESISTOR' 
PRP PARENT_PPT_PART 'RESISTOR-G155-11004-01,1MOHM,1%' 
PRP PART_NAME 'RESISTOR' 
TOP 0 0.452 2.368 90.0 N 2 251 1
TOP 1 0.452 2.326 90.0 N 273 2 2
#
# CMP 223
CMP 56 0.455 1.665 270.0 N R499 ??? ;0=1,1=0.016000
PRP ALT_SYMBOLS '(SMC_0402R_C_H016)' 
PRP PARENT_PART_TYPE 'RESISTOR' 
PRP PARENT_PPT 'RESISTOR' 
PRP PARENT_PPT_PART 'RESISTOR-G155-11004-01,1MOHM,1%' 
PRP PART_NAME 'RESISTOR' 
TOP 0 0.455 1.644 270.0 N 2 252 1
TOP 1 0.455 1.686 270.0 N 272 2 2
#
# CMP 224
CMP 56 1.835 2.96 90.0 N R487 ??? ;0=1,1=0.016000
PRP SIGNAL_MODEL 'RESISTOR-G155-100R0-J0_0OHM_-' 
PRP ALT_SYMBOLS '(SMC_0402R_C_H016)' 
PRP PARENT_PART_TYPE 'RESISTOR' 
PRP PARENT_PPT 'RESISTOR' 
PRP PARENT_PPT_PART 'RESISTOR-G155-14701-01,4.7KOHM,1%' 
PRP PART_NAME 'RESISTOR' 
TOP 0 1.835 2.981 90.0 N 85 3 1
TOP 1 1.835 2.939 90.0 N 86 1 2
#
# CMP 225
CMP 56 4.405 3.7 0.0 N R452 ??? ;0=1,1=0.016000
PRP SIGNAL_MODEL 'RESISTOR-G155-100R0-J0_0OHM_-' 
PRP ALT_SYMBOLS '(SMC_0402R_C_H016)' 
PRP PARENT_PART_TYPE 'RESISTOR' 
PRP PARENT_PPT 'RESISTOR' 
PRP PARENT_PPT_PART 'RESISTOR-G155-14701-01,4.7KOHM,1%' 
PRP PART_NAME 'RESISTOR' 
TOP 0 4.384 3.7 0.0 N 246 2 1
TOP 1 4.426 3.7 0.0 N 1 67 2
#
# CMP 226
CMP 56 4.715 0.915 0.0 N R486 ??? ;0=1,1=0.016000
PRP SIGNAL_MODEL 'DEFAULT_RESISTOR_33OHM_2_1' 
PRP ALT_SYMBOLS '(SMC_0402R_C_H016)' 
PRP PARENT_PART_TYPE 'RESISTOR' 
PRP PARENT_PPT 'RESISTOR' 
PRP PARENT_PPT_PART 'RESISTOR-G155-133R0-01,33OHM,1%' 
PRP PART_NAME 'RESISTOR' 
TOP 0 4.694 0.915 0.0 N 515 1 1
TOP 1 4.736 0.915 0.0 N 512 2 2
#
# CMP 227
CMP 56 4.715 0.965 0.0 N R485 ??? ;0=1,1=0.016000
PRP SIGNAL_MODEL 'DEFAULT_RESISTOR_33OHM_2_1' 
PRP ALT_SYMBOLS '(SMC_0402R_C_H016)' 
PRP PARENT_PART_TYPE 'RESISTOR' 
PRP PARENT_PPT 'RESISTOR' 
PRP PARENT_PPT_PART 'RESISTOR-G155-133R0-01,33OHM,1%' 
PRP PART_NAME 'RESISTOR' 
TOP 0 4.694 0.965 0.0 N 514 1 1
TOP 1 4.736 0.965 0.0 N 512 3 2
#
# CMP 228
CMP 56 0.725 3.2 180.0 N R472 ??? ;0=1,1=0.016000
PRP SIGNAL_MODEL 'RESISTOR-G155-100R0-J0_0OHM_-' 
PRP ALT_SYMBOLS '(SMC_0402R_C_H016,C0402-0P8MM-45DG)' 
PRP PARENT_PART_TYPE 'RESISTOR' 
PRP PARENT_PPT 'RESISTOR' 
PRP PARENT_PPT_PART 'RESISTOR-G155-100R0-J0,0OHM,-' 
PRP PART_NAME 'RESISTOR' 
TOP 0 0.746 3.2 180.0 N 505 1 1
TOP 1 0.704 3.2 180.0 N 506 2 2
#
# CMP 229
CMP 56 0.725 3.245 180.0 N R471 ??? ;0=1,1=0.016000
PRP SIGNAL_MODEL 'RESISTOR-G155-100R0-J0_0OHM_-' 
PRP ALT_SYMBOLS '(SMC_0402R_C_H016,C0402-0P8MM-45DG)' 
PRP PARENT_PART_TYPE 'RESISTOR' 
PRP PARENT_PPT 'RESISTOR' 
PRP PARENT_PPT_PART 'RESISTOR-G155-100R0-J0,0OHM,-' 
PRP PART_NAME 'RESISTOR' 
TOP 0 0.746 3.245 180.0 N 503 1 1
TOP 1 0.704 3.245 180.0 N 504 2 2
#
# CMP 230
CMP 56 3.994 3.239 0.0 N R462 ??? ;0=1,1=0.016000
PRP SIGNAL_MODEL 'DEFAULT_RESISTOR_33OHM_2_1' 
PRP ALT_SYMBOLS '(SMC_0402R_C_H016)' 
PRP PARENT_PART_TYPE 'RESISTOR' 
PRP PARENT_PPT 'RESISTOR' 
PRP PARENT_PPT_PART 'RESISTOR-G155-133R0-01,33OHM,1%' 
PRP PART_NAME 'RESISTOR' 
TOP 0 3.973 3.239 0.0 N 493 1 1
TOP 1 4.015 3.239 0.0 N 488 4 2
#
# CMP 231
CMP 56 3.994 3.291 0.0 N R461 ??? ;0=1,1=0.016000
PRP SIGNAL_MODEL 'DEFAULT_RESISTOR_33OHM_2_1' 
PRP ALT_SYMBOLS '(SMC_0402R_C_H016)' 
PRP PARENT_PART_TYPE 'RESISTOR' 
PRP PARENT_PPT 'RESISTOR' 
PRP PARENT_PPT_PART 'RESISTOR-G155-133R0-01,33OHM,1%' 
PRP PART_NAME 'RESISTOR' 
TOP 0 3.973 3.291 0.0 N 492 1 1
TOP 1 4.015 3.291 0.0 N 488 5 2
#
# CMP 232
CMP 56 3.86 3.758 180.0 N R449 ??? ;0=1,1=0.016000
PRP SIGNAL_MODEL 'DEFAULT_RESISTOR_33OHM_2_1' 
PRP ALT_SYMBOLS '(SMC_0402R_C_H016)' 
PRP PARENT_PART_TYPE 'RESISTOR' 
PRP PARENT_PPT 'RESISTOR' 
PRP PARENT_PPT_PART 'RESISTOR-G155-133R0-01,33OHM,1%' 
PRP PART_NAME 'RESISTOR' 
TOP 0 3.881 3.758 180.0 N 482 2 1
TOP 1 3.839 3.758 180.0 N 484 1 2
#
# CMP 233
CMP 56 3.86 3.81 180.0 N R448 ??? ;0=1,1=0.016000
PRP SIGNAL_MODEL 'DEFAULT_RESISTOR_33OHM_2_1' 
PRP ALT_SYMBOLS '(SMC_0402R_C_H016)' 
PRP PARENT_PART_TYPE 'RESISTOR' 
PRP PARENT_PPT 'RESISTOR' 
PRP PARENT_PPT_PART 'RESISTOR-G155-133R0-01,33OHM,1%' 
PRP PART_NAME 'RESISTOR' 
TOP 0 3.881 3.81 180.0 N 482 3 1
TOP 1 3.839 3.81 180.0 N 483 1 2
#
# CMP 234
CMP 56 5.27 0.87 180.0 N R484 ??? ;0=1,1=0.016000
PRP ALT_SYMBOLS '(SMC_0402R_C_H016)' 
PRP PARENT_PART_TYPE 'RESISTOR' 
PRP PARENT_PPT 'RESISTOR' 
PRP PARENT_PPT_PART 'RESISTOR-G155-11001-01,1KOHM,1%' 
PRP PART_NAME 'RESISTOR' 
TOP 0 5.291 0.87 180.0 N 2 253 1
TOP 1 5.249 0.87 180.0 N 513 1 2
#
# CMP 235
CMP 56 4.533 3.22 180.0 N R459 ??? ;0=1,1=0.016000
PRP ALT_SYMBOLS '(SMC_0402R_C_H016)' 
PRP PARENT_PART_TYPE 'RESISTOR' 
PRP PARENT_PPT 'RESISTOR' 
PRP PARENT_PPT_PART 'RESISTOR-G155-11001-01,1KOHM,1%' 
PRP PART_NAME 'RESISTOR' 
TOP 0 4.554 3.22 180.0 N 2 254 1
TOP 1 4.512 3.22 180.0 N 489 1 2
#
# CMP 236
CMP 56 4.405 3.745 0.0 N R453 ??? ;0=1,1=0.016000
PRP ALT_SYMBOLS '(SMC_0402R_C_H016)' 
PRP PARENT_PART_TYPE 'RESISTOR' 
PRP PARENT_PPT 'RESISTOR' 
PRP PARENT_PPT_PART 'RESISTOR-G155-11001-01,1KOHM,1%' 
PRP PART_NAME 'RESISTOR' 
TOP 0 4.384 3.745 0.0 N 246 3 1
TOP 1 4.426 3.745 0.0 N 2 255 2
#
# CMP 237
CMP 56 1.055 3.71 90.0 N R456 ??? ;0=1,1=0.016000
PRP SIGNAL_MODEL 'RESISTOR-G155-11000-01_100OHM_A' 
PRP ALT_SYMBOLS '(SMC_0402R_C_H016)' 
PRP PARENT_PART_TYPE 'RESISTOR' 
PRP PARENT_PPT 'RESISTOR' 
PRP PARENT_PPT_PART 'RESISTOR-G155-11000-01,100OHM,1%' 
PRP PART_NAME 'RESISTOR' 
TOP 0 1.055 3.731 90.0 N 487 1 1
TOP 1 1.055 3.689 90.0 N 245 2 2
#
# CMP 238
CMP 56 4.34 3.475 90.0 N R443 ??? ;0=1,1=0.016000
PRP SIGNAL_MODEL 'RESISTOR-G155-11000-01_100OHM_A' 
PRP ALT_SYMBOLS '(SMC_0402R_C_H016)' 
PRP PARENT_PART_TYPE 'RESISTOR' 
PRP PARENT_PPT 'RESISTOR' 
PRP PARENT_PPT_PART 'RESISTOR-G155-11000-01,100OHM,1%' 
PRP PART_NAME 'RESISTOR' 
TOP 0 4.34 3.496 90.0 N 245 3 1
TOP 1 4.34 3.454 90.0 N 478 1 2
#
# CMP 239
CMP 56 4.08 3.45 270.0 N R465 ??? ;0=1,1=0.016000
PRP SIGNAL_MODEL 'RESISTOR-G155-100R0-J0_0OHM_-' 
PRP ALT_SYMBOLS '(SMC_0402R_C_H016,C0402-0P8MM-45DG)' 
PRP PARENT_PART_TYPE 'RESISTOR' 
PRP PARENT_PPT 'RESISTOR' 
PRP PARENT_PPT_PART 'RESISTOR-G155-100R0-J0,0OHM,-' 
PRP PART_NAME 'RESISTOR' 
TOP 0 4.08 3.429 270.0 N 414 2 1
TOP 1 4.08 3.471 270.0 N 327 1 2
#
# CMP 240
CMP 56 3.87 3.445 270.0 N R464 ??? ;0=1,1=0.016000
PRP SIGNAL_MODEL 'RESISTOR-G155-100R0-J0_0OHM_-' 
PRP ALT_SYMBOLS '(SMC_0402R_C_H016,C0402-0P8MM-45DG)' 
PRP PARENT_PART_TYPE 'RESISTOR' 
PRP PARENT_PPT 'RESISTOR' 
PRP PARENT_PPT_PART 'RESISTOR-G155-100R0-J0,0OHM,-' 
PRP PART_NAME 'RESISTOR' 
TOP 0 3.87 3.424 270.0 N 406 2 1
TOP 1 3.87 3.466 270.0 N 326 1 2
#
# CMP 241
CMP 56 1.175 2.96 90.0 N R481 ??? ;0=1,1=0.016000
PRP ALT_SYMBOLS '(SMC_0402R_C_H016)' 
PRP PARENT_PART_TYPE 'RESISTOR' 
PRP PARENT_PPT 'RESISTOR' 
PRP PARENT_PPT_PART 'RESISTOR-G155-11003-01,100KOHM,1%' 
PRP PART_NAME 'RESISTOR' 
TOP 0 1.175 2.981 90.0 N 418 1 1
TOP 1 1.175 2.939 90.0 N 88 9 2
#
# CMP 242
CMP 56 1.025 2.96 270.0 N R480 ??? ;0=1,1=0.016000
PRP ALT_SYMBOLS '(SMC_0402R_C_H016)' 
PRP PARENT_PART_TYPE 'RESISTOR' 
PRP PARENT_PPT 'RESISTOR' 
PRP PARENT_PPT_PART 'RESISTOR-G155-11003-01,100KOHM,1%' 
PRP PART_NAME 'RESISTOR' 
TOP 0 1.025 2.939 270.0 N 421 1 1
TOP 1 1.025 2.981 270.0 N 88 10 2
#
# CMP 243
CMP 56 5.27 0.82 180.0 N R477 ??? ;0=1,1=0.016000
PRP ALT_SYMBOLS '(SMC_0402R_C_H016)' 
PRP PARENT_PART_TYPE 'RESISTOR' 
PRP PARENT_PPT 'RESISTOR' 
PRP PARENT_PPT_PART 'RESISTOR-G155-11003-01,100KOHM,1%' 
PRP PART_NAME 'RESISTOR' 
TOP 0 5.291 0.82 180.0 N 1 68 1
TOP 1 5.249 0.82 180.0 N 511 2 2
#
# CMP 244
CMP 56 5.27 0.76 180.0 N R476 ??? ;0=1,1=0.016000
PRP ALT_SYMBOLS '(SMC_0402R_C_H016)' 
PRP PARENT_PART_TYPE 'RESISTOR' 
PRP PARENT_PPT 'RESISTOR' 
PRP PARENT_PPT_PART 'RESISTOR-G155-11003-01,100KOHM,1%' 
PRP PART_NAME 'RESISTOR' 
TOP 0 5.291 0.76 180.0 N 1 69 1
TOP 1 5.249 0.76 180.0 N 510 2 2
#
# CMP 245
CMP 56 4.715 0.785 0.0 N R475 ??? ;0=1,1=0.016000
PRP ALT_SYMBOLS '(SMC_0402R_C_H016)' 
PRP PARENT_PART_TYPE 'RESISTOR' 
PRP PARENT_PPT 'RESISTOR' 
PRP PARENT_PPT_PART 'RESISTOR-G155-11003-01,100KOHM,1%' 
PRP PART_NAME 'RESISTOR' 
TOP 0 4.694 0.785 0.0 N 1 70 1
TOP 1 4.736 0.785 0.0 N 509 2 2
#
# CMP 246
CMP 56 4.715 0.865 0.0 N R474 ??? ;0=1,1=0.016000
PRP ALT_SYMBOLS '(SMC_0402R_C_H016)' 
PRP PARENT_PART_TYPE 'RESISTOR' 
PRP PARENT_PPT 'RESISTOR' 
PRP PARENT_PPT_PART 'RESISTOR-G155-11003-01,100KOHM,1%' 
PRP PART_NAME 'RESISTOR' 
TOP 0 4.694 0.865 0.0 N 1 71 1
TOP 1 4.736 0.865 0.0 N 508 2 2
#
# CMP 247
CMP 56 4.575 2.44 270.0 N R435 ??? ;0=1,1=0.016000
PRP ALT_SYMBOLS '(SMC_0402R_C_H016)' 
PRP PARENT_PART_TYPE 'RESISTOR' 
PRP PARENT_PPT 'RESISTOR' 
PRP PARENT_PPT_PART 'RESISTOR-G155-11003-01,100KOHM,1%' 
PRP PART_NAME 'RESISTOR' 
TOP 0 4.575 2.419 270.0 N 345 2 1
TOP 1 4.575 2.461 270.0 N 1 72 2
#
# CMP 248
CMP 56 1.53 3.025 90.0 N R490 ??? ;0=1,1=0.016000
PRP SIGNAL_MODEL 'RESISTOR-G155-100R0-J0_0OHM_-' 
PRP ALT_SYMBOLS '(SMC_0402R_C_H016)' 
PRP PARENT_PART_TYPE 'RESISTOR' 
PRP PARENT_PPT 'RESISTOR' 
PRP PARENT_PPT_PART 'RESISTOR-G155-11002-01,10KOHM,1%' 
PRP PART_NAME 'RESISTOR' 
TOP 0 1.53 3.046 90.0 N 88 11 1
TOP 1 1.53 3.004 90.0 N 516 1 2
#
# CMP 249
CMP 56 4.53 1.16 90.0 N R439 ??? ;0=1,1=0.016000
PRP SIGNAL_MODEL 'RESISTOR-G155-100R0-J0_0OHM_-' 
PRP ALT_SYMBOLS '(SMC_0402R_C_H016)' 
PRP PARENT_PART_TYPE 'RESISTOR' 
PRP PARENT_PPT 'RESISTOR' 
PRP PARENT_PPT_PART 'RESISTOR-G155-11002-01,10KOHM,1%' 
PRP PART_NAME 'RESISTOR' 
TOP 0 4.53 1.181 90.0 N 357 2 1
TOP 1 4.53 1.139 90.0 N 9 15 2
#
# CMP 250
CMP 56 4.585 1.16 90.0 N R438 ??? ;0=1,1=0.016000
PRP SIGNAL_MODEL 'RESISTOR-G155-100R0-J0_0OHM_-' 
PRP ALT_SYMBOLS '(SMC_0402R_C_H016)' 
PRP PARENT_PART_TYPE 'RESISTOR' 
PRP PARENT_PPT 'RESISTOR' 
PRP PARENT_PPT_PART 'RESISTOR-G155-11002-01,10KOHM,1%' 
PRP PART_NAME 'RESISTOR' 
TOP 0 4.585 1.181 90.0 N 358 2 1
TOP 1 4.585 1.139 90.0 N 9 16 2
#
# CMP 251
CMP 56 4.15 2.531 90.0 N R327 ??? ;0=1,1=0.016000
PRP SIGNAL_MODEL 'RESISTOR-G155-100R0-J0_0OHM_-' 
PRP ALT_SYMBOLS '(SMC_0402R_C_H016)' 
PRP PARENT_PART_TYPE 'RESISTOR' 
PRP PARENT_PPT 'RESISTOR' 
PRP PARENT_PPT_PART 'RESISTOR-G155-11002-01,10KOHM,1%' 
PRP PART_NAME 'RESISTOR' 
TOP 0 4.15 2.552 90.0 N 1 73 1
TOP 1 4.15 2.51 90.0 N 397 1 2
#
# CMP 252
CMP 56 4.209 2.531 90.0 N R325 ??? ;0=1,1=0.016000
PRP SIGNAL_MODEL 'RESISTOR-G155-100R0-J0_0OHM_-' 
PRP ALT_SYMBOLS '(SMC_0402R_C_H016)' 
PRP PARENT_PART_TYPE 'RESISTOR' 
PRP PARENT_PPT 'RESISTOR' 
PRP PARENT_PPT_PART 'RESISTOR-G155-11002-01,10KOHM,1%' 
PRP PART_NAME 'RESISTOR' 
TOP 0 4.209 2.552 90.0 N 1 74 1
TOP 1 4.209 2.51 90.0 N 396 1 2
#
# CMP 253
CMP 56 4.093 2.531 90.0 N R308 ??? ;0=1,1=0.016000
PRP SIGNAL_MODEL 'RESISTOR-G155-100R0-J0_0OHM_-' 
PRP ALT_SYMBOLS '(SMC_0402R_C_H016)' 
PRP PARENT_PART_TYPE 'RESISTOR' 
PRP PARENT_PPT 'RESISTOR' 
PRP PARENT_PPT_PART 'RESISTOR-G155-11002-01,10KOHM,1%' 
PRP PART_NAME 'RESISTOR' 
TOP 0 4.093 2.552 90.0 N 1 75 1
TOP 1 4.093 2.51 90.0 N 382 1 2
#
# CMP 254
CMP 56 3.801 2.531 90.0 N R285 ??? ;0=1,1=0.016000
PRP SIGNAL_MODEL 'RESISTOR-G155-100R0-J0_0OHM_-' 
PRP ALT_SYMBOLS '(SMC_0402R_C_H016)' 
PRP PARENT_PART_TYPE 'RESISTOR' 
PRP PARENT_PPT 'RESISTOR' 
PRP PARENT_PPT_PART 'RESISTOR-G155-11002-01,10KOHM,1%' 
PRP PART_NAME 'RESISTOR' 
TOP 0 3.801 2.552 90.0 N 1 76 1
TOP 1 3.801 2.51 90.0 N 366 1 2
#
# CMP 255
CMP 56 3.86 2.531 90.0 N R283 ??? ;0=1,1=0.016000
PRP SIGNAL_MODEL 'RESISTOR-G155-100R0-J0_0OHM_-' 
PRP ALT_SYMBOLS '(SMC_0402R_C_H016)' 
PRP PARENT_PART_TYPE 'RESISTOR' 
PRP PARENT_PPT 'RESISTOR' 
PRP PARENT_PPT_PART 'RESISTOR-G155-11002-01,10KOHM,1%' 
PRP PART_NAME 'RESISTOR' 
TOP 0 3.86 2.552 90.0 N 1 77 1
TOP 1 3.86 2.51 90.0 N 365 1 2
#
# CMP 256
CMP 56 0.61 3.29 0.0 N R445 ??? ;0=1,1=0.016000
PRP ALT_SYMBOLS '(SMC_0402R_C_H016)' 
PRP PARENT_PART_TYPE 'RESISTOR' 
PRP PARENT_PPT 'RESISTOR' 
PRP PARENT_PPT_PART 'RESISTOR-G155-05101-01,5.1KOHM,1%' 
PRP PART_NAME 'RESISTOR' 
TOP 0 0.589 3.29 0.0 N 209 1 1
TOP 1 0.631 3.29 0.0 N 2 256 2
#
# CMP 257
CMP 56 0.595 3.575 270.0 N R442 ??? ;0=1,1=0.016000
PRP HARD_LOCATION 'YES' 
PRP ALT_SYMBOLS '(SMC_0402R_C_H016)' 
PRP PARENT_PART_TYPE 'RESISTOR' 
PRP PARENT_PPT 'RESISTOR' 
PRP PARENT_PPT_PART 'RESISTOR-G155-05101-01,5.1KOHM,1%' 
PRP PART_NAME 'RESISTOR' 
TOP 0 0.595 3.554 270.0 N 206 1 1
TOP 1 0.595 3.596 270.0 N 2 257 2
#
# CMP 258
CMP 56 1.25 3.75 180.0 N R455 ??? ;0=1,1=0.016000
PRP ALT_SYMBOLS '(SMC_0402R_C_H016)' 
PRP PARENT_PART_TYPE 'RESISTOR' 
PRP PARENT_PPT 'RESISTOR' 
PRP PARENT_PPT_PART 'RESISTOR-G155-11004-01,1MOHM,1%' 
PRP PART_NAME 'RESISTOR' 
TOP 0 1.271 3.75 180.0 N 129 1 1
TOP 1 1.229 3.75 180.0 N 130 1 2
#
# CMP 259
CMP 56 3.837 2.68 0.0 N R186 ??? ;0=1,1=0.016000
PRP REUSE_ID '10' 
PRP ALT_SYMBOLS '(SMC_0402R_C_H016)' 
PRP PARENT_PART_TYPE 'RESISTOR' 
PRP PARENT_PPT 'RESISTOR' 
PRP PARENT_PPT_PART 'RESISTOR-G155-03001-01,3KOHM,1%' 
PRP PART_NAME 'RESISTOR' 
TOP 0 3.816 2.68 0.0 N 2 258 1
TOP 1 3.858 2.68 0.0 N 310 2 2
#
# CMP 260
CMP 56 1.155 3.71 90.0 N R128 ??? ;0=1,1=0.016000
PRP SIGNAL_MODEL 'RESISTOR-G155-100R0-J0_0OHM_-' 
PRP ALT_SYMBOLS '(SMC_0402R_C_H016,C0402-0P8MM-45DG)' 
PRP PARENT_PART_TYPE 'RESISTOR' 
PRP PARENT_PPT 'RESISTOR' 
PRP PARENT_PPT_PART 'RESISTOR-G155-100R0-J0,0OHM,-' 
PRP PART_NAME 'RESISTOR' 
TOP 0 1.155 3.731 90.0 N 208 2 1
TOP 1 1.155 3.689 90.0 N 274 1 2
#
# CMP 261
CMP 56 1.105 3.71 90.0 N R129 ??? ;0=1,1=0.016000
PRP SIGNAL_MODEL 'RESISTOR-G155-100R0-J0_0OHM_-' 
PRP ALT_SYMBOLS '(SMC_0402R_C_H016,C0402-0P8MM-45DG)' 
PRP PARENT_PART_TYPE 'RESISTOR' 
PRP PARENT_PPT 'RESISTOR' 
PRP PARENT_PPT_PART 'RESISTOR-G155-100R0-J0,0OHM,-' 
PRP PART_NAME 'RESISTOR' 
TOP 0 1.105 3.731 90.0 N 207 2 1
TOP 1 1.105 3.689 90.0 N 275 1 2
#
# CMP 262
CMP 56 0.64 2.79 180.0 N R346 ??? ;0=1,1=0.016000
PRP HARD_LOCATION 'YES' 
PRP SIGNAL_MODEL 'RESISTOR-G155-100R0-J0_0OHM_-' 
PRP ALT_SYMBOLS '(SMC_0402R_C_H016,C0402-0P8MM-45DG)' 
PRP PARENT_PART_TYPE 'RESISTOR' 
PRP PARENT_PPT 'RESISTOR' 
PRP PARENT_PPT_PART 'RESISTOR-G155-100R0-J0,0OHM,-' 
PRP PART_NAME 'RESISTOR' 
TOP 0 0.661 2.79 180.0 N 411 1 1
TOP 1 0.619 2.79 180.0 N 2 259 2
#
# CMP 263
CMP 56 0.66348 2.614 180.0 N R347 ??? ;0=1,1=0.016000
PRP HARD_LOCATION 'YES' 
PRP SIGNAL_MODEL 'RESISTOR-G155-100R0-J0_0OHM_-' 
PRP ALT_SYMBOLS '(SMC_0402R_C_H016,C0402-0P8MM-45DG)' 
PRP PARENT_PART_TYPE 'RESISTOR' 
PRP PARENT_PPT 'RESISTOR' 
PRP PARENT_PPT_PART 'RESISTOR-G155-100R0-J0,0OHM,-' 
PRP PART_NAME 'RESISTOR' 
TOP 0 0.68448 2.614 180.0 N 412 1 1
TOP 1 0.64248 2.614 180.0 N 72 3 2
#
# CMP 264
CMP 56 0.76948 2.546 90.0 N R350 ??? ;0=1,1=0.016000
PRP HARD_LOCATION 'YES' 
PRP SIGNAL_MODEL 'RESISTOR-G155-100R0-J0_0OHM_-' 
PRP ALT_SYMBOLS '(SMC_0402R_C_H016,C0402-0P8MM-45DG)' 
PRP PARENT_PART_TYPE 'RESISTOR' 
PRP PARENT_PPT 'RESISTOR' 
PRP PARENT_PPT_PART 'RESISTOR-G155-100R0-J0,0OHM,-' 
PRP PART_NAME 'RESISTOR' 
TOP 0 0.76948 2.567 90.0 N 416 1 1
TOP 1 0.76948 2.525 90.0 N 72 4 2
#
# CMP 265
CMP 56 0.835 2.545 90.0 N R351 ??? ;0=1,1=0.016000
PRP SIGNAL_MODEL 'RESISTOR-G155-100R0-J0_0OHM_-' 
PRP ALT_SYMBOLS '(SMC_0402R_C_H016,C0402-0P8MM-45DG)' 
PRP PARENT_PART_TYPE 'RESISTOR' 
PRP PARENT_PPT 'RESISTOR' 
PRP PARENT_PPT_PART 'RESISTOR-G155-100R0-J0,0OHM,-' 
PRP PART_NAME 'RESISTOR' 
TOP 0 0.835 2.566 90.0 N 417 1 1
TOP 1 0.835 2.524 90.0 N 2 260 2
#
# CMP 266
CMP 56 4.905 2.07 180.0 N R356 ??? ;0=1,1=0.016000
PRP SIGNAL_MODEL 'RESISTOR-G155-100R0-J0_0OHM_-' 
PRP ALT_SYMBOLS '(SMC_0402R_C_H016,C0402-0P8MM-45DG)' 
PRP PARENT_PART_TYPE 'RESISTOR' 
PRP PARENT_PPT 'RESISTOR' 
PRP PARENT_PPT_PART 'RESISTOR-G155-100R0-J0,0OHM,-' 
PRP PART_NAME 'RESISTOR' 
TOP 0 4.926 2.07 180.0 N 423 1 1
TOP 1 4.884 2.07 180.0 N 314 2 2
#
# CMP 267
CMP 56 1.125 2.96 90.0 N R352 ??? ;0=1,1=0.016000
PRP SIGNAL_MODEL 'RESISTOR-G155-11000-01_100OHM_A' 
PRP ALT_SYMBOLS '(SMC_0402R_C_H016)' 
PRP PARENT_PART_TYPE 'RESISTOR' 
PRP PARENT_PPT 'RESISTOR' 
PRP PARENT_PPT_PART 'RESISTOR-G155-11000-01,100OHM,1%' 
PRP PART_NAME 'RESISTOR' 
TOP 0 1.125 2.981 90.0 N 418 2 1
TOP 1 1.125 2.939 90.0 N 419 1 2
#
# CMP 268
CMP 56 1.075 2.96 90.0 N R353 ??? ;0=1,1=0.016000
PRP SIGNAL_MODEL 'RESISTOR-G155-11000-01_100OHM_A' 
PRP ALT_SYMBOLS '(SMC_0402R_C_H016)' 
PRP PARENT_PART_TYPE 'RESISTOR' 
PRP PARENT_PPT 'RESISTOR' 
PRP PARENT_PPT_PART 'RESISTOR-G155-11000-01,100OHM,1%' 
PRP PART_NAME 'RESISTOR' 
TOP 0 1.075 2.981 90.0 N 420 1 1
TOP 1 1.075 2.939 90.0 N 421 2 2
#
# CMP 269
CMP 56 4.545 2.845 0.0 N R237 ??? ;0=1,1=0.016000
PRP SIGNAL_MODEL 'RESISTOR-G155-100R0-J0_0OHM_-' 
PRP ALT_SYMBOLS '(SMC_0402R_C_H016)' 
PRP PARENT_PART_TYPE 'RESISTOR' 
PRP PARENT_PPT 'RESISTOR' 
PRP PARENT_PPT_PART 'RESISTOR-G155-11002-01,10KOHM,1%' 
PRP PART_NAME 'RESISTOR' 
TOP 0 4.524 2.845 0.0 N 33 1 1
TOP 1 4.566 2.845 0.0 N 2 261 2
#
# CMP 270
CMP 56 4.4375 1.123 0.0 N R359 ??? ;0=1,1=0.016000
PRP HARD_LOCATION 'YES' 
PRP SIGNAL_MODEL 'RESISTOR-G155-100R0-J0_0OHM_-' 
PRP ALT_SYMBOLS '(SMC_0402R_C_H016)' 
PRP PARENT_PART_TYPE 'RESISTOR' 
PRP PARENT_PPT 'RESISTOR' 
PRP PARENT_PPT_PART 'RESISTOR-G155-11002-01,10KOHM,1%' 
PRP PART_NAME 'RESISTOR' 
TOP 0 4.4165 1.123 0.0 N 47 1 1
TOP 1 4.4585 1.123 0.0 N 2 262 2
#
# CMP 271
CMP 56 4.3455 1.123 180.0 N R360 ??? ;0=1,1=0.016000
PRP HARD_LOCATION 'YES' 
PRP SIGNAL_MODEL 'RESISTOR-G155-100R0-J0_0OHM_-' 
PRP ALT_SYMBOLS '(SMC_0402R_C_H016)' 
PRP PARENT_PART_TYPE 'RESISTOR' 
PRP PARENT_PPT 'RESISTOR' 
PRP PARENT_PPT_PART 'RESISTOR-G155-11002-01,10KOHM,1%' 
PRP PART_NAME 'RESISTOR' 
TOP 0 4.3665 1.123 180.0 N 49 1 1
TOP 1 4.3245 1.123 180.0 N 2 263 2
#
# CMP 272
CMP 56 0.53 2.605 90.0 N R120 ??? ;0=1,1=0.016000
PRP HARD_LOCATION 'YES' 
PRP SIGNAL_MODEL 'RESISTOR-G155-11000-01_100OHM_A' 
PRP REUSE_ID '8' 
PRP ALT_SYMBOLS '(SMC_0402R_C_H016)' 
PRP PARENT_PART_TYPE 'RESISTOR' 
PRP PARENT_PPT 'RESISTOR' 
PRP PARENT_PPT_PART 'RESISTOR-G155-11000-01,100OHM,1%' 
PRP PART_NAME 'RESISTOR' 
TOP 0 0.53 2.626 90.0 N 264 1 1
TOP 1 0.53 2.584 90.0 N 265 1 2
#
# CMP 273
CMP 56 0.53 2.07 90.0 N R121 ??? ;0=1,1=0.016000
PRP HARD_LOCATION 'YES' 
PRP SIGNAL_MODEL 'RESISTOR-G155-11000-01_100OHM_A' 
PRP ALT_SYMBOLS '(SMC_0402R_C_H016)' 
PRP PARENT_PART_TYPE 'RESISTOR' 
PRP PARENT_PPT 'RESISTOR' 
PRP PARENT_PPT_PART 'RESISTOR-G155-11000-01,100OHM,1%' 
PRP PART_NAME 'RESISTOR' 
TOP 0 0.53 2.091 90.0 N 266 1 1
TOP 1 0.53 2.049 90.0 N 267 1 2
#
# CMP 274
CMP 56 0.455 1.1049 90.0 N R122 ??? ;0=1,1=0.016000
PRP HARD_LOCATION 'YES' 
PRP SIGNAL_MODEL 'RESISTOR-G155-049R9-01_49.9OHMA' 
PRP REUSE_ID '9' 
PRP ALT_SYMBOLS '(SMC_0402R_C_H016)' 
PRP PARENT_PART_TYPE 'RESISTOR' 
PRP PARENT_PPT 'RESISTOR' 
PRP PARENT_PPT_PART 'RESISTOR-G155-149R9-01,49.9OHM,1%' 
PRP PART_NAME 'RESISTOR' 
TOP 0 0.455 1.1259 90.0 N 268 3 1
TOP 1 0.455 1.0839 90.0 N 138 1 2
#
# CMP 275
CMP 56 0.455 1.76 270.0 N R126 ??? ;0=1,1=0.016000
PRP HARD_LOCATION 'YES' 
PRP SIGNAL_MODEL 'RESISTOR-G155-049R9-01_49.9OHMA' 
PRP ALT_SYMBOLS '(SMC_0402R_C_H016)' 
PRP PARENT_PART_TYPE 'RESISTOR' 
PRP PARENT_PPT 'RESISTOR' 
PRP PARENT_PPT_PART 'RESISTOR-G155-149R9-01,49.9OHM,1%' 
PRP PART_NAME 'RESISTOR' 
TOP 0 0.455 1.739 270.0 N 272 3 1
TOP 1 0.455 1.781 270.0 N 135 1 2
#
# CMP 276
CMP 56 0.46452 2.254 90.0 N R127 ??? ;0=1,1=0.016000
PRP HARD_LOCATION 'YES' 
PRP SIGNAL_MODEL 'RESISTOR-G155-049R9-01_49.9OHMA' 
PRP REUSE_ID '3' 
PRP ALT_SYMBOLS '(SMC_0402R_C_H016)' 
PRP PARENT_PART_TYPE 'RESISTOR' 
PRP PARENT_PPT 'RESISTOR' 
PRP PARENT_PPT_PART 'RESISTOR-G155-149R9-01,49.9OHM,1%' 
PRP PART_NAME 'RESISTOR' 
TOP 0 0.46452 2.275 90.0 N 273 3 1
TOP 1 0.46452 2.233 90.0 N 136 1 2
#
# CMP 277
CMP 56 0.53 1.465 90.0 N R156 ??? ;0=1,1=0.016000
PRP SIGNAL_MODEL 'RESISTOR-G155-11000-01_100OHM_A' 
PRP REUSE_ID '11' 
PRP ALT_SYMBOLS '(SMC_0402R_C_H016)' 
PRP PARENT_PART_TYPE 'RESISTOR' 
PRP PARENT_PPT 'RESISTOR' 
PRP PARENT_PPT_PART 'RESISTOR-G155-11000-01,100OHM,1%' 
PRP PART_NAME 'RESISTOR' 
TOP 0 0.53 1.486 90.0 N 296 1 1
TOP 1 0.53 1.444 90.0 N 297 1 2
#
# CMP 278
CMP 56 0.535 0.905 90.0 N R157 ??? ;0=1,1=0.016000
PRP HARD_LOCATION 'YES' 
PRP SIGNAL_MODEL 'RESISTOR-G155-11000-01_100OHM_A' 
PRP REUSE_ID '2' 
PRP ALT_SYMBOLS '(SMC_0402R_C_H016)' 
PRP PARENT_PART_TYPE 'RESISTOR' 
PRP PARENT_PPT 'RESISTOR' 
PRP PARENT_PPT_PART 'RESISTOR-G155-11000-01,100OHM,1%' 
PRP PART_NAME 'RESISTOR' 
TOP 0 0.535 0.926 90.0 N 298 1 1
TOP 1 0.535 0.884 90.0 N 299 1 2
#
# CMP 279
CMP 56 0.48 1.465 270.0 N R367 ??? ;0=1,1=0.016000
PRP SIGNAL_MODEL 'RESISTOR-G155-049R9-01_49.9OHMA' 
PRP REUSE_ID '12' 
PRP ALT_SYMBOLS '(SMC_0402R_C_H016)' 
PRP PARENT_PART_TYPE 'RESISTOR' 
PRP PARENT_PPT 'RESISTOR' 
PRP PARENT_PPT_PART 'RESISTOR-G155-149R9-01,49.9OHM,1%' 
PRP PART_NAME 'RESISTOR' 
TOP 0 0.48 1.444 270.0 N 429 1 1
TOP 1 0.48 1.486 270.0 N 430 1 2
#
# CMP 280
CMP 56 0.485 0.905 270.0 N R370 ??? ;0=1,1=0.016000
PRP HARD_LOCATION 'YES' 
PRP SIGNAL_MODEL 'RESISTOR-G155-049R9-01_49.9OHMA' 
PRP REUSE_ID '5' 
PRP ALT_SYMBOLS '(SMC_0402R_C_H016)' 
PRP PARENT_PART_TYPE 'RESISTOR' 
PRP PARENT_PPT 'RESISTOR' 
PRP PARENT_PPT_PART 'RESISTOR-G155-149R9-01,49.9OHM,1%' 
PRP PART_NAME 'RESISTOR' 
TOP 0 0.485 0.884 270.0 N 433 1 1
TOP 1 0.485 0.926 270.0 N 434 1 2
#
# CMP 281
CMP 56 0.478 2.59 270.0 N R371 ??? ;0=1,1=0.016000
PRP HARD_LOCATION 'YES' 
PRP SIGNAL_MODEL 'RESISTOR-G155-049R9-01_49.9OHMA' 
PRP REUSE_ID '9' 
PRP ALT_SYMBOLS '(SMC_0402R_C_H016)' 
PRP PARENT_PART_TYPE 'RESISTOR' 
PRP PARENT_PPT 'RESISTOR' 
PRP PARENT_PPT_PART 'RESISTOR-G155-149R9-01,49.9OHM,1%' 
PRP PART_NAME 'RESISTOR' 
TOP 0 0.478 2.569 270.0 N 435 1 1
TOP 1 0.478 2.611 270.0 N 436 1 2
#
# CMP 282
CMP 56 0.48 2.07 270.0 N R372 ??? ;0=1,1=0.016000
PRP HARD_LOCATION 'YES' 
PRP SIGNAL_MODEL 'RESISTOR-G155-049R9-01_49.9OHMA' 
PRP ALT_SYMBOLS '(SMC_0402R_C_H016)' 
PRP PARENT_PART_TYPE 'RESISTOR' 
PRP PARENT_PPT 'RESISTOR' 
PRP PARENT_PPT_PART 'RESISTOR-G155-149R9-01,49.9OHM,1%' 
PRP PART_NAME 'RESISTOR' 
TOP 0 0.48 2.049 270.0 N 437 1 1
TOP 1 0.48 2.091 270.0 N 438 1 2
#
# CMP 283
CMP 56 1.456 4.142 0.0 N R34 ??? ;0=1,1=0.016000
PRP REUSE_ID '2' 
PRP ALT_SYMBOLS '(SMC_0402R_C_H016)' 
PRP PARENT_PART_TYPE 'RESISTOR' 
PRP PARENT_PPT 'RESISTOR' 
PRP PARENT_PPT_PART 'RESISTOR-G155-02402-01,24KOHM,1%' 
PRP PART_NAME 'RESISTOR' 
TOP 0 1.435 4.142 0.0 N 11 0 1
TOP 1 1.477 4.142 0.0 N 12 1 2
#
# CMP 284
CMP 56 0.33 3.21 270.0 N R399 ??? ;0=1,1=0.016000
PRP HARD_LOCATION 'YES' 
PRP SIGNAL_MODEL 'DEFAULT_RESISTOR_33OHM_2_1' 
PRP ALT_SYMBOLS '(SMC_0402R_C_H016)' 
PRP PARENT_PART_TYPE 'RESISTOR' 
PRP PARENT_PPT 'RESISTOR' 
PRP PARENT_PPT_PART 'RESISTOR-G155-133R0-01,33OHM,1%' 
PRP PART_NAME 'RESISTOR' 
TOP 0 0.33 3.189 270.0 N 461 1 1
TOP 1 0.33 3.231 270.0 N 163 1 2
#
# CMP 285
CMP 56 0.28 3.21 270.0 N R427 ??? ;0=1,1=0.016000
PRP SIGNAL_MODEL 'RESISTOR-G155-11000-01_100OHM_A' 
PRP ALT_SYMBOLS '(SMC_0402R_C_H016)' 
PRP PARENT_PART_TYPE 'RESISTOR' 
PRP PARENT_PPT 'RESISTOR' 
PRP PARENT_PPT_PART 'RESISTOR-G155-11000-01,100OHM,1%' 
PRP PART_NAME 'RESISTOR' 
TOP 0 0.28 3.189 270.0 N 477 1 1
TOP 1 0.28 3.231 270.0 N 163 2 2
#
# CMP 286
CMP 56 0.23 3.21 270.0 N R425 ??? ;0=1,1=0.016000
PRP SIGNAL_MODEL 'RESISTOR-G155-11000-01_100OHM_A' 
PRP ALT_SYMBOLS '(SMC_0402R_C_H016)' 
PRP PARENT_PART_TYPE 'RESISTOR' 
PRP PARENT_PPT 'RESISTOR' 
PRP PARENT_PPT_PART 'RESISTOR-G155-11000-01,100OHM,1%' 
PRP PART_NAME 'RESISTOR' 
TOP 0 0.23 3.189 270.0 N 475 1 1
TOP 1 0.23 3.231 270.0 N 162 1 2
#
# CMP 287
CMP 56 0.38 3.21 270.0 N R426 ??? ;0=1,1=0.016000
PRP SIGNAL_MODEL 'RESISTOR-G155-11000-01_100OHM_A' 
PRP ALT_SYMBOLS '(SMC_0402R_C_H016)' 
PRP PARENT_PART_TYPE 'RESISTOR' 
PRP PARENT_PPT 'RESISTOR' 
PRP PARENT_PPT_PART 'RESISTOR-G155-11000-01,100OHM,1%' 
PRP PART_NAME 'RESISTOR' 
TOP 0 0.38 3.189 270.0 N 476 1 1
TOP 1 0.38 3.231 270.0 N 164 1 2
#
# CMP 288
CMP 56 0.43 3.21 270.0 N R398 ??? ;0=1,1=0.016000
PRP HARD_LOCATION 'YES' 
PRP SIGNAL_MODEL 'DEFAULT_RESISTOR_33OHM_2_1' 
PRP ALT_SYMBOLS '(SMC_0402R_C_H016)' 
PRP PARENT_PART_TYPE 'RESISTOR' 
PRP PARENT_PPT 'RESISTOR' 
PRP PARENT_PPT_PART 'RESISTOR-G155-133R0-01,33OHM,1%' 
PRP PART_NAME 'RESISTOR' 
TOP 0 0.43 3.189 270.0 N 460 1 1
TOP 1 0.43 3.231 270.0 N 164 2 2
#
# CMP 289
CMP 56 0.18 3.21 270.0 N R397 ??? ;0=1,1=0.016000
PRP HARD_LOCATION 'YES' 
PRP SIGNAL_MODEL 'DEFAULT_RESISTOR_33OHM_2_1' 
PRP ALT_SYMBOLS '(SMC_0402R_C_H016)' 
PRP PARENT_PART_TYPE 'RESISTOR' 
PRP PARENT_PPT 'RESISTOR' 
PRP PARENT_PPT_PART 'RESISTOR-G155-133R0-01,33OHM,1%' 
PRP PART_NAME 'RESISTOR' 
TOP 0 0.18 3.189 270.0 N 459 1 1
TOP 1 0.18 3.231 270.0 N 162 2 2
#
# CMP 290
CMP 56 0.287 2.68508 270.0 N R376 ??? ;0=1,1=0.016000
PRP SIGNAL_MODEL 'RESISTOR-G155-11000-01_100OHM_A' 
PRP ALT_SYMBOLS '(SMC_0402R_C_H016)' 
PRP PARENT_PART_TYPE 'RESISTOR' 
PRP PARENT_PPT 'RESISTOR' 
PRP PARENT_PPT_PART 'RESISTOR-G155-11000-01,100OHM,1%' 
PRP PART_NAME 'RESISTOR' 
TOP 0 0.287 2.66408 270.0 N 442 1 1
TOP 1 0.287 2.70608 270.0 N 157 1 2
#
# CMP 291
CMP 56 0.197 2.68508 270.0 N R391 ??? ;0=1,1=0.016000
PRP HARD_LOCATION 'YES' 
PRP SIGNAL_MODEL 'DEFAULT_RESISTOR_33OHM_2_1' 
PRP ALT_SYMBOLS '(SMC_0402R_C_H016)' 
PRP PARENT_PART_TYPE 'RESISTOR' 
PRP PARENT_PPT 'RESISTOR' 
PRP PARENT_PPT_PART 'RESISTOR-G155-133R0-01,33OHM,1%' 
PRP PART_NAME 'RESISTOR' 
TOP 0 0.197 2.66408 270.0 N 453 1 1
TOP 1 0.197 2.70608 270.0 N 156 1 2
#
# CMP 292
CMP 56 0.242 2.68508 270.0 N R374 ??? ;0=1,1=0.016000
PRP SIGNAL_MODEL 'RESISTOR-G155-11000-01_100OHM_A' 
PRP ALT_SYMBOLS '(SMC_0402R_C_H016)' 
PRP PARENT_PART_TYPE 'RESISTOR' 
PRP PARENT_PPT 'RESISTOR' 
PRP PARENT_PPT_PART 'RESISTOR-G155-11000-01,100OHM,1%' 
PRP PART_NAME 'RESISTOR' 
TOP 0 0.242 2.66408 270.0 N 440 1 1
TOP 1 0.242 2.70608 270.0 N 156 2 2
#
# CMP 293
CMP 56 0.76647 1.84 180.0 N R424 ??? ;0=1,1=0.016000
PRP SIGNAL_MODEL 'RESISTOR-G155-11000-01_100OHM_A' 
PRP ALT_SYMBOLS '(SMC_0402R_C_H016)' 
PRP PARENT_PART_TYPE 'RESISTOR' 
PRP PARENT_PPT 'RESISTOR' 
PRP PARENT_PPT_PART 'RESISTOR-G155-11000-01,100OHM,1%' 
PRP PART_NAME 'RESISTOR' 
TOP 0 0.78747 1.84 180.0 N 474 1 1
TOP 1 0.74547 1.84 180.0 N 160 1 2
#
# CMP 294
CMP 56 0.76647 1.75 180.0 N R394 ??? ;0=1,1=0.016000
PRP HARD_LOCATION 'YES' 
PRP SIGNAL_MODEL 'DEFAULT_RESISTOR_33OHM_2_1' 
PRP ALT_SYMBOLS '(SMC_0402R_C_H016)' 
PRP PARENT_PART_TYPE 'RESISTOR' 
PRP PARENT_PPT 'RESISTOR' 
PRP PARENT_PPT_PART 'RESISTOR-G155-133R0-01,33OHM,1%' 
PRP PART_NAME 'RESISTOR' 
TOP 0 0.78747 1.75 180.0 N 456 1 1
TOP 1 0.74547 1.75 180.0 N 159 1 2
#
# CMP 295
CMP 56 0.76647 1.795 180.0 N R400 ??? ;0=1,1=0.016000
PRP SIGNAL_MODEL 'RESISTOR-G155-11000-01_100OHM_A' 
PRP ALT_SYMBOLS '(SMC_0402R_C_H016)' 
PRP PARENT_PART_TYPE 'RESISTOR' 
PRP PARENT_PPT 'RESISTOR' 
PRP PARENT_PPT_PART 'RESISTOR-G155-11000-01,100OHM,1%' 
PRP PART_NAME 'RESISTOR' 
TOP 0 0.78747 1.795 180.0 N 462 1 1
TOP 1 0.74547 1.795 180.0 N 159 2 2
#
# CMP 296
CMP 56 0.191 1.54798 270.0 N R385 ??? ;0=1,1=0.016000
PRP SIGNAL_MODEL 'DEFAULT_RESISTOR_33OHM_2_1' 
PRP ALT_SYMBOLS '(SMC_0402R_C_H016)' 
PRP PARENT_PART_TYPE 'RESISTOR' 
PRP PARENT_PPT 'RESISTOR' 
PRP PARENT_PPT_PART 'RESISTOR-G155-133R0-01,33OHM,1%' 
PRP PART_NAME 'RESISTOR' 
TOP 0 0.191 1.52698 270.0 N 447 1 1
TOP 1 0.191 1.56898 270.0 N 150 1 2
#
# CMP 297
CMP 56 0.236 1.54798 270.0 N R124 ??? ;0=1,1=0.016000
PRP SIGNAL_MODEL 'RESISTOR-G155-11000-01_100OHM_A' 
PRP ALT_SYMBOLS '(SMC_0402R_C_H016)' 
PRP PARENT_PART_TYPE 'RESISTOR' 
PRP PARENT_PPT 'RESISTOR' 
PRP PARENT_PPT_PART 'RESISTOR-G155-11000-01,100OHM,1%' 
PRP PART_NAME 'RESISTOR' 
TOP 0 0.236 1.52698 270.0 N 270 1 1
TOP 1 0.236 1.56898 270.0 N 150 2 2
#
# CMP 298
CMP 56 0.281 1.54798 270.0 N R272 ??? ;0=1,1=0.016000
PRP SIGNAL_MODEL 'RESISTOR-G155-11000-01_100OHM_A' 
PRP ALT_SYMBOLS '(SMC_0402R_C_H016)' 
PRP PARENT_PART_TYPE 'RESISTOR' 
PRP PARENT_PPT 'RESISTOR' 
PRP PARENT_PPT_PART 'RESISTOR-G155-11000-01,100OHM,1%' 
PRP PART_NAME 'RESISTOR' 
TOP 0 0.281 1.52698 270.0 N 354 1 1
TOP 1 0.281 1.56898 270.0 N 151 1 2
#
# CMP 299
CMP 56 0.8 1.05 180.0 N R388 ??? ;0=1,1=0.016000
PRP HARD_LOCATION 'YES' 
PRP SIGNAL_MODEL 'DEFAULT_RESISTOR_33OHM_2_1' 
PRP REUSE_ID '2' 
PRP ALT_SYMBOLS '(SMC_0402R_C_H016)' 
PRP PARENT_PART_TYPE 'RESISTOR' 
PRP PARENT_PPT 'RESISTOR' 
PRP PARENT_PPT_PART 'RESISTOR-G155-133R0-01,33OHM,1%' 
PRP PART_NAME 'RESISTOR' 
TOP 0 0.821 1.05 180.0 N 450 1 1
TOP 1 0.779 1.05 180.0 N 153 1 2
#
# CMP 300
CMP 56 0.8 1.1 180.0 N R273 ??? ;0=1,1=0.016000
PRP SIGNAL_MODEL 'RESISTOR-G155-11000-01_100OHM_A' 
PRP ALT_SYMBOLS '(SMC_0402R_C_H016)' 
PRP PARENT_PART_TYPE 'RESISTOR' 
PRP PARENT_PPT 'RESISTOR' 
PRP PARENT_PPT_PART 'RESISTOR-G155-11000-01,100OHM,1%' 
PRP PART_NAME 'RESISTOR' 
TOP 0 0.821 1.1 180.0 N 355 1 1
TOP 1 0.779 1.1 180.0 N 153 2 2
#
# CMP 301
CMP 56 0.8 1.15 180.0 N R373 ??? ;0=1,1=0.016000
PRP SIGNAL_MODEL 'RESISTOR-G155-11000-01_100OHM_A' 
PRP ALT_SYMBOLS '(SMC_0402R_C_H016)' 
PRP PARENT_PART_TYPE 'RESISTOR' 
PRP PARENT_PPT 'RESISTOR' 
PRP PARENT_PPT_PART 'RESISTOR-G155-11000-01,100OHM,1%' 
PRP PART_NAME 'RESISTOR' 
TOP 0 0.821 1.15 180.0 N 439 1 1
TOP 1 0.779 1.15 180.0 N 154 1 2
#
# CMP 302
CMP 56 5.935 1.025 0.0 N R21 ??? ;0=1,1=0.016000
PRP SIGNAL_MODEL 'RESISTOR-G155-100R0-J0_0OHM_-' 
PRP ALT_SYMBOLS '(SMC_0402R_C_H016)' 
PRP PARENT_PART_TYPE 'RESISTOR' 
PRP PARENT_PPT 'RESISTOR' 
PRP PARENT_PPT_PART 'RESISTOR-G155-14701-01,4.7KOHM,1%' 
PRP PART_NAME 'RESISTOR' 
TOP 0 5.914 1.025 0.0 N 1 78 1
TOP 1 5.956 1.025 0.0 N 331 2 2
#
# CMP 303
CMP 56 5.935 1.125 180.0 N R20 ??? ;0=1,1=0.016000
PRP SIGNAL_MODEL 'RESISTOR-G155-100R0-J0_0OHM_-' 
PRP ALT_SYMBOLS '(SMC_0402R_C_H016)' 
PRP PARENT_PART_TYPE 'RESISTOR' 
PRP PARENT_PPT 'RESISTOR' 
PRP PARENT_PPT_PART 'RESISTOR-G155-14701-01,4.7KOHM,1%' 
PRP PART_NAME 'RESISTOR' 
TOP 0 5.956 1.125 180.0 N 1 79 1
TOP 1 5.914 1.125 180.0 N 320 0 2
#
# CMP 304
CMP 56 0.66348 2.709 180.0 N R70 ??? ;0=1,1=0.016000
PRP SIGNAL_MODEL 'RESISTOR-G155-100R0-J0_0OHM_-' 
PRP ALT_SYMBOLS '(SMC_0402R_C_H016)' 
PRP PARENT_PART_TYPE 'RESISTOR' 
PRP PARENT_PPT 'RESISTOR' 
PRP PARENT_PPT_PART 'RESISTOR-G155-14701-01,4.7KOHM,1%' 
PRP PART_NAME 'RESISTOR' 
TOP 0 0.68448 2.709 180.0 N 72 5 1
TOP 1 0.64248 2.709 180.0 N 388 1 2
#
# CMP 305
CMP 56 0.66348 2.664 0.0 N R72 ??? ;0=1,1=0.016000
PRP SIGNAL_MODEL 'DEFAULT_RESISTOR_33OHM_2_1' 
PRP ALT_SYMBOLS '(SMC_0402R_C_H016)' 
PRP PARENT_PART_TYPE 'RESISTOR' 
PRP PARENT_PPT 'RESISTOR' 
PRP PARENT_PPT_PART 'RESISTOR-G155-133R0-01,33OHM,1%' 
PRP PART_NAME 'RESISTOR' 
TOP 0 0.64248 2.664 0.0 N 388 2 1
TOP 1 0.68448 2.664 0.0 N 526 1 2
#
# CMP 306
CMP 56 0.51452 2.254 270.0 N R381 ??? ;0=1,1=0.016000
PRP HARD_LOCATION 'YES' 
PRP SIGNAL_MODEL 'RESISTOR-G155-100R0-J0_0OHM_-' 
PRP REUSE_ID '4' 
PRP ALT_SYMBOLS '(SMC_0402R_C_H016)' 
PRP PARENT_PART_TYPE 'RESISTOR' 
PRP PARENT_PPT 'RESISTOR' 
PRP PARENT_PPT_PART 'RESISTOR-G155-14701-01,4.7KOHM,1%' 
PRP PART_NAME 'RESISTOR' 
TOP 0 0.51452 2.233 270.0 N 1 80 1
TOP 1 0.51452 2.275 270.0 N 445 3 2
#
# CMP 307
CMP 56 0.575 2.07 90.0 N R331 ??? ;0=1,1=0.016000
PRP HARD_LOCATION 'YES' 
PRP SIGNAL_MODEL 'RESISTOR-G155-100R0-J0_0OHM_-' 
PRP ALT_SYMBOLS '(SMC_0402R_C_H016)' 
PRP PARENT_PART_TYPE 'RESISTOR' 
PRP PARENT_PPT 'RESISTOR' 
PRP PARENT_PPT_PART 'RESISTOR-G155-14701-01,4.7KOHM,1%' 
PRP PART_NAME 'RESISTOR' 
TOP 0 0.575 2.091 90.0 N 1 81 1
TOP 1 0.575 2.049 90.0 N 400 3 2
#
# CMP 308
CMP 56 0.535 1.65 0.0 N R383 ??? ;0=1,1=0.016000
PRP HARD_LOCATION 'YES' 
PRP SIGNAL_MODEL 'RESISTOR-G155-100R0-J0_0OHM_-' 
PRP ALT_SYMBOLS '(SMC_0402R_C_H016)' 
PRP PARENT_PART_TYPE 'RESISTOR' 
PRP PARENT_PPT 'RESISTOR' 
PRP PARENT_PPT_PART 'RESISTOR-G155-14701-01,4.7KOHM,1%' 
PRP PART_NAME 'RESISTOR' 
TOP 0 0.514 1.65 0.0 N 1 82 1
TOP 1 0.556 1.65 0.0 N 446 3 2
#
# CMP 309
CMP 56 0.58 1.465 90.0 N R365 ??? ;0=1,1=0.016000
PRP SIGNAL_MODEL 'RESISTOR-G155-100R0-J0_0OHM_-' 
PRP REUSE_ID '14' 
PRP ALT_SYMBOLS '(SMC_0402R_C_H016)' 
PRP PARENT_PART_TYPE 'RESISTOR' 
PRP PARENT_PPT 'RESISTOR' 
PRP PARENT_PPT_PART 'RESISTOR-G155-14701-01,4.7KOHM,1%' 
PRP PART_NAME 'RESISTOR' 
TOP 0 0.58 1.486 90.0 N 1 83 1
TOP 1 0.58 1.444 90.0 N 428 3 2
#
# CMP 310
CMP 56 0.505 1.1049 270.0 N R377 ??? ;0=1,1=0.016000
PRP HARD_LOCATION 'YES' 
PRP SIGNAL_MODEL 'RESISTOR-G155-100R0-J0_0OHM_-' 
PRP REUSE_ID '15' 
PRP ALT_SYMBOLS '(SMC_0402R_C_H016)' 
PRP PARENT_PART_TYPE 'RESISTOR' 
PRP PARENT_PPT 'RESISTOR' 
PRP PARENT_PPT_PART 'RESISTOR-G155-14701-01,4.7KOHM,1%' 
PRP PART_NAME 'RESISTOR' 
TOP 0 0.505 1.0839 270.0 N 1 84 1
TOP 1 0.505 1.1259 270.0 N 443 3 2
#
# CMP 311
CMP 56 0.58 0.905 90.0 N R368 ??? ;0=1,1=0.016000
PRP HARD_LOCATION 'YES' 
PRP SIGNAL_MODEL 'RESISTOR-G155-100R0-J0_0OHM_-' 
PRP ALT_SYMBOLS '(SMC_0402R_C_H016)' 
PRP PARENT_PART_TYPE 'RESISTOR' 
PRP PARENT_PPT 'RESISTOR' 
PRP PARENT_PPT_PART 'RESISTOR-G155-14701-01,4.7KOHM,1%' 
PRP PART_NAME 'RESISTOR' 
TOP 0 0.58 0.926 90.0 N 1 85 1
TOP 1 0.58 0.884 90.0 N 431 3 2
#
# CMP 312
CMP 56 0.332 2.68508 270.0 N R393 ??? ;0=1,1=0.016000
PRP HARD_LOCATION 'YES' 
PRP SIGNAL_MODEL 'DEFAULT_RESISTOR_33OHM_2_1' 
PRP ALT_SYMBOLS '(SMC_0402R_C_H016)' 
PRP PARENT_PART_TYPE 'RESISTOR' 
PRP PARENT_PPT 'RESISTOR' 
PRP PARENT_PPT_PART 'RESISTOR-G155-133R0-01,33OHM,1%' 
PRP PART_NAME 'RESISTOR' 
TOP 0 0.332 2.66408 270.0 N 455 1 1
TOP 1 0.332 2.70608 270.0 N 157 2 2
#
# CMP 313
CMP 56 0.422 2.68508 270.0 N R375 ??? ;0=1,1=0.016000
PRP SIGNAL_MODEL 'RESISTOR-G155-11000-01_100OHM_A' 
PRP ALT_SYMBOLS '(SMC_0402R_C_H016)' 
PRP PARENT_PART_TYPE 'RESISTOR' 
PRP PARENT_PPT 'RESISTOR' 
PRP PARENT_PPT_PART 'RESISTOR-G155-11000-01,100OHM,1%' 
PRP PART_NAME 'RESISTOR' 
TOP 0 0.422 2.66408 270.0 N 441 1 1
TOP 1 0.422 2.70608 270.0 N 158 1 2
#
# CMP 314
CMP 56 0.377 2.68508 270.0 N R392 ??? ;0=1,1=0.016000
PRP HARD_LOCATION 'YES' 
PRP SIGNAL_MODEL 'DEFAULT_RESISTOR_33OHM_2_1' 
PRP ALT_SYMBOLS '(SMC_0402R_C_H016)' 
PRP PARENT_PART_TYPE 'RESISTOR' 
PRP PARENT_PPT 'RESISTOR' 
PRP PARENT_PPT_PART 'RESISTOR-G155-133R0-01,33OHM,1%' 
PRP PART_NAME 'RESISTOR' 
TOP 0 0.377 2.66408 270.0 N 454 1 1
TOP 1 0.377 2.70608 270.0 N 158 2 2
#
# CMP 315
CMP 56 0.76647 1.885 180.0 N R396 ??? ;0=1,1=0.016000
PRP HARD_LOCATION 'YES' 
PRP SIGNAL_MODEL 'DEFAULT_RESISTOR_33OHM_2_1' 
PRP ALT_SYMBOLS '(SMC_0402R_C_H016)' 
PRP PARENT_PART_TYPE 'RESISTOR' 
PRP PARENT_PPT 'RESISTOR' 
PRP PARENT_PPT_PART 'RESISTOR-G155-133R0-01,33OHM,1%' 
PRP PART_NAME 'RESISTOR' 
TOP 0 0.78747 1.885 180.0 N 458 1 1
TOP 1 0.74547 1.885 180.0 N 160 2 2
#
# CMP 316
CMP 56 0.76647 1.975 180.0 N R401 ??? ;0=1,1=0.016000
PRP SIGNAL_MODEL 'RESISTOR-G155-11000-01_100OHM_A' 
PRP ALT_SYMBOLS '(SMC_0402R_C_H016)' 
PRP PARENT_PART_TYPE 'RESISTOR' 
PRP PARENT_PPT 'RESISTOR' 
PRP PARENT_PPT_PART 'RESISTOR-G155-11000-01,100OHM,1%' 
PRP PART_NAME 'RESISTOR' 
TOP 0 0.78747 1.975 180.0 N 463 1 1
TOP 1 0.74547 1.975 180.0 N 161 1 2
#
# CMP 317
CMP 56 0.76647 1.93 180.0 N R395 ??? ;0=1,1=0.016000
PRP HARD_LOCATION 'YES' 
PRP SIGNAL_MODEL 'DEFAULT_RESISTOR_33OHM_2_1' 
PRP ALT_SYMBOLS '(SMC_0402R_C_H016)' 
PRP PARENT_PART_TYPE 'RESISTOR' 
PRP PARENT_PPT 'RESISTOR' 
PRP PARENT_PPT_PART 'RESISTOR-G155-133R0-01,33OHM,1%' 
PRP PART_NAME 'RESISTOR' 
TOP 0 0.78747 1.93 180.0 N 457 1 1
TOP 1 0.74547 1.93 180.0 N 161 2 2
#
# CMP 318
CMP 56 0.416 1.54798 270.0 N R386 ??? ;0=1,1=0.016000
PRP SIGNAL_MODEL 'DEFAULT_RESISTOR_33OHM_2_1' 
PRP ALT_SYMBOLS '(SMC_0402R_C_H016)' 
PRP PARENT_PART_TYPE 'RESISTOR' 
PRP PARENT_PPT 'RESISTOR' 
PRP PARENT_PPT_PART 'RESISTOR-G155-133R0-01,33OHM,1%' 
PRP PART_NAME 'RESISTOR' 
TOP 0 0.416 1.52698 270.0 N 448 1 1
TOP 1 0.416 1.56898 270.0 N 152 1 2
#
# CMP 319
CMP 56 0.371 1.54798 270.0 N R125 ??? ;0=1,1=0.016000
PRP SIGNAL_MODEL 'RESISTOR-G155-11000-01_100OHM_A' 
PRP ALT_SYMBOLS '(SMC_0402R_C_H016)' 
PRP PARENT_PART_TYPE 'RESISTOR' 
PRP PARENT_PPT 'RESISTOR' 
PRP PARENT_PPT_PART 'RESISTOR-G155-11000-01,100OHM,1%' 
PRP PART_NAME 'RESISTOR' 
TOP 0 0.371 1.52698 270.0 N 271 1 1
TOP 1 0.371 1.56898 270.0 N 152 2 2
#
# CMP 320
CMP 56 0.326 1.54798 270.0 N R387 ??? ;0=1,1=0.016000
PRP SIGNAL_MODEL 'DEFAULT_RESISTOR_33OHM_2_1' 
PRP ALT_SYMBOLS '(SMC_0402R_C_H016)' 
PRP PARENT_PART_TYPE 'RESISTOR' 
PRP PARENT_PPT 'RESISTOR' 
PRP PARENT_PPT_PART 'RESISTOR-G155-133R0-01,33OHM,1%' 
PRP PART_NAME 'RESISTOR' 
TOP 0 0.326 1.52698 270.0 N 449 1 1
TOP 1 0.326 1.56898 270.0 N 151 2 2
#
# CMP 321
CMP 56 0.8 1.3 180.0 N R389 ??? ;0=1,1=0.016000
PRP HARD_LOCATION 'YES' 
PRP SIGNAL_MODEL 'DEFAULT_RESISTOR_33OHM_2_1' 
PRP REUSE_ID '1' 
PRP ALT_SYMBOLS '(SMC_0402R_C_H016)' 
PRP PARENT_PART_TYPE 'RESISTOR' 
PRP PARENT_PPT 'RESISTOR' 
PRP PARENT_PPT_PART 'RESISTOR-G155-133R0-01,33OHM,1%' 
PRP PART_NAME 'RESISTOR' 
TOP 0 0.821 1.3 180.0 N 451 1 1
TOP 1 0.779 1.3 180.0 N 155 1 2
#
# CMP 322
CMP 56 0.8 1.25 180.0 N R274 ??? ;0=1,1=0.016000
PRP SIGNAL_MODEL 'RESISTOR-G155-11000-01_100OHM_A' 
PRP ALT_SYMBOLS '(SMC_0402R_C_H016)' 
PRP PARENT_PART_TYPE 'RESISTOR' 
PRP PARENT_PPT 'RESISTOR' 
PRP PARENT_PPT_PART 'RESISTOR-G155-11000-01,100OHM,1%' 
PRP PART_NAME 'RESISTOR' 
TOP 0 0.821 1.25 180.0 N 356 1 1
TOP 1 0.779 1.25 180.0 N 155 2 2
#
# CMP 323
CMP 56 0.8 1.2 180.0 N R390 ??? ;0=1,1=0.016000
PRP HARD_LOCATION 'YES' 
PRP SIGNAL_MODEL 'DEFAULT_RESISTOR_33OHM_2_1' 
PRP REUSE_ID '4' 
PRP ALT_SYMBOLS '(SMC_0402R_C_H016)' 
PRP PARENT_PART_TYPE 'RESISTOR' 
PRP PARENT_PPT 'RESISTOR' 
PRP PARENT_PPT_PART 'RESISTOR-G155-133R0-01,33OHM,1%' 
PRP PART_NAME 'RESISTOR' 
TOP 0 0.821 1.2 180.0 N 452 1 1
TOP 1 0.779 1.2 180.0 N 154 2 2
#
# CMP 324
CMP 56 5.741 3.617 180.0 N R7 ??? ;0=1,1=0.016000
PRP SIGNAL_MODEL 'RESISTOR-G155-100R0-J0_0OHM_-' 
PRP REUSE_ID '31' 
PRP ALT_SYMBOLS '(SMC_0402R_C_H016,C0402-0P8MM-45DG)' 
PRP PARENT_PART_TYPE 'RESISTOR' 
PRP PARENT_PPT 'RESISTOR' 
PRP PARENT_PPT_PART 'RESISTOR-G155-100R0-J0,0OHM,-' 
PRP PART_NAME 'RESISTOR' 
TOP 0 5.762 3.617 180.0 N 2 264 1
TOP 1 5.72 3.617 180.0 N 525 1 2
#
# CMP 325
CMP 56 5.741 3.667 180.0 N R8 ??? ;0=1,1=0.016000
PRP SIGNAL_MODEL 'RESISTOR-G155-100R0-J0_0OHM_-' 
PRP REUSE_ID '22' 
PRP ALT_SYMBOLS '(SMC_0402R_C_H016,C0402-0P8MM-45DG)' 
PRP PARENT_PART_TYPE 'RESISTOR' 
PRP PARENT_PPT 'RESISTOR' 
PRP PARENT_PPT_PART 'RESISTOR-G155-100R0-J0,0OHM,-' 
PRP PART_NAME 'RESISTOR' 
TOP 0 5.762 3.667 180.0 N 2 265 1
TOP 1 5.72 3.667 180.0 N 534 1 2
#
# CMP 326
CMP 56 5.741 3.467 180.0 N R4 ??? ;0=1,1=0.016000
PRP SIGNAL_MODEL 'RESISTOR-G155-100R0-J0_0OHM_-' 
PRP REUSE_ID '21' 
PRP ALT_SYMBOLS '(SMC_0402R_C_H016)' 
PRP PARENT_PART_TYPE 'RESISTOR' 
PRP PARENT_PPT 'RESISTOR' 
PRP PARENT_PPT_PART 'RESISTOR-G155-11002-01,10KOHM,1%' 
PRP PART_NAME 'RESISTOR' 
TOP 0 5.762 3.467 180.0 N 30 12 1
TOP 1 5.72 3.467 180.0 N 83 2 2
#
# CMP 327
CMP 56 1.3297 0.753 180.0 N R313 ??? ;0=1,1=0.016000
PRP SIGNAL_MODEL 'RESISTOR-G155-100R0-J0_0OHM_-' 
PRP ALT_SYMBOLS '(SMC_0402R_C_H016,C0402-0P8MM-45DG)' 
PRP PARENT_PART_TYPE 'RESISTOR' 
PRP PARENT_PPT 'RESISTOR' 
PRP PARENT_PPT_PART 'RESISTOR-G155-100R0-J0,0OHM,-' 
PRP PART_NAME 'RESISTOR' 
TOP 0 1.3507 0.753 180.0 N 385 1 1
TOP 1 1.3087 0.753 180.0 N 225 3 2
#
# CMP 328
CMP 56 1.3297 0.708 180.0 N R184 ??? ;0=1,1=0.016000
PRP SIGNAL_MODEL 'DEFAULT_RESISTOR_33OHM_2_1' 
PRP ALT_SYMBOLS '(SMC_0402R_C_H016)' 
PRP PARENT_PART_TYPE 'RESISTOR' 
PRP PARENT_PPT 'RESISTOR' 
PRP PARENT_PPT_PART 'RESISTOR-G155-133R0-01,33OHM,1%' 
PRP PART_NAME 'RESISTOR' 
TOP 0 1.3507 0.708 180.0 N 309 1 1
TOP 1 1.3087 0.708 180.0 N 225 4 2
#
# CMP 329
CMP 56 1.3295 0.613 180.0 N R183 ??? ;0=1,1=0.016000
PRP SIGNAL_MODEL 'DEFAULT_RESISTOR_33OHM_2_1' 
PRP ALT_SYMBOLS '(SMC_0402R_C_H016)' 
PRP PARENT_PART_TYPE 'RESISTOR' 
PRP PARENT_PPT 'RESISTOR' 
PRP PARENT_PPT_PART 'RESISTOR-G155-133R0-01,33OHM,1%' 
PRP PART_NAME 'RESISTOR' 
TOP 0 1.3505 0.613 180.0 N 308 1 1
TOP 1 1.3085 0.613 180.0 N 223 1 2
#
# CMP 330
CMP 56 1.3295 0.658 180.0 N R312 ??? ;0=1,1=0.016000
PRP SIGNAL_MODEL 'RESISTOR-G155-100R0-J0_0OHM_-' 
PRP ALT_SYMBOLS '(SMC_0402R_C_H016,C0402-0P8MM-45DG)' 
PRP PARENT_PART_TYPE 'RESISTOR' 
PRP PARENT_PPT 'RESISTOR' 
PRP PARENT_PPT_PART 'RESISTOR-G155-100R0-J0,0OHM,-' 
PRP PART_NAME 'RESISTOR' 
TOP 0 1.3505 0.658 180.0 N 384 1 1
TOP 1 1.3085 0.658 180.0 N 223 2 2
#
# CMP 331
CMP 56 5.741 3.757 180.0 N R46 ??? ;0=1,1=0.016000
PRP REUSE_ID '23' 
PRP ALT_SYMBOLS '(SMC_0402R_C_H016)' 
PRP PARENT_PART_TYPE 'RESISTOR' 
PRP PARENT_PPT 'RESISTOR' 
PRP PARENT_PPT_PART 'RESISTOR-G155-02672-01,26.7K,1%' 
PRP PART_NAME 'RESISTOR' 
TOP 0 5.762 3.757 180.0 N 2 266 1
TOP 1 5.72 3.757 180.0 N 490 1 2
#
# CMP 332
CMP 56 5.741 3.907 180.0 N R15 ??? ;0=1,1=0.016000
PRP SIGNAL_MODEL 'RESISTOR-G155-100R0-J0_0OHM_-' 
PRP REUSE_ID '16' 
PRP ALT_SYMBOLS '(SMC_0402R_C_H016)' 
PRP PARENT_PART_TYPE 'RESISTOR' 
PRP PARENT_PPT 'RESISTOR' 
PRP PARENT_PPT_PART 'RESISTOR-G155-11002-01,10KOHM,1%' 
PRP PART_NAME 'RESISTOR' 
TOP 0 5.762 3.907 180.0 N 3 13 1
TOP 1 5.72 3.907 180.0 N 293 2 2
#
# CMP 333
CMP 56 1.1947 0.7086 180.0 N R19 ??? ;0=1,1=0.016000
PRP SIGNAL_MODEL 'RESISTOR-G155-100R0-J0_0OHM_-' 
PRP ALT_SYMBOLS '(SMC_0402R_C_H016)' 
PRP PARENT_PART_TYPE 'RESISTOR' 
PRP PARENT_PPT 'RESISTOR' 
PRP PARENT_PPT_PART 'RESISTOR-G155-11002-01,10KOHM,1%' 
PRP PART_NAME 'RESISTOR' 
TOP 0 1.2157 0.7086 180.0 N 1 86 1
TOP 1 1.1737 0.7086 180.0 N 225 5 2
#
# CMP 334
CMP 56 1.1947 0.7536 180.0 N R1992 ??? ;0=1,1=0.016000
PRP SIGNAL_MODEL 'RESISTOR-G155-100R0-J0_0OHM_-' 
PRP ALT_SYMBOLS '(SMC_0402R_C_H016)' 
PRP PARENT_PART_TYPE 'RESISTOR' 
PRP PARENT_PPT 'RESISTOR' 
PRP PARENT_PPT_PART 'RESISTOR-G155-14701-01,4.7KOHM,1%' 
PRP PART_NAME 'RESISTOR' 
TOP 0 1.2157 0.7536 180.0 N 1 87 1
TOP 1 1.1737 0.7536 180.0 N 211 3 2
#
# CMP 335
CMP 56 1.1947 0.6586 180.0 N R345 ??? ;0=1,1=0.016000
PRP SIGNAL_MODEL 'DEFAULT_RESISTOR_33OHM_2_1' 
PRP ALT_SYMBOLS '(SMC_0402R_C_H016)' 
PRP PARENT_PART_TYPE 'RESISTOR' 
PRP PARENT_PPT 'RESISTOR' 
PRP PARENT_PPT_PART 'RESISTOR-G155-133R0-01,33OHM,1%' 
PRP PART_NAME 'RESISTOR' 
TOP 0 1.2157 0.6586 180.0 N 223 3 1
TOP 1 1.1737 0.6586 180.0 N 410 1 2
#
# CMP 336
CMP 56 5.58 3.96 180.0 N R13 ??? ;0=1,1=0.016000
PRP SIGNAL_MODEL 'RESISTOR-G155-100R0-J0_0OHM_-' 
PRP REUSE_ID '10' 
PRP ALT_SYMBOLS '(SMC_0402R_C_H016)' 
PRP PARENT_PART_TYPE 'RESISTOR' 
PRP PARENT_PPT 'RESISTOR' 
PRP PARENT_PPT_PART 'RESISTOR-G155-11002-01,10KOHM,1%' 
PRP PART_NAME 'RESISTOR' 
TOP 0 5.601 3.96 180.0 N 3 14 1
TOP 1 5.559 3.96 180.0 N 276 2 2
#
# CMP 337
CMP 56 5.341 3.957 0.0 N R11 ??? ;0=1,1=0.016000
PRP REUSE_ID '5' 
PRP ALT_SYMBOLS '(SMC_0402R_C_H016)' 
PRP PARENT_PART_TYPE 'RESISTOR' 
PRP PARENT_PPT 'RESISTOR' 
PRP PARENT_PPT_PART 'RESISTOR-G155-01203-01,120KOHM,1%' 
PRP PART_NAME 'RESISTOR' 
TOP 0 5.32 3.957 0.0 N 30 13 1
TOP 1 5.362 3.957 0.0 N 128 1 2
#
# CMP 338
CMP 56 5.48543 3.967 180.0 N R12 ??? ;0=1,1=0.016000
PRP SIGNAL_MODEL 'RESISTOR-G155-100R0-J0_0OHM_-' 
PRP REUSE_ID '11' 
PRP ALT_SYMBOLS '(SMC_0402R_C_H016)' 
PRP PARENT_PART_TYPE 'RESISTOR' 
PRP PARENT_PPT 'RESISTOR' 
PRP PARENT_PPT_PART 'RESISTOR-G155-11002-01,10KOHM,1%' 
PRP PART_NAME 'RESISTOR' 
TOP 0 5.50643 3.967 180.0 N 128 2 1
TOP 1 5.46443 3.967 180.0 N 2 267 2
#
# CMP 339
CMP 56 0.80648 2.81 270.0 N R71 ??? ;0=1,1=0.016000
PRP SIGNAL_MODEL 'RESISTOR-G155-100R0-J0_0OHM_-' 
PRP ALT_SYMBOLS '(SMC_0402R_C_H016)' 
PRP PARENT_PART_TYPE 'RESISTOR' 
PRP PARENT_PPT 'RESISTOR' 
PRP PARENT_PPT_PART 'RESISTOR-G155-14701-01,4.7KOHM,1%' 
PRP PART_NAME 'RESISTOR' 
TOP 0 0.80648 2.789 270.0 N 72 6 1
TOP 1 0.80648 2.831 270.0 N 387 1 2
#
# CMP 340
CMP 56 0.735 2.79 180.0 N R73 ??? ;0=1,1=0.016000
PRP SIGNAL_MODEL 'DEFAULT_RESISTOR_33OHM_2_1' 
PRP ALT_SYMBOLS '(SMC_0402R_C_H016)' 
PRP PARENT_PART_TYPE 'RESISTOR' 
PRP PARENT_PPT 'RESISTOR' 
PRP PARENT_PPT_PART 'RESISTOR-G155-133R0-01,33OHM,1%' 
PRP PART_NAME 'RESISTOR' 
TOP 0 0.756 2.79 180.0 N 387 2 1
TOP 1 0.714 2.79 180.0 N 527 1 2
#
# CMP 341
CMP 56 0.578 2.59 90.0 N R361 ??? ;0=1,1=0.016000
PRP HARD_LOCATION 'YES' 
PRP SIGNAL_MODEL 'RESISTOR-G155-100R0-J0_0OHM_-' 
PRP REUSE_ID '7' 
PRP ALT_SYMBOLS '(SMC_0402R_C_H016)' 
PRP PARENT_PART_TYPE 'RESISTOR' 
PRP PARENT_PPT 'RESISTOR' 
PRP PARENT_PPT_PART 'RESISTOR-G155-14701-01,4.7KOHM,1%' 
PRP PART_NAME 'RESISTOR' 
TOP 0 0.578 2.611 90.0 N 1 88 1
TOP 1 0.578 2.569 90.0 N 424 3 2
#
# CMP 342
CMP 56 2.083 2.952 270.0 N R408 ??? ;0=1,1=0.016000
PRP SIGNAL_MODEL 'RESISTOR-G155-100R0-J0_0OHM_-' 
PRP REUSE_ID '6' 
PRP ALT_SYMBOLS '(SMC_0402R_C_H016)' 
PRP PARENT_PART_TYPE 'RESISTOR' 
PRP PARENT_PPT 'RESISTOR' 
PRP PARENT_PPT_PART 'RESISTOR-G155-14701-01,4.7KOHM,1%' 
PRP PART_NAME 'RESISTOR' 
TOP 0 2.083 2.931 270.0 N 1 89 1
TOP 1 2.083 2.973 270.0 N 466 1 2
#
# CMP 343
CMP 56 2.128 2.952 270.0 N R412 ??? ;0=1,1=0.016000
PRP SIGNAL_MODEL 'RESISTOR-G155-100R0-J0_0OHM_-' 
PRP REUSE_ID '11' 
PRP ALT_SYMBOLS '(SMC_0402R_C_H016)' 
PRP PARENT_PART_TYPE 'RESISTOR' 
PRP PARENT_PPT 'RESISTOR' 
PRP PARENT_PPT_PART 'RESISTOR-G155-14701-01,4.7KOHM,1%' 
PRP PART_NAME 'RESISTOR' 
TOP 0 2.128 2.931 270.0 N 1 90 1
TOP 1 2.128 2.973 270.0 N 468 1 2
#
# CMP 344
CMP 56 2.173 2.952 270.0 N R418 ??? ;0=1,1=0.016000
PRP SIGNAL_MODEL 'RESISTOR-G155-100R0-J0_0OHM_-' 
PRP REUSE_ID '9' 
PRP ALT_SYMBOLS '(SMC_0402R_C_H016)' 
PRP PARENT_PART_TYPE 'RESISTOR' 
PRP PARENT_PPT 'RESISTOR' 
PRP PARENT_PPT_PART 'RESISTOR-G155-14701-01,4.7KOHM,1%' 
PRP PART_NAME 'RESISTOR' 
TOP 0 2.173 2.931 270.0 N 1 91 1
TOP 1 2.173 2.973 270.0 N 470 1 2
#
# CMP 345
CMP 56 1.556 4.141 270.0 N R29 ??? ;0=1,1=0.016000
PRP REUSE_ID '20' 
PRP ALT_SYMBOLS '(SMC_0402R_C_H016)' 
PRP PARENT_PART_TYPE 'RESISTOR' 
PRP PARENT_PPT 'RESISTOR' 
PRP PARENT_PPT_PART 'RESISTOR-G155-11003-01,100KOHM,1%' 
PRP PART_NAME 'RESISTOR' 
TOP 0 1.556 4.12 270.0 N 370 1 1
TOP 1 1.556 4.162 270.0 N 90 1 2
#
# CMP 346
CMP 56 2.2628 3.266 270.0 N R406 ??? ;0=1,1=0.016000
PRP SIGNAL_MODEL 'DEFAULT_RESISTOR_33OHM_2_1' 
PRP REUSE_ID '2' 
PRP ALT_SYMBOLS '(SMC_0402R_C_H016)' 
PRP PARENT_PART_TYPE 'RESISTOR' 
PRP PARENT_PPT 'RESISTOR' 
PRP PARENT_PPT_PART 'RESISTOR-G155-133R0-01,33OHM,1%' 
PRP PART_NAME 'RESISTOR' 
TOP 0 2.2628 3.245 270.0 N 320 1 1
TOP 1 2.2628 3.287 270.0 N 464 1 2
#
# CMP 347
CMP 56 1.959 3.268 90.0 N R422 ??? ;0=1,1=0.016000
PRP SIGNAL_MODEL 'RESISTOR-G155-100R0-J0_0OHM_-' 
PRP REUSE_ID '4' 
PRP ALT_SYMBOLS '(SMC_0402R_C_H016)' 
PRP PARENT_PART_TYPE 'RESISTOR' 
PRP PARENT_PPT 'RESISTOR' 
PRP PARENT_PPT_PART 'RESISTOR-G155-14701-01,4.7KOHM,1%' 
PRP PART_NAME 'RESISTOR' 
TOP 0 1.959 3.289 90.0 N 1 92 1
TOP 1 1.959 3.247 90.0 N 472 3 2
#
# CMP 348
CMP 56 1.385 4.105 90.0 N R6 ??? ;0=1,1=0.016000
PRP REUSE_ID '30' 
PRP ALT_SYMBOLS '(SMC_0402R_C_H016)' 
PRP PARENT_PART_TYPE 'RESISTOR' 
PRP PARENT_PPT 'RESISTOR' 
PRP PARENT_PPT_PART 'RESISTOR-G155-120R0-01,20OHM,1%' 
PRP PART_NAME 'RESISTOR' 
TOP 0 1.385 4.126 90.0 N 13 4 1
TOP 1 1.385 4.084 90.0 N 11 1 2
#
# CMP 349
CMP 56 1.446 3.851 180.0 N R294 ??? ;0=1,1=0.016000
PRP SIGNAL_MODEL 'DEFAULT_RESISTOR_33OHM_2_1' 
PRP REUSE_ID '4' 
PRP ALT_SYMBOLS '(SMC_0402R_C_H016)' 
PRP PARENT_PART_TYPE 'RESISTOR' 
PRP PARENT_PPT 'RESISTOR' 
PRP PARENT_PPT_PART 'RESISTOR-G155-133R0-01,33OHM,1%' 
PRP PART_NAME 'RESISTOR' 
TOP 0 1.467 3.851 180.0 N 126 1 1
TOP 1 1.425 3.851 180.0 N 203 2 2
#
# CMP 350
CMP 56 5.741 3.517 0.0 N R5 ??? ;0=1,1=0.016000
PRP SIGNAL_MODEL 'RESISTOR-G155-100R0-J0_0OHM_-' 
PRP REUSE_ID '29' 
PRP ALT_SYMBOLS '(SMC_0402R_C_H016)' 
PRP PARENT_PART_TYPE 'RESISTOR' 
PRP PARENT_PPT 'RESISTOR' 
PRP PARENT_PPT_PART 'RESISTOR-G155-11002-01,10KOHM,1%' 
PRP PART_NAME 'RESISTOR' 
TOP 0 5.72 3.517 0.0 N 83 3 1
TOP 1 5.762 3.517 0.0 N 2 268 2
#
# CMP 351
CMP 56 3.18 2.434 0.0 N R306 ??? ;0=1,1=0.016000
PRP SIGNAL_MODEL 'RESISTOR-G155-100R0-J0_0OHM_-' 
PRP ALT_SYMBOLS '(SMC_0402R_C_H016)' 
PRP PARENT_PART_TYPE 'RESISTOR' 
PRP PARENT_PPT 'RESISTOR' 
PRP PARENT_PPT_PART 'RESISTOR-G155-14701-01,4.7KOHM,1%' 
PRP PART_NAME 'RESISTOR' 
TOP 0 3.159 2.434 0.0 N 1 93 1
TOP 1 3.201 2.434 0.0 N 381 1 2
#
# CMP 352
CMP 56 3.18 2.389 0.0 N R291 ??? ;0=1,1=0.016000
PRP SIGNAL_MODEL 'RESISTOR-G155-100R0-J0_0OHM_-' 
PRP ALT_SYMBOLS '(SMC_0402R_C_H016)' 
PRP PARENT_PART_TYPE 'RESISTOR' 
PRP PARENT_PPT 'RESISTOR' 
PRP PARENT_PPT_PART 'RESISTOR-G155-14701-01,4.7KOHM,1%' 
PRP PART_NAME 'RESISTOR' 
TOP 0 3.159 2.389 0.0 N 1 94 1
TOP 1 3.201 2.389 0.0 N 372 2 2
#
# CMP 353
CMP 56 3.18 2.254 0.0 N R79 ??? ;0=1,1=0.016000
PRP SIGNAL_MODEL 'DEFAULT_RESISTOR_33OHM_2_1' 
PRP ALT_SYMBOLS '(SMC_0402R_C_H016)' 
PRP PARENT_PART_TYPE 'RESISTOR' 
PRP PARENT_PPT 'RESISTOR' 
PRP PARENT_PPT_PART 'RESISTOR-G155-133R0-01,33OHM,1%' 
PRP PART_NAME 'RESISTOR' 
TOP 0 3.159 2.254 0.0 N 369 1 1
TOP 1 3.201 2.254 0.0 N 533 2 2
#
# CMP 354
CMP 56 3.18 2.299 180.0 N R78 ??? ;0=1,1=0.016000
PRP SIGNAL_MODEL 'DEFAULT_RESISTOR_33OHM_2_1' 
PRP ALT_SYMBOLS '(SMC_0402R_C_H016)' 
PRP PARENT_PART_TYPE 'RESISTOR' 
PRP PARENT_PPT 'RESISTOR' 
PRP PARENT_PPT_PART 'RESISTOR-G155-133R0-01,33OHM,1%' 
PRP PART_NAME 'RESISTOR' 
TOP 0 3.201 2.299 180.0 N 372 3 1
TOP 1 3.159 2.299 180.0 N 532 1 2
#
# CMP 355
CMP 56 3.18 2.344 180.0 N R301 ??? ;0=1,1=0.016000
PRP SIGNAL_MODEL 'RESISTOR-G155-100R0-J0_0OHM_-' 
PRP ALT_SYMBOLS '(SMC_0402R_C_H016)' 
PRP PARENT_PART_TYPE 'RESISTOR' 
PRP PARENT_PPT 'RESISTOR' 
PRP PARENT_PPT_PART 'RESISTOR-G155-14701-01,4.7KOHM,1%' 
PRP PART_NAME 'RESISTOR' 
TOP 0 3.201 2.344 180.0 N 372 4 1
TOP 1 3.159 2.344 180.0 N 2 269 2
#
# CMP 356
CMP 56 3.18 2.479 180.0 N R307 ??? ;0=1,1=0.016000
PRP ALT_SYMBOLS '(SMC_0402R_C_H016)' 
PRP PARENT_PART_TYPE 'RESISTOR' 
PRP PARENT_PPT 'RESISTOR' 
PRP PARENT_PPT_PART 'RESISTOR-G155-11001-01,1KOHM,1%' 
PRP PART_NAME 'RESISTOR' 
TOP 0 3.201 2.479 180.0 N 381 2 1
TOP 1 3.159 2.479 180.0 N 2 270 2
#
# CMP 357
CMP 56 4.905 1.975 180.0 N R94 ??? ;0=1,1=0.016000
PRP SIGNAL_MODEL 'DEFAULT_RESISTOR_33OHM_2_1' 
PRP ALT_SYMBOLS '(SMC_0402R_C_H016)' 
PRP PARENT_PART_TYPE 'RESISTOR' 
PRP PARENT_PPT 'RESISTOR' 
PRP PARENT_PPT_PART 'RESISTOR-G155-133R0-01,33OHM,1%' 
PRP PART_NAME 'RESISTOR' 
TOP 0 4.926 1.975 180.0 N 229 1 1
TOP 1 4.884 1.975 180.0 N 351 1 2
#
# CMP 358
CMP 56 4.905 2.025 180.0 N R95 ??? ;0=1,1=0.016000
PRP SIGNAL_MODEL 'DEFAULT_RESISTOR_33OHM_2_1' 
PRP ALT_SYMBOLS '(SMC_0402R_C_H016)' 
PRP PARENT_PART_TYPE 'RESISTOR' 
PRP PARENT_PPT 'RESISTOR' 
PRP PARENT_PPT_PART 'RESISTOR-G155-133R0-01,33OHM,1%' 
PRP PART_NAME 'RESISTOR' 
TOP 0 4.926 2.025 180.0 N 230 1 1
TOP 1 4.884 2.025 180.0 N 536 1 2
#
# CMP 359
CMP 56 4.44 2.44 270.0 N R214 ??? ;0=1,1=0.016000
PRP ALT_SYMBOLS '(SMC_0402R_C_H016)' 
PRP PARENT_PART_TYPE 'RESISTOR' 
PRP PARENT_PPT 'RESISTOR' 
PRP PARENT_PPT_PART 'RESISTOR-G155-11001-01,1KOHM,1%' 
PRP PART_NAME 'RESISTOR' 
TOP 0 4.44 2.419 270.0 N 333 1 1
TOP 1 4.44 2.461 270.0 N 2 271 2
#
# CMP 360
CMP 56 4.905 2.115 180.0 N R193 ??? ;0=1,1=0.016000
PRP SIGNAL_MODEL 'RESISTOR-G155-100R0-J0_0OHM_-' 
PRP ALT_SYMBOLS '(SMC_0402R_C_H016)' 
PRP PARENT_PART_TYPE 'RESISTOR' 
PRP PARENT_PPT 'RESISTOR' 
PRP PARENT_PPT_PART 'RESISTOR-G155-14701-01,4.7KOHM,1%' 
PRP PART_NAME 'RESISTOR' 
TOP 0 4.926 2.115 180.0 N 1 95 1
TOP 1 4.884 2.115 180.0 N 314 3 2
#
# CMP 361
CMP 56 4.395 2.44 90.0 N R213 ??? ;0=1,1=0.016000
PRP SIGNAL_MODEL 'RESISTOR-G155-100R0-J0_0OHM_-' 
PRP ALT_SYMBOLS '(SMC_0402R_C_H016)' 
PRP PARENT_PART_TYPE 'RESISTOR' 
PRP PARENT_PPT 'RESISTOR' 
PRP PARENT_PPT_PART 'RESISTOR-G155-11002-01,10KOHM,1%' 
PRP PART_NAME 'RESISTOR' 
TOP 0 4.395 2.461 90.0 N 1 96 1
TOP 1 4.395 2.419 90.0 N 333 2 2
#
# CMP 362
CMP 56 3.18 2.209 180.0 N R289 ??? ;0=1,1=0.016000
PRP HARD_LOCATION 'YES' 
PRP SIGNAL_MODEL 'RESISTOR-G155-100R0-J0_0OHM_-' 
PRP ALT_SYMBOLS '(SMC_0402R_C_H016)' 
PRP PARENT_PART_TYPE 'RESISTOR' 
PRP PARENT_PPT 'RESISTOR' 
PRP PARENT_PPT_PART 'RESISTOR-G155-14701-01,4.7KOHM,1%' 
PRP PART_NAME 'RESISTOR' 
TOP 0 3.201 2.209 180.0 N 1 97 1
TOP 1 3.159 2.209 180.0 N 369 2 2
#
# CMP 363
CMP 56 3.18 2.164 180.0 N R302 ??? ;0=1,1=0.016000
PRP ALT_SYMBOLS '(SMC_0402R_C_H016)' 
PRP PARENT_PART_TYPE 'RESISTOR' 
PRP PARENT_PPT 'RESISTOR' 
PRP PARENT_PPT_PART 'RESISTOR-G155-11001-01,1KOHM,1%' 
PRP PART_NAME 'RESISTOR' 
TOP 0 3.201 2.164 180.0 N 371 1 1
TOP 1 3.159 2.164 180.0 N 2 272 2
#
# CMP 364
CMP 56 3.189 2.11 180.0 N R83 ??? ;0=1,1=0.016000
PRP SIGNAL_MODEL 'RESISTOR-G155-100R0-J0_0OHM_-' 
PRP ALT_SYMBOLS '(SMC_0402R_C_H016,C0402-0P8MM-45DG)' 
PRP PARENT_PART_TYPE 'RESISTOR' 
PRP PARENT_PPT 'RESISTOR' 
PRP PARENT_PPT_PART 'RESISTOR-G155-100R0-J0,0OHM,-' 
PRP PART_NAME 'RESISTOR' 
TOP 0 3.21 2.11 180.0 N 361 1 1
TOP 1 3.168 2.11 180.0 N 231 1 2
#
# CMP 365
CMP 56 3.259 2.085 90.0 N R277 ??? ;0=1,1=0.016000
PRP SIGNAL_MODEL 'RESISTOR-G155-11000-01_100OHM_A' 
PRP ALT_SYMBOLS '(SMC_0402R_C_H016)' 
PRP PARENT_PART_TYPE 'RESISTOR' 
PRP PARENT_PPT 'RESISTOR' 
PRP PARENT_PPT_PART 'RESISTOR-G155-11000-01,100OHM,1%' 
PRP PART_NAME 'RESISTOR' 
TOP 0 3.259 2.106 90.0 N 361 2 1
TOP 1 3.259 2.064 90.0 N 362 1 2
#
# CMP 366
CMP 56 3.189 2.06 180.0 N R84 ??? ;0=1,1=0.016000
PRP SIGNAL_MODEL 'RESISTOR-G155-100R0-J0_0OHM_-' 
PRP ALT_SYMBOLS '(SMC_0402R_C_H016,C0402-0P8MM-45DG)' 
PRP PARENT_PART_TYPE 'RESISTOR' 
PRP PARENT_PPT 'RESISTOR' 
PRP PARENT_PPT_PART 'RESISTOR-G155-100R0-J0,0OHM,-' 
PRP PART_NAME 'RESISTOR' 
TOP 0 3.21 2.06 180.0 N 362 2 1
TOP 1 3.168 2.06 180.0 N 233 1 2
#
# CMP 367
CMP 56 3.189 2.015 180.0 N R85 ??? ;0=1,1=0.016000
PRP SIGNAL_MODEL 'RESISTOR-G155-100R0-J0_0OHM_-' 
PRP ALT_SYMBOLS '(SMC_0402R_C_H016,C0402-0P8MM-45DG)' 
PRP PARENT_PART_TYPE 'RESISTOR' 
PRP PARENT_PPT 'RESISTOR' 
PRP PARENT_PPT_PART 'RESISTOR-G155-100R0-J0,0OHM,-' 
PRP PART_NAME 'RESISTOR' 
TOP 0 3.21 2.015 180.0 N 359 1 1
TOP 1 3.168 2.015 180.0 N 235 1 2
#
# CMP 368
CMP 56 3.259 1.99 90.0 N R276 ??? ;0=1,1=0.016000
PRP SIGNAL_MODEL 'RESISTOR-G155-11000-01_100OHM_A' 
PRP ALT_SYMBOLS '(SMC_0402R_C_H016)' 
PRP PARENT_PART_TYPE 'RESISTOR' 
PRP PARENT_PPT 'RESISTOR' 
PRP PARENT_PPT_PART 'RESISTOR-G155-11000-01,100OHM,1%' 
PRP PART_NAME 'RESISTOR' 
TOP 0 3.259 2.011 90.0 N 359 2 1
TOP 1 3.259 1.969 90.0 N 360 1 2
#
# CMP 369
CMP 56 3.189 1.965 180.0 N R86 ??? ;0=1,1=0.016000
PRP SIGNAL_MODEL 'RESISTOR-G155-100R0-J0_0OHM_-' 
PRP ALT_SYMBOLS '(SMC_0402R_C_H016,C0402-0P8MM-45DG)' 
PRP PARENT_PART_TYPE 'RESISTOR' 
PRP PARENT_PPT 'RESISTOR' 
PRP PARENT_PPT_PART 'RESISTOR-G155-100R0-J0,0OHM,-' 
PRP PART_NAME 'RESISTOR' 
TOP 0 3.21 1.965 180.0 N 360 2 1
TOP 1 3.168 1.965 180.0 N 236 1 2
#
# CMP 370
CMP 56 3.275 2.165 0.0 N R290 ??? ;0=1,1=0.016000
PRP HARD_LOCATION 'YES' 
PRP SIGNAL_MODEL 'RESISTOR-G155-100R0-J0_0OHM_-' 
PRP ALT_SYMBOLS '(SMC_0402R_C_H016)' 
PRP PARENT_PART_TYPE 'RESISTOR' 
PRP PARENT_PPT 'RESISTOR' 
PRP PARENT_PPT_PART 'RESISTOR-G155-14701-01,4.7KOHM,1%' 
PRP PART_NAME 'RESISTOR' 
TOP 0 3.254 2.165 0.0 N 1 98 1
TOP 1 3.296 2.165 0.0 N 371 2 2
#
# CMP 371
CMP 56 4.98 1.335 180.0 N R194 ??? ;0=1,1=0.016000
PRP SIGNAL_MODEL 'RESISTOR-G155-100R0-J0_0OHM_-' 
PRP ALT_SYMBOLS '(SMC_0402R_C_H016)' 
PRP PARENT_PART_TYPE 'RESISTOR' 
PRP PARENT_PPT 'RESISTOR' 
PRP PARENT_PPT_PART 'RESISTOR-G155-14701-01,4.7KOHM,1%' 
PRP PART_NAME 'RESISTOR' 
TOP 0 5.001 1.335 180.0 N 1 99 1
TOP 1 4.959 1.335 180.0 N 315 1 2
#
# CMP 372
CMP 56 4.98 1.43 0.0 N R222 ??? ;0=1,1=0.016000
PRP SIGNAL_MODEL 'RESISTOR-G155-11000-01_100OHM_A' 
PRP ALT_SYMBOLS '(SMC_0402R_C_H016)' 
PRP PARENT_PART_TYPE 'RESISTOR' 
PRP PARENT_PPT 'RESISTOR' 
PRP PARENT_PPT_PART 'RESISTOR-G155-11000-01,100OHM,1%' 
PRP PART_NAME 'RESISTOR' 
TOP 0 4.959 1.43 0.0 N 337 1 1
TOP 1 5.001 1.43 0.0 N 2 273 2
#
# CMP 373
CMP 56 4.98 1.385 180.0 N R221 ??? ;0=1,1=0.016000
PRP SIGNAL_MODEL 'RESISTOR-G155-11000-01_100OHM_A' 
PRP ALT_SYMBOLS '(SMC_0402R_C_H016)' 
PRP PARENT_PART_TYPE 'RESISTOR' 
PRP PARENT_PPT 'RESISTOR' 
PRP PARENT_PPT_PART 'RESISTOR-G155-11000-01,100OHM,1%' 
PRP PART_NAME 'RESISTOR' 
TOP 0 5.001 1.385 180.0 N 1 100 1
TOP 1 4.959 1.385 180.0 N 337 2 2
#
# CMP 374
CMP 56 4.439 0.973 0.0 N R241 ??? ;0=1,1=0.016000
PRP ALT_SYMBOLS '(SMC_0402R_C_H016)' 
PRP PARENT_PART_TYPE 'RESISTOR' 
PRP PARENT_PPT 'RESISTOR' 
PRP PARENT_PPT_PART 'RESISTOR-G155-11500-01,150OHM,1%' 
PRP PART_NAME 'RESISTOR' 
TOP 0 4.418 0.973 0.0 N 46 1 1
TOP 1 4.46 0.973 0.0 N 2 274 2
#
# CMP 375
CMP 56 4.343 0.973 180.0 N R239 ??? ;0=1,1=0.016000
PRP ALT_SYMBOLS '(SMC_0402R_C_H016)' 
PRP PARENT_PART_TYPE 'RESISTOR' 
PRP PARENT_PPT 'RESISTOR' 
PRP PARENT_PPT_PART 'RESISTOR-G155-11500-01,150OHM,1%' 
PRP PART_NAME 'RESISTOR' 
TOP 0 4.364 0.973 180.0 N 48 1 1
TOP 1 4.322 0.973 180.0 N 2 275 2
#
# CMP 376
CMP 56 4.205 0.9 90.0 N R235 ??? ;0=1,1=0.016000
PRP SIGNAL_MODEL 'RESISTOR-G155-100R0-J0_0OHM_-' 
PRP ALT_SYMBOLS '(SMC_0402R_C_H016)' 
PRP PARENT_PART_TYPE 'RESISTOR' 
PRP PARENT_PPT 'RESISTOR' 
PRP PARENT_PPT_PART 'RESISTOR-G155-14701-01,4.7KOHM,1%' 
PRP PART_NAME 'RESISTOR' 
TOP 0 4.205 0.921 90.0 N 41 1 1
TOP 1 4.205 0.879 90.0 N 342 2 2
#
# CMP 377
CMP 56 4.905 1.72 0.0 N R212 ??? ;0=1,1=0.016000
PRP SIGNAL_MODEL 'RESISTOR-G155-11000-01_100OHM_A' 
PRP ALT_SYMBOLS '(SMC_0402R_C_H016)' 
PRP PARENT_PART_TYPE 'RESISTOR' 
PRP PARENT_PPT 'RESISTOR' 
PRP PARENT_PPT_PART 'RESISTOR-G155-11000-01,100OHM,1%' 
PRP PART_NAME 'RESISTOR' 
TOP 0 4.884 1.72 0.0 N 332 1 1
TOP 1 4.926 1.72 0.0 N 2 276 2
#
# CMP 378
CMP 56 4.905 1.765 180.0 N R211 ??? ;0=1,1=0.016000
PRP SIGNAL_MODEL 'RESISTOR-G155-11000-01_100OHM_A' 
PRP ALT_SYMBOLS '(SMC_0402R_C_H016)' 
PRP PARENT_PART_TYPE 'RESISTOR' 
PRP PARENT_PPT 'RESISTOR' 
PRP PARENT_PPT_PART 'RESISTOR-G155-11000-01,100OHM,1%' 
PRP PART_NAME 'RESISTOR' 
TOP 0 4.926 1.765 180.0 N 1 101 1
TOP 1 4.884 1.765 180.0 N 332 2 2
#
# CMP 379
CMP 56 4.905 1.63 180.0 N R93 ??? ;0=1,1=0.016000
PRP SIGNAL_MODEL 'DEFAULT_RESISTOR_33OHM_2_1' 
PRP ALT_SYMBOLS '(SMC_0402R_C_H016)' 
PRP PARENT_PART_TYPE 'RESISTOR' 
PRP PARENT_PPT 'RESISTOR' 
PRP PARENT_PPT_PART 'RESISTOR-G155-133R0-01,33OHM,1%' 
PRP PART_NAME 'RESISTOR' 
TOP 0 4.926 1.63 180.0 N 228 2 1
TOP 1 4.884 1.63 180.0 N 368 1 2
#
# CMP 380
CMP 56 4.905 1.675 180.0 N R288 ??? ;0=1,1=0.016000
PRP HARD_LOCATION 'YES' 
PRP SIGNAL_MODEL 'RESISTOR-G155-100R0-J0_0OHM_-' 
PRP ALT_SYMBOLS '(SMC_0402R_C_H016)' 
PRP PARENT_PART_TYPE 'RESISTOR' 
PRP PARENT_PPT 'RESISTOR' 
PRP PARENT_PPT_PART 'RESISTOR-G155-14701-01,4.7KOHM,1%' 
PRP PART_NAME 'RESISTOR' 
TOP 0 4.926 1.675 180.0 N 2 277 1
TOP 1 4.884 1.675 180.0 N 368 2 2
#
# CMP 381
CMP 56 4.545 2.995 180.0 N R143 ??? ;0=1,1=0.016000
PRP SIGNAL_MODEL 'DEFAULT_RESISTOR_33OHM_2_1' 
PRP ALT_SYMBOLS '(SMC_0402R_C_H016)' 
PRP PARENT_PART_TYPE 'RESISTOR' 
PRP PARENT_PPT 'RESISTOR' 
PRP PARENT_PPT_PART 'RESISTOR-G155-133R0-01,33OHM,1%' 
PRP PART_NAME 'RESISTOR' 
TOP 0 4.566 2.995 180.0 N 203 3 1
TOP 1 4.524 2.995 180.0 N 286 1 2
#
# CMP 382
CMP 56 3.947 2.725 0.0 N R181 ??? ;0=1,1=0.016000
PRP SIGNAL_MODEL 'RESISTOR-G155-100R0-J0_0OHM_-' 
PRP REUSE_ID '1' 
PRP ALT_SYMBOLS '(SMC_0402R_C_H016,C0402-0P8MM-45DG)' 
PRP PARENT_PART_TYPE 'RESISTOR' 
PRP PARENT_PPT 'RESISTOR' 
PRP PARENT_PPT_PART 'RESISTOR-G155-100R0-J0,0OHM,-' 
PRP PART_NAME 'RESISTOR' 
TOP 0 3.926 2.725 0.0 N 28 1 1
TOP 1 3.968 2.725 0.0 N 284 1 2
#
# CMP 383
CMP 56 3.947 2.68 180.0 N R178 ??? ;0=1,1=0.016000
PRP SIGNAL_MODEL 'RESISTOR-G155-100R0-J0_0OHM_-' 
PRP REUSE_ID '2' 
PRP ALT_SYMBOLS '(SMC_0402R_C_H016)' 
PRP PARENT_PART_TYPE 'RESISTOR' 
PRP PARENT_PPT 'RESISTOR' 
PRP PARENT_PPT_PART 'RESISTOR-G155-14701-01,4.7KOHM,1%' 
PRP PART_NAME 'RESISTOR' 
TOP 0 3.968 2.68 180.0 N 19 10 1
TOP 1 3.926 2.68 180.0 N 28 2 2
#
# CMP 384
CMP 56 3.18 2.569 180.0 N R305 ??? ;0=1,1=0.016000
PRP ALT_SYMBOLS '(SMC_0402R_C_H016)' 
PRP PARENT_PART_TYPE 'RESISTOR' 
PRP PARENT_PPT 'RESISTOR' 
PRP PARENT_PPT_PART 'RESISTOR-G155-11001-01,1KOHM,1%' 
PRP PART_NAME 'RESISTOR' 
TOP 0 3.201 2.569 180.0 N 380 1 1
TOP 1 3.159 2.569 180.0 N 2 278 2
#
# CMP 385
CMP 56 4.889 2.707 90.0 N R141 ??? ;0=1,1=0.016000
PRP SIGNAL_MODEL 'RESISTOR-G155-100R0-J0_0OHM_-' 
PRP ALT_SYMBOLS '(SMC_0402R_C_H016,C0402-0P8MM-45DG)' 
PRP PARENT_PART_TYPE 'RESISTOR' 
PRP PARENT_PPT 'RESISTOR' 
PRP PARENT_PPT_PART 'RESISTOR-G155-100R0-J0,0OHM,-' 
PRP PART_NAME 'RESISTOR' 
TOP 0 4.889 2.728 90.0 N 284 2 1
TOP 1 4.889 2.686 90.0 N 23 1 2
#
# CMP 386
CMP 56 4.375 3.865 180.0 N R320 ??? ;0=1,1=0.016000
PRP HARD_LOCATION 'YES' 
PRP SIGNAL_MODEL 'RESISTOR-G155-100R0-J0_0OHM_-' 
PRP ALT_SYMBOLS '(SMC_0402R_C_H016)' 
PRP PARENT_PART_TYPE 'RESISTOR' 
PRP PARENT_PPT 'RESISTOR' 
PRP PARENT_PPT_PART 'RESISTOR-G155-14701-01,4.7KOHM,1%' 
PRP PART_NAME 'RESISTOR' 
TOP 0 4.396 3.865 180.0 N 1 102 1
TOP 1 4.354 3.865 180.0 N 93 2 2
#
# CMP 387
CMP 56 2.917 3.332 0.0 N R311 ??? ;0=1,1=0.016000
PRP SIGNAL_MODEL 'RESISTOR-G155-100R0-J0_0OHM_-' 
PRP ALT_SYMBOLS '(SMC_0402R_C_H016,C0402-0P8MM-45DG)' 
PRP PARENT_PART_TYPE 'RESISTOR' 
PRP PARENT_PPT 'RESISTOR' 
PRP PARENT_PPT_PART 'RESISTOR-G155-100R0-J0,0OHM,-' 
PRP PART_NAME 'RESISTOR' 
TOP 0 2.896 3.332 0.0 N 385 2 1
TOP 1 2.938 3.332 0.0 N 290 0 2
#
# CMP 388
CMP 56 2.916 3.259 0.0 N R310 ??? ;0=1,1=0.016000
PRP SIGNAL_MODEL 'RESISTOR-G155-100R0-J0_0OHM_-' 
PRP ALT_SYMBOLS '(SMC_0402R_C_H016,C0402-0P8MM-45DG)' 
PRP PARENT_PART_TYPE 'RESISTOR' 
PRP PARENT_PPT 'RESISTOR' 
PRP PARENT_PPT_PART 'RESISTOR-G155-100R0-J0,0OHM,-' 
PRP PART_NAME 'RESISTOR' 
TOP 0 2.895 3.259 0.0 N 384 2 1
TOP 1 2.937 3.259 0.0 N 288 0 2
#
# CMP 389
CMP 56 3.814 3.092 0.0 N R140 ??? ;0=1,1=0.016000
PRP SIGNAL_MODEL 'RESISTOR-G155-100R0-J0_0OHM_-' 
PRP REUSE_ID '18' 
PRP ALT_SYMBOLS '(SMC_0402R_C_H016,C0402-0P8MM-45DG)' 
PRP PARENT_PART_TYPE 'RESISTOR' 
PRP PARENT_PPT 'RESISTOR' 
PRP PARENT_PPT_PART 'RESISTOR-G155-100R0-J0,0OHM,-' 
PRP PART_NAME 'RESISTOR' 
TOP 0 3.793 3.092 0.0 N 283 1 1
TOP 1 3.835 3.092 0.0 N 20 1 2
#
# CMP 390
CMP 56 3.543 4.077 0.0 N R52 ??? ;0=1,1=0.016000
PRP REUSE_ID '16' 
PRP ALT_SYMBOLS '(SMC_0402R_C_H016)' 
PRP PARENT_PART_TYPE 'RESISTOR' 
PRP PARENT_PPT 'RESISTOR' 
PRP PARENT_PPT_PART 'RESISTOR-G155-05101-01,5.1KOHM,1%' 
PRP PART_NAME 'RESISTOR' 
TOP 0 3.522 4.077 0.0 N 79 2 1
TOP 1 3.564 4.077 0.0 N 2 279 2
#
# CMP 391
CMP 56 3.443 3.837 90.0 N R35 ??? ;0=1,1=0.016000
PRP REUSE_ID '33' 
PRP ALT_SYMBOLS '(SMC_0402R_C_H016)' 
PRP PARENT_PART_TYPE 'RESISTOR' 
PRP PARENT_PPT 'RESISTOR' 
PRP PARENT_PPT_PART 'RESISTOR-G155-11003-01,100KOHM,1%' 
PRP PART_NAME 'RESISTOR' 
TOP 0 3.443 3.858 90.0 N 415 1 1
TOP 1 3.443 3.816 90.0 N 112 1 2
#
# CMP 392
CMP 56 3.623 3.857 270.0 N R17 ??? ;0=1,1=0.016000
PRP REUSE_ID '34' 
PRP ALT_SYMBOLS '(SMC_0402R_C_H016)' 
PRP PARENT_PART_TYPE 'RESISTOR' 
PRP PARENT_PPT 'RESISTOR' 
PRP PARENT_PPT_PART 'RESISTOR-G155-120R0-01,20OHM,1%' 
PRP PART_NAME 'RESISTOR' 
TOP 0 3.623 3.836 270.0 N 19 11 1
TOP 1 3.623 3.878 270.0 N 17 0 2
#
# CMP 393
CMP 56 3.515 3.78 180.0 N R38 ??? ;0=1,1=0.016000
PRP REUSE_ID '25' 
PRP ALT_SYMBOLS '(SMC_0402R_C_H016)' 
PRP PARENT_PART_TYPE 'RESISTOR' 
PRP PARENT_PPT 'RESISTOR' 
PRP PARENT_PPT_PART 'RESISTOR-G155-04421-01,4.42KOHM,1%' 
PRP PART_NAME 'RESISTOR' 
TOP 0 3.536 3.78 180.0 N 18 1 1
TOP 1 3.494 3.78 180.0 N 112 2 2
#
# CMP 394
CMP 56 3.543 3.833 180.0 N R40 ??? ;0=1,1=0.016000
PRP REUSE_ID '27' 
PRP ALT_SYMBOLS '(SMC_0402R_C_H016)' 
PRP PARENT_PART_TYPE 'RESISTOR' 
PRP PARENT_PPT 'RESISTOR' 
PRP PARENT_PPT_PART 'RESISTOR-G155-12002-01,20KOHM,1%' 
PRP PART_NAME 'RESISTOR' 
TOP 0 3.564 3.833 180.0 N 17 1 1
TOP 1 3.522 3.833 180.0 N 18 2 2
#
# CMP 395
CMP 56 4.935 3.525 270.0 N R268 ??? ;0=1,1=0.016000
PRP ALT_SYMBOLS '(SMC_0402R_C_H016)' 
PRP PARENT_PART_TYPE 'RESISTOR' 
PRP PARENT_PPT 'RESISTOR' 
PRP PARENT_PPT_PART 'RESISTOR-G155-11003-01,100KOHM,1%' 
PRP PART_NAME 'RESISTOR' 
TOP 0 4.935 3.504 270.0 N 1 103 1
TOP 1 4.935 3.546 270.0 N 242 1 2
#
# CMP 396
CMP 56 4.985 3.525 270.0 N R112 ??? ;0=1,1=0.016000
PRP SIGNAL_MODEL 'DEFAULT_RESISTOR_33OHM_2_1' 
PRP ALT_SYMBOLS '(SMC_0402R_C_H016)' 
PRP PARENT_PART_TYPE 'RESISTOR' 
PRP PARENT_PPT 'RESISTOR' 
PRP PARENT_PPT_PART 'RESISTOR-G155-133R0-01,33OHM,1%' 
PRP PART_NAME 'RESISTOR' 
TOP 0 4.985 3.504 270.0 N 202 0 1
TOP 1 4.985 3.546 270.0 N 240 1 2
#
# CMP 397
CMP 56 4.785 3.525 90.0 N R116 ??? ;0=1,1=0.016000
PRP SIGNAL_MODEL 'DEFAULT_RESISTOR_33OHM_2_1' 
PRP ALT_SYMBOLS '(SMC_0402R_C_H016)' 
PRP PARENT_PART_TYPE 'RESISTOR' 
PRP PARENT_PPT 'RESISTOR' 
PRP PARENT_PPT_PART 'RESISTOR-G155-133R0-01,33OHM,1%' 
PRP PART_NAME 'RESISTOR' 
TOP 0 4.785 3.546 90.0 N 241 2 1
TOP 1 4.785 3.504 90.0 N 262 1 2
#
# CMP 398
CMP 56 4.835 3.525 90.0 N R117 ??? ;0=1,1=0.016000
PRP SIGNAL_MODEL 'DEFAULT_RESISTOR_33OHM_2_1' 
PRP ALT_SYMBOLS '(SMC_0402R_C_H016)' 
PRP PARENT_PART_TYPE 'RESISTOR' 
PRP PARENT_PPT 'RESISTOR' 
PRP PARENT_PPT_PART 'RESISTOR-G155-133R0-01,33OHM,1%' 
PRP PART_NAME 'RESISTOR' 
TOP 0 4.835 3.546 90.0 N 243 1 1
TOP 1 4.835 3.504 90.0 N 263 1 2
#
# CMP 399
CMP 56 4.885 3.525 270.0 N R113 ??? ;0=1,1=0.016000
PRP SIGNAL_MODEL 'DEFAULT_RESISTOR_33OHM_2_1' 
PRP ALT_SYMBOLS '(SMC_0402R_C_H016)' 
PRP PARENT_PART_TYPE 'RESISTOR' 
PRP PARENT_PPT 'RESISTOR' 
PRP PARENT_PPT_PART 'RESISTOR-G155-133R0-01,33OHM,1%' 
PRP PART_NAME 'RESISTOR' 
TOP 0 4.885 3.504 270.0 N 199 0 1
TOP 1 4.885 3.546 270.0 N 242 2 2
#
# CMP 400
CMP 56 4.735 3.525 90.0 N R114 ??? ;0=1,1=0.016000
PRP SIGNAL_MODEL 'RESISTOR-G155-100R0-J0_0OHM_-' 
PRP ALT_SYMBOLS '(SMC_0402R_C_H016)' 
PRP PARENT_PART_TYPE 'RESISTOR' 
PRP PARENT_PPT 'RESISTOR' 
PRP PARENT_PPT_PART 'RESISTOR-G155-14701-01,4.7KOHM,1%' 
PRP PART_NAME 'RESISTOR' 
TOP 0 4.735 3.546 90.0 N 241 3 1
TOP 1 4.735 3.504 90.0 N 2 280 2
#
# CMP 401
CMP 56 4.375 3.915 180.0 N R324 ??? ;0=1,1=0.016000
PRP SIGNAL_MODEL 'RESISTOR-G155-100R0-J0_0OHM_-' 
PRP ALT_SYMBOLS '(SMC_0402R_C_H016,C0402-0P8MM-45DG)' 
PRP PARENT_PART_TYPE 'RESISTOR' 
PRP PARENT_PPT 'RESISTOR' 
PRP PARENT_PPT_PART 'RESISTOR-G155-100R0-J0,0OHM,-' 
PRP PART_NAME 'RESISTOR' 
TOP 0 4.396 3.915 180.0 N 2 281 1
TOP 1 4.354 3.915 180.0 N 395 1 2
#
# CMP 402
CMP 56 4.375 4.015 0.0 N R323 ??? ;0=1,1=0.016000
PRP SIGNAL_MODEL 'RESISTOR-G155-100R0-J0_0OHM_-' 
PRP ALT_SYMBOLS '(SMC_0402R_C_H016)' 
PRP PARENT_PART_TYPE 'RESISTOR' 
PRP PARENT_PPT 'RESISTOR' 
PRP PARENT_PPT_PART 'RESISTOR-G155-14701-01,4.7KOHM,1%' 
PRP PART_NAME 'RESISTOR' 
TOP 0 4.354 4.015 0.0 N 394 1 1
TOP 1 4.396 4.015 0.0 N 2 282 2
#
# CMP 403
CMP 56 5.315 2.79 270.0 N R182 ??? ;0=1,1=0.016000
PRP SIGNAL_MODEL 'RESISTOR-G155-100R0-J0_0OHM_-' 
PRP ALT_SYMBOLS '(SMC_0402R_C_H016,C0402-0P8MM-45DG)' 
PRP PARENT_PART_TYPE 'RESISTOR' 
PRP PARENT_PPT 'RESISTOR' 
PRP PARENT_PPT_PART 'RESISTOR-G155-100R0-J0,0OHM,-' 
PRP PART_NAME 'RESISTOR' 
TOP 0 5.315 2.769 270.0 N 29 1 1
TOP 1 5.315 2.811 270.0 N 285 1 2
#
# CMP 404
CMP 56 5.27 2.79 90.0 N R179 ??? ;0=1,1=0.016000
PRP SIGNAL_MODEL 'RESISTOR-G155-100R0-J0_0OHM_-' 
PRP ALT_SYMBOLS '(SMC_0402R_C_H016)' 
PRP PARENT_PART_TYPE 'RESISTOR' 
PRP PARENT_PPT 'RESISTOR' 
PRP PARENT_PPT_PART 'RESISTOR-G155-14701-01,4.7KOHM,1%' 
PRP PART_NAME 'RESISTOR' 
TOP 0 5.27 2.811 90.0 N 19 12 1
TOP 1 5.27 2.769 90.0 N 29 2 2
#
# CMP 405
CMP 56 3.978 2.531 90.0 N R170 ??? ;0=1,1=0.016000
PRP SIGNAL_MODEL 'RESISTOR-G155-100R0-J0_0OHM_-' 
PRP REUSE_ID '23' 
PRP ALT_SYMBOLS '(SMC_0402R_C_H016)' 
PRP PARENT_PART_TYPE 'RESISTOR' 
PRP PARENT_PPT 'RESISTOR' 
PRP PARENT_PPT_PART 'RESISTOR-G155-11002-01,10KOHM,1%' 
PRP PART_NAME 'RESISTOR' 
TOP 0 3.978 2.552 90.0 N 1 104 1
TOP 1 3.978 2.51 90.0 N 304 1 2
#
# CMP 406
CMP 56 3.919 2.531 90.0 N R172 ??? ;0=1,1=0.016000
PRP SIGNAL_MODEL 'RESISTOR-G155-100R0-J0_0OHM_-' 
PRP REUSE_ID '24' 
PRP ALT_SYMBOLS '(SMC_0402R_C_H016)' 
PRP PARENT_PART_TYPE 'RESISTOR' 
PRP PARENT_PPT 'RESISTOR' 
PRP PARENT_PPT_PART 'RESISTOR-G155-11002-01,10KOHM,1%' 
PRP PART_NAME 'RESISTOR' 
TOP 0 3.919 2.552 90.0 N 1 105 1
TOP 1 3.919 2.51 90.0 N 305 1 2
#
# CMP 407
CMP 56 5.675 2.4 0.0 N R254 ??? ;0=1,1=0.016000
PRP ALT_SYMBOLS '(SMC_0402R_C_H016)' 
PRP PARENT_PART_TYPE 'RESISTOR' 
PRP PARENT_PPT 'RESISTOR' 
PRP PARENT_PPT_PART 'RESISTOR-G155-120R0-01,20OHM,1%' 
PRP PART_NAME 'RESISTOR' 
TOP 0 5.654 2.4 0.0 N 15 4 1
TOP 1 5.696 2.4 0.0 N 66 0 2
#
# CMP 408
CMP 56 5.75 2.245 0.0 N R248 ??? ;0=1,1=0.016000
PRP ALT_SYMBOLS '(SMC_0402R_C_H016)' 
PRP PARENT_PART_TYPE 'RESISTOR' 
PRP PARENT_PPT 'RESISTOR' 
PRP PARENT_PPT_PART 'RESISTOR-G155-11003-01,100KOHM,1%' 
PRP PART_NAME 'RESISTOR' 
TOP 0 5.729 2.245 0.0 N 347 1 1
TOP 1 5.771 2.245 0.0 N 58 1 2
#
# CMP 409
CMP 56 5.754 2.345 90.0 N R255 ??? ;0=1,1=0.016000
PRP ALT_SYMBOLS '(SMC_0402R_C_H016)' 
PRP PARENT_PART_TYPE 'RESISTOR' 
PRP PARENT_PPT 'RESISTOR' 
PRP PARENT_PPT_PART 'RESISTOR-G155-02262-01,22.6K,1%' 
PRP PART_NAME 'RESISTOR' 
TOP 0 5.754 2.366 90.0 N 66 1 1
TOP 1 5.754 2.324 90.0 N 67 1 2
#
# CMP 410
CMP 56 5.465 2.345 90.0 N R245 ??? ;0=1,1=0.016000
PRP SIGNAL_MODEL 'RESISTOR-G155-100R0-J0_0OHM_-' 
PRP ALT_SYMBOLS '(SMC_0402R_C_H016,C0402-0P8MM-45DG)' 
PRP PARENT_PART_TYPE 'RESISTOR' 
PRP PARENT_PPT 'RESISTOR' 
PRP PARENT_PPT_PART 'RESISTOR-G155-100R0-J0,0OHM,-' 
PRP PART_NAME 'RESISTOR' 
TOP 0 5.465 2.366 90.0 N 283 2 1
TOP 1 5.465 2.324 90.0 N 56 1 2
#
# CMP 411
CMP 56 6.4 1.08 180.0 N R419 ??? ;0=1,1=0.016000
PRP SIGNAL_MODEL 'RESISTOR-G155-100R0-J0_0OHM_-' 
PRP REUSE_ID '9' 
PRP ALT_SYMBOLS '(SMC_0402R_C_H016)' 
PRP PARENT_PART_TYPE 'RESISTOR' 
PRP PARENT_PPT 'RESISTOR' 
PRP PARENT_PPT_PART 'RESISTOR-G155-14701-01,4.7KOHM,1%' 
PRP PART_NAME 'RESISTOR' 
TOP 0 6.421 1.08 180.0 N 1 106 1
TOP 1 6.379 1.08 180.0 N 471 1 2
#
# CMP 412
CMP 56 6.4 1.02 180.0 N R414 ??? ;0=1,1=0.016000
PRP SIGNAL_MODEL 'RESISTOR-G155-100R0-J0_0OHM_-' 
PRP REUSE_ID '6' 
PRP ALT_SYMBOLS '(SMC_0402R_C_H016)' 
PRP PARENT_PART_TYPE 'RESISTOR' 
PRP PARENT_PPT 'RESISTOR' 
PRP PARENT_PPT_PART 'RESISTOR-G155-14701-01,4.7KOHM,1%' 
PRP PART_NAME 'RESISTOR' 
TOP 0 6.421 1.02 180.0 N 1 107 1
TOP 1 6.379 1.02 180.0 N 469 1 2
#
# CMP 413
CMP 56 6.4 0.965 180.0 N R410 ??? ;0=1,1=0.016000
PRP SIGNAL_MODEL 'RESISTOR-G155-100R0-J0_0OHM_-' 
PRP REUSE_ID '4' 
PRP ALT_SYMBOLS '(SMC_0402R_C_H016)' 
PRP PARENT_PART_TYPE 'RESISTOR' 
PRP PARENT_PPT 'RESISTOR' 
PRP PARENT_PPT_PART 'RESISTOR-G155-14701-01,4.7KOHM,1%' 
PRP PART_NAME 'RESISTOR' 
TOP 0 6.421 0.965 180.0 N 1 108 1
TOP 1 6.379 0.965 180.0 N 467 1 2
#
# CMP 414
CMP 56 5.935 0.965 0.0 N R423 ??? ;0=1,1=0.016000
PRP SIGNAL_MODEL 'RESISTOR-G155-100R0-J0_0OHM_-' 
PRP ALT_SYMBOLS '(SMC_0402R_C_H016)' 
PRP PARENT_PART_TYPE 'RESISTOR' 
PRP PARENT_PPT 'RESISTOR' 
PRP PARENT_PPT_PART 'RESISTOR-G155-14701-01,4.7KOHM,1%' 
PRP PART_NAME 'RESISTOR' 
TOP 0 5.914 0.965 0.0 N 1 109 1
TOP 1 5.956 0.965 0.0 N 473 3 2
#
# CMP 415
CMP 56 5.92053 2.33 180.0 N R298 ??? ;0=1,1=0.016000
PRP SIGNAL_MODEL 'DEFAULT_RESISTOR_33OHM_2_1' 
PRP ALT_SYMBOLS '(SMC_0402R_C_H016)' 
PRP PARENT_PART_TYPE 'RESISTOR' 
PRP PARENT_PPT 'RESISTOR' 
PRP PARENT_PPT_PART 'RESISTOR-G155-133R0-01,33OHM,1%' 
PRP PART_NAME 'RESISTOR' 
TOP 0 5.94153 2.33 180.0 N 374 2 1
TOP 1 5.89953 2.33 180.0 N 375 1 2
#
# CMP 416
CMP 56 5.92053 2.28402 180.0 N R297 ??? ;0=1,1=0.016000
PRP HARD_LOCATION 'YES' 
PRP SIGNAL_MODEL 'RESISTOR-G155-100R0-J0_0OHM_-' 
PRP ALT_SYMBOLS '(SMC_0402R_C_H016)' 
PRP PARENT_PART_TYPE 'RESISTOR' 
PRP PARENT_PPT 'RESISTOR' 
PRP PARENT_PPT_PART 'RESISTOR-G155-14701-01,4.7KOHM,1%' 
PRP PART_NAME 'RESISTOR' 
TOP 0 5.94153 2.28402 180.0 N 374 3 1
TOP 1 5.89953 2.28402 180.0 N 2 283 2
#
# CMP 417
CMP 56 5.92053 2.239 0.0 N R296 ??? ;0=1,1=0.016000
PRP HARD_LOCATION 'YES' 
PRP SIGNAL_MODEL 'RESISTOR-G155-100R0-J0_0OHM_-' 
PRP ALT_SYMBOLS '(SMC_0402R_C_H016)' 
PRP PARENT_PART_TYPE 'RESISTOR' 
PRP PARENT_PPT 'RESISTOR' 
PRP PARENT_PPT_PART 'RESISTOR-G155-14701-01,4.7KOHM,1%' 
PRP PART_NAME 'RESISTOR' 
TOP 0 5.89953 2.239 0.0 N 1 110 1
TOP 1 5.94153 2.239 0.0 N 374 4 2
#
# CMP 418
CMP 56 6.01902 1.92965 90.0 N R299 ??? ;0=1,1=0.016000
PRP SIGNAL_MODEL 'DEFAULT_RESISTOR_33OHM_2_1' 
PRP ALT_SYMBOLS '(SMC_0402R_C_H016)' 
PRP PARENT_PART_TYPE 'RESISTOR' 
PRP PARENT_PPT 'RESISTOR' 
PRP PARENT_PPT_PART 'RESISTOR-G155-133R0-01,33OHM,1%' 
PRP PART_NAME 'RESISTOR' 
TOP 0 6.01902 1.95065 90.0 N 376 2 1
TOP 1 6.01902 1.90865 90.0 N 377 1 2
#
# CMP 419
CMP 56 6.06902 1.92965 270.0 N R67 ??? ;0=1,1=0.016000
PRP SIGNAL_MODEL 'DEFAULT_RESISTOR_33OHM_2_1' 
PRP ALT_SYMBOLS '(SMC_0402R_C_H016)' 
PRP PARENT_PART_TYPE 'RESISTOR' 
PRP PARENT_PPT 'RESISTOR' 
PRP PARENT_PPT_PART 'RESISTOR-G155-133R0-01,33OHM,1%' 
PRP PART_NAME 'RESISTOR' 
TOP 0 6.06902 1.90865 270.0 N 521 0 1
TOP 1 6.06902 1.95065 270.0 N 523 1 2
#
# CMP 420
CMP 56 5.96902 1.92965 270.0 N R68 ??? ;0=1,1=0.016000
PRP SIGNAL_MODEL 'RESISTOR-G155-100R0-J0_0OHM_-' 
PRP ALT_SYMBOLS '(SMC_0402R_C_H016)' 
PRP PARENT_PART_TYPE 'RESISTOR' 
PRP PARENT_PPT 'RESISTOR' 
PRP PARENT_PPT_PART 'RESISTOR-G155-14701-01,4.7KOHM,1%' 
PRP PART_NAME 'RESISTOR' 
TOP 0 5.96902 1.90865 270.0 N 1 111 1
TOP 1 5.96902 1.95065 270.0 N 524 1 2
#
# CMP 421
CMP 56 5.91902 1.92965 270.0 N R66 ??? ;0=1,1=0.016000
PRP SIGNAL_MODEL 'DEFAULT_RESISTOR_33OHM_2_1' 
PRP ALT_SYMBOLS '(SMC_0402R_C_H016)' 
PRP PARENT_PART_TYPE 'RESISTOR' 
PRP PARENT_PPT 'RESISTOR' 
PRP PARENT_PPT_PART 'RESISTOR-G155-133R0-01,33OHM,1%' 
PRP PART_NAME 'RESISTOR' 
TOP 0 5.91902 1.90865 270.0 N 520 0 1
TOP 1 5.91902 1.95065 270.0 N 522 1 2
#
# CMP 422
CMP 56 5.935 1.08 0.0 N R407 ??? ;0=1,1=0.016000
PRP SIGNAL_MODEL 'DEFAULT_RESISTOR_33OHM_2_1' 
PRP REUSE_ID '1' 
PRP ALT_SYMBOLS '(SMC_0402R_C_H016)' 
PRP PARENT_PART_TYPE 'RESISTOR' 
PRP PARENT_PPT 'RESISTOR' 
PRP PARENT_PPT_PART 'RESISTOR-G155-133R0-01,33OHM,1%' 
PRP PART_NAME 'RESISTOR' 
TOP 0 5.914 1.08 0.0 N 320 2 1
TOP 1 5.956 1.08 0.0 N 465 1 2
#
# CMP 423
CMP 56 4.037 2.531 90.0 N R292 ??? ;0=1,1=0.016000
PRP SIGNAL_MODEL 'RESISTOR-G155-100R0-J0_0OHM_-' 
PRP ALT_SYMBOLS '(SMC_0402R_C_H016)' 
PRP PARENT_PART_TYPE 'RESISTOR' 
PRP PARENT_PPT 'RESISTOR' 
PRP PARENT_PPT_PART 'RESISTOR-G155-11002-01,10KOHM,1%' 
PRP PART_NAME 'RESISTOR' 
TOP 0 4.037 2.552 90.0 N 1 112 1
TOP 1 4.037 2.51 90.0 N 373 1 2
#
# CMP 424
CMP 56 3.285 2.532 270.0 N R303 ??? ;0=1,1=0.016000
PRP ALT_SYMBOLS '(SMC_0402R_C_H016)' 
PRP PARENT_PART_TYPE 'RESISTOR' 
PRP PARENT_PPT 'RESISTOR' 
PRP PARENT_PPT_PART 'RESISTOR-G155-11001-01,1KOHM,1%' 
PRP PART_NAME 'RESISTOR' 
TOP 0 3.285 2.511 270.0 N 378 1 1
TOP 1 3.285 2.553 270.0 N 2 284 2
#
# CMP 425
CMP 56 3.335 2.532 90.0 N R304 ??? ;0=1,1=0.016000
PRP SIGNAL_MODEL 'RESISTOR-G155-100R0-J0_0OHM_-' 
PRP ALT_SYMBOLS '(SMC_0402R_C_H016)' 
PRP PARENT_PART_TYPE 'RESISTOR' 
PRP PARENT_PPT 'RESISTOR' 
PRP PARENT_PPT_PART 'RESISTOR-G155-14701-01,4.7KOHM,1%' 
PRP PART_NAME 'RESISTOR' 
TOP 0 3.335 2.553 90.0 N 1 113 1
TOP 1 3.335 2.511 90.0 N 379 2 2
#
# CMP 426
CMP 57 1.505 2.95 180.0 N R489 ??? ;0=1,1=0.025000
PRP ALT_SYMBOLS '(SMC_0402R_C)' 
PRP PARENT_PART_TYPE 'RESISTOR' 
PRP PARENT_PPT 'RESISTOR' 
PRP PARENT_PPT_PART 'RESISTOR-G155-03921-01,3.92KOHM,1%' 
PRP PART_NAME 'RESISTOR' 
TOP 0 1.526 2.95 180.0 N 516 2 1
TOP 1 1.484 2.95 180.0 N 2 285 2
#
# CMP 427
CMP 57 5.58 3.915 0.0 N R14 ??? ;0=1,1=0.025000
PRP REUSE_ID '8' 
PRP ALT_SYMBOLS '(SMC_0402R_C)' 
PRP PARENT_PART_TYPE 'RESISTOR' 
PRP PARENT_PPT 'RESISTOR' 
PRP PARENT_PPT_PART 'RESISTOR-G155-03921-01,3.92KOHM,1%' 
PRP PART_NAME 'RESISTOR' 
TOP 0 5.559 3.915 0.0 N 276 3 1
TOP 1 5.601 3.915 0.0 N 2 286 2
#
# CMP 428
CMP 57 5.425 0.69 0.0 N R231 ??? ;0=1,1=0.025000
PRP REUSE_ID '14' 
PRP ALT_SYMBOLS '(SMC_0402R_C)' 
PRP PARENT_PART_TYPE 'RESISTOR' 
PRP PARENT_PPT 'RESISTOR' 
PRP PARENT_PPT_PART 'RESISTOR-G155-04221-01,4.22KOHM,1%' 
PRP PART_NAME 'RESISTOR' 
TOP 0 5.404 0.69 0.0 N 9 17 1
TOP 1 5.446 0.69 0.0 N 339 1 2
#
# CMP 429
CMP 57 5.775 0.775 90.0 N R228 ??? ;0=1,1=0.025000
PRP REUSE_ID '2' 
PRP ALT_SYMBOLS '(SMC_0402R_C)' 
PRP PARENT_PART_TYPE 'RESISTOR' 
PRP PARENT_PPT 'RESISTOR' 
PRP PARENT_PPT_PART 'RESISTOR-G152-00055-01,1.13KOHM,1%' 
PRP PART_NAME 'RESISTOR' 
TOP 0 5.775 0.796 90.0 N 32 3 1
TOP 1 5.775 0.754 90.0 N 31 1 2
#
# CMP 430
CMP 57 3.837 2.775 0.0 N R185 ??? ;0=1,1=0.025000
PRP REUSE_ID '8' 
PRP ALT_SYMBOLS '(SMC_0402R_C)' 
PRP PARENT_PART_TYPE 'RESISTOR' 
PRP PARENT_PPT 'RESISTOR' 
PRP PARENT_PPT_PART 'RESISTOR-G155-04221-01,4.22KOHM,1%' 
PRP PART_NAME 'RESISTOR' 
TOP 0 3.816 2.775 0.0 N 14 3 1
TOP 1 3.858 2.775 0.0 N 310 3 2
#
# CMP 431
CMP 57 4.96 2.615 270.0 N R166 ??? ;0=1,1=0.025000
PRP ALT_SYMBOLS '(SMC_0402R_C)' 
PRP PARENT_PART_TYPE 'RESISTOR' 
PRP PARENT_PPT 'RESISTOR' 
PRP PARENT_PPT_PART 'RESISTOR-G152-00055-01,1.13KOHM,1%' 
PRP PART_NAME 'RESISTOR' 
TOP 0 4.96 2.594 270.0 N 22 3 1
TOP 1 4.96 2.636 270.0 N 23 2 2
#
# CMP 432
CMP 57 5.278 2.632 270.0 N R187 ??? ;0=1,1=0.025000
PRP ALT_SYMBOLS '(SMC_0402R_C)' 
PRP PARENT_PART_TYPE 'RESISTOR' 
PRP PARENT_PPT 'RESISTOR' 
PRP PARENT_PPT_PART 'RESISTOR-G155-04221-01,4.22KOHM,1%' 
PRP PART_NAME 'RESISTOR' 
TOP 0 5.278 2.611 270.0 N 16 5 1
TOP 1 5.278 2.653 270.0 N 311 2 2
#
# CMP 433
CMP 58 6.1437 4.10827 90.0 N DS12 ??? ;0=1,1=0.035430
PRP ALT_SYMBOLS '(SMC_DS_063X031_V4)' 
PRP PARENT_PART_TYPE 'OPTICAL' 
PRP PARENT_PPT 'OPTICAL' 
PRP PARENT_PPT_PART 'OPTICAL-G170-10143-01' 
PRP PART_NAME 'OPTICAL' 
TOP 0 6.1437 4.13779 90.0 N 149 0 A
TOP 1 6.1437 4.07875 90.0 N 2 287 C
#
# CMP 434
CMP 58 6.02559 4.10827 90.0 N DS20 ??? ;0=1,1=0.035430
PRP ALT_SYMBOLS '(SMC_DS_063X031_V4)' 
PRP PARENT_PART_TYPE 'OPTICAL' 
PRP PARENT_PPT 'OPTICAL' 
PRP PARENT_PPT_PART 'OPTICAL-G170-10143-01' 
PRP PART_NAME 'OPTICAL' 
TOP 0 6.02559 4.13779 90.0 N 168 0 A
TOP 1 6.02559 4.07875 90.0 N 2 288 C
#
# CMP 435
CMP 58 5.90748 4.10827 90.0 N DS19 ??? ;0=1,1=0.035430
PRP ALT_SYMBOLS '(SMC_DS_063X031_V4)' 
PRP PARENT_PART_TYPE 'OPTICAL' 
PRP PARENT_PPT 'OPTICAL' 
PRP PARENT_PPT_PART 'OPTICAL-G170-10143-01' 
PRP PART_NAME 'OPTICAL' 
TOP 0 5.90748 4.13779 90.0 N 165 0 A
TOP 1 5.90748 4.07875 90.0 N 2 289 C
#
# CMP 436
CMP 58 5.67126 4.24606 90.0 N DS3 ??? ;0=1,1=0.035430
PRP HARD_LOCATION 'YES' 
PRP ALT_SYMBOLS '(SMC_DS_063X031_V4)' 
PRP PARENT_PART_TYPE 'OPTICAL' 
PRP PARENT_PPT 'OPTICAL' 
PRP PARENT_PPT_PART 'OPTICAL-G170-10143-01' 
PRP PART_NAME 'OPTICAL' 
TOP 0 5.67126 4.27558 90.0 N 169 0 A
TOP 1 5.67126 4.21654 90.0 N 170 1 C
#
# CMP 437
CMP 58 5.43504 4.10827 90.0 N DS6 ??? ;0=1,1=0.035430
PRP HARD_LOCATION 'YES' 
PRP ALT_SYMBOLS '(SMC_DS_063X031_V4)' 
PRP PARENT_PART_TYPE 'OPTICAL' 
PRP PARENT_PPT 'OPTICAL' 
PRP PARENT_PPT_PART 'OPTICAL-G170-10143-01' 
PRP PART_NAME 'OPTICAL' 
TOP 0 5.43504 4.13779 90.0 N 174 0 A
TOP 1 5.43504 4.07875 90.0 N 2 290 C
#
# CMP 438
CMP 58 5.78937 4.24606 90.0 N DS4 ??? ;0=1,1=0.035430
PRP HARD_LOCATION 'YES' 
PRP ALT_SYMBOLS '(SMC_DS_063X031_V4)' 
PRP PARENT_PART_TYPE 'OPTICAL' 
PRP PARENT_PPT 'OPTICAL' 
PRP PARENT_PPT_PART 'OPTICAL-G170-10143-01' 
PRP PART_NAME 'OPTICAL' 
TOP 0 5.78937 4.27558 90.0 N 171 0 A
TOP 1 5.78937 4.21654 90.0 N 172 1 C
#
# CMP 439
CMP 58 5.283 4.18001 90.0 N DS9 ??? ;0=1,1=0.035430
PRP HARD_LOCATION 'YES' 
PRP ALT_SYMBOLS '(SMC_DS_063X031_V4)' 
PRP PARENT_PART_TYPE 'OPTICAL' 
PRP PARENT_PPT 'OPTICAL' 
PRP PARENT_PPT_PART 'OPTICAL-G170-10143-01' 
PRP PART_NAME 'OPTICAL' 
TOP 0 5.283 4.20953 90.0 N 177 0 A
TOP 1 5.283 4.15049 90.0 N 2 291 C
#
# CMP 440
CMP 58 5.43504 4.24606 90.0 N DS1 ??? ;0=1,1=0.035430
PRP REUSE_ID '2' 
PRP ALT_SYMBOLS '(SMC_DS_063X031_V4)' 
PRP PARENT_PART_TYPE 'OPTICAL' 
PRP PARENT_PPT 'OPTICAL' 
PRP PARENT_PPT_PART 'OPTICAL-G170-10143-01' 
PRP PART_NAME 'OPTICAL' 
TOP 0 5.43504 4.27558 90.0 N 143 0 A
TOP 1 5.43504 4.21654 90.0 N 144 1 C
#
# CMP 441
CMP 58 5.55315 4.10827 90.0 N DS7 ??? ;0=1,1=0.035430
PRP HARD_LOCATION 'YES' 
PRP ALT_SYMBOLS '(SMC_DS_063X031_V4)' 
PRP PARENT_PART_TYPE 'OPTICAL' 
PRP PARENT_PPT 'OPTICAL' 
PRP PARENT_PPT_PART 'OPTICAL-G170-10143-01' 
PRP PART_NAME 'OPTICAL' 
TOP 0 5.55315 4.13779 90.0 N 175 0 A
TOP 1 5.55315 4.07875 90.0 N 2 292 C
#
# CMP 442
CMP 58 6.1437 4.24606 90.0 N DS11 ??? ;0=1,1=0.035430
PRP HARD_LOCATION 'YES' 
PRP ALT_SYMBOLS '(SMC_DS_063X031_V4)' 
PRP PARENT_PART_TYPE 'OPTICAL' 
PRP PARENT_PPT 'OPTICAL' 
PRP PARENT_PPT_PART 'OPTICAL-G170-10143-01' 
PRP PART_NAME 'OPTICAL' 
TOP 0 6.1437 4.27558 90.0 N 147 0 A
TOP 1 6.1437 4.21654 90.0 N 148 1 C
#
# CMP 443
CMP 58 6.02559 4.24606 90.0 N DS10 ??? ;0=1,1=0.035430
PRP HARD_LOCATION 'YES' 
PRP ALT_SYMBOLS '(SMC_DS_063X031_V4)' 
PRP PARENT_PART_TYPE 'OPTICAL' 
PRP PARENT_PPT 'OPTICAL' 
PRP PARENT_PPT_PART 'OPTICAL-G170-10143-01' 
PRP PART_NAME 'OPTICAL' 
TOP 0 6.02559 4.27558 90.0 N 145 0 A
TOP 1 6.02559 4.21654 90.0 N 146 1 C
#
# CMP 444
CMP 58 5.78937 4.10827 90.0 N DS5 ??? ;0=1,1=0.035430
PRP HARD_LOCATION 'YES' 
PRP ALT_SYMBOLS '(SMC_DS_063X031_V4)' 
PRP PARENT_PART_TYPE 'OPTICAL' 
PRP PARENT_PPT 'OPTICAL' 
PRP PARENT_PPT_PART 'OPTICAL-G170-10143-01' 
PRP PART_NAME 'OPTICAL' 
TOP 0 5.78937 4.13779 90.0 N 173 0 A
TOP 1 5.78937 4.07875 90.0 N 2 293 C
#
# CMP 445
CMP 58 5.67126 4.10827 90.0 N DS8 ??? ;0=1,1=0.035430
PRP HARD_LOCATION 'YES' 
PRP REUSE_ID '2' 
PRP ALT_SYMBOLS '(SMC_DS_063X031_V4)' 
PRP PARENT_PART_TYPE 'OPTICAL' 
PRP PARENT_PPT 'OPTICAL' 
PRP PARENT_PPT_PART 'OPTICAL-G170-10143-01' 
PRP PART_NAME 'OPTICAL' 
TOP 0 5.67126 4.13779 90.0 N 176 0 A
TOP 1 5.67126 4.07875 90.0 N 2 294 C
#
# CMP 446
CMP 58 5.55315 4.24606 90.0 N DS2 ??? ;0=1,1=0.035430
PRP ALT_SYMBOLS '(SMC_DS_063X031_V4)' 
PRP PARENT_PART_TYPE 'OPTICAL' 
PRP PARENT_PPT 'OPTICAL' 
PRP PARENT_PPT_PART 'OPTICAL-G170-10143-01' 
PRP PART_NAME 'OPTICAL' 
TOP 0 5.55315 4.27558 90.0 N 166 0 A
TOP 1 5.55315 4.21654 90.0 N 167 1 C
#
# CMP 447
CMP 59 0.5 1.57 180.0 N C310 ??? ;0=1,1=0.012990
PRP ALT_SYMBOLS '(SMC_0201R_C)' 
PRP PARENT_PART_TYPE 'CAPACITOR' 
PRP PARENT_PPT 'CAPACITOR' 
PRP PARENT_PPT_PART 'CAPACITOR-G104-0A180-FJ,18PF,5%' 
PRP PART_NAME 'CAPACITOR' 
TOP 0 0.51043 1.57 180.0 N 2 295 1
TOP 1 0.48957 1.57 180.0 N 91 0 2
#
# CMP 448
CMP 59 0.514 1 0.0 N C311 ??? ;0=1,1=0.012990
PRP ALT_SYMBOLS '(SMC_0201R_C)' 
PRP PARENT_PART_TYPE 'CAPACITOR' 
PRP PARENT_PPT 'CAPACITOR' 
PRP PARENT_PPT_PART 'CAPACITOR-G104-0A180-FJ,18PF,5%' 
PRP PART_NAME 'CAPACITOR' 
TOP 0 0.50357 1 0.0 N 2 296 1
TOP 1 0.52443 1 0.0 N 92 0 2
#
# CMP 449
CMP 59 0.507 2.68 0.0 N C317 ??? ;0=1,1=0.012990
PRP ALT_SYMBOLS '(SMC_0201R_C)' 
PRP PARENT_PART_TYPE 'CAPACITOR' 
PRP PARENT_PPT 'CAPACITOR' 
PRP PARENT_PPT_PART 'CAPACITOR-G104-0A180-FJ,18PF,5%' 
PRP PART_NAME 'CAPACITOR' 
TOP 0 0.49657 2.68 0.0 N 2 297 1
TOP 1 0.51743 2.68 0.0 N 94 0 2
#
# CMP 450
CMP 59 0.506 2.166 180.0 N C318 ??? ;0=1,1=0.012990
PRP ALT_SYMBOLS '(SMC_0201R_C)' 
PRP PARENT_PART_TYPE 'CAPACITOR' 
PRP PARENT_PPT 'CAPACITOR' 
PRP PARENT_PPT_PART 'CAPACITOR-G104-0A180-FJ,18PF,5%' 
PRP PART_NAME 'CAPACITOR' 
TOP 0 0.51643 2.166 180.0 N 2 298 1
TOP 1 0.49557 2.166 180.0 N 95 0 2
#
# CMP 451
CMP 59 1.725 2.9 180.0 N C307 ??? ;0=1,1=0.012990
PRP ALT_SYMBOLS '(SMC_0201R_C)' 
PRP PARENT_PART_TYPE 'CAPACITOR' 
PRP PARENT_PPT 'CAPACITOR' 
PRP PARENT_PPT_PART 'CAPACITOR-G104-0B103-EK,0.01UF,10%' 
PRP PART_NAME 'CAPACITOR' 
TOP 0 1.73543 2.9 180.0 N 87 1 1
TOP 1 1.71457 2.9 180.0 N 2 299 2
#
# CMP 452
CMP 59 5.721 3.712 180.0 N C4 ??? ;0=1,1=0.012990
PRP REUSE_ID '20' 
PRP ALT_SYMBOLS '(SMC_0201R_C)' 
PRP PARENT_PART_TYPE 'CAPACITOR' 
PRP PARENT_PPT 'CAPACITOR' 
PRP PARENT_PPT_PART 'CAPACITOR-G104-0F224-BK,0.22UF,10%' 
PRP PART_NAME 'CAPACITOR' 
TOP 0 5.73143 3.712 180.0 N 2 300 1
TOP 1 5.71057 3.712 180.0 N 103 1 2
#
# CMP 453
CMP 59 5.496 3.912 180.0 N C8 ??? ;0=1,1=0.012990
PRP REUSE_ID '9' 
PRP ALT_SYMBOLS '(SMC_0201R_C)' 
PRP PARENT_PART_TYPE 'CAPACITOR' 
PRP PARENT_PPT 'CAPACITOR' 
PRP PARENT_PPT_PART 'CAPACITOR-G104-0B103-EK,0.01UF,10%' 
PRP PART_NAME 'CAPACITOR' 
TOP 0 5.50643 3.912 180.0 N 128 3 1
TOP 1 5.48557 3.912 180.0 N 2 301 2
#
# CMP 454
CMP 59 1.456 4.086 0.0 N C11 ??? ;0=1,1=0.012990
PRP REUSE_ID '19' 
PRP ALT_SYMBOLS '(SMC_0201R_C)' 
PRP PARENT_PART_TYPE 'CAPACITOR' 
PRP PARENT_PPT 'CAPACITOR' 
PRP PARENT_PPT_PART 'CAPACITOR-G104-0B101-FK,100PF,10%' 
PRP PART_NAME 'CAPACITOR' 
TOP 0 1.44557 4.086 0.0 N 11 2 1
TOP 1 1.46643 4.086 0.0 N 12 2 2
#
# CMP 455
CMP 59 1.461 4.031 180.0 N C43 ??? ;0=1,1=0.012990
PRP REUSE_ID '21' 
PRP ALT_SYMBOLS '(SMC_0201R_C)' 
PRP PARENT_PART_TYPE 'CAPACITOR' 
PRP PARENT_PPT 'CAPACITOR' 
PRP PARENT_PPT_PART 'CAPACITOR-G104-0A180-FJ,18PF,5%' 
PRP PART_NAME 'CAPACITOR' 
TOP 0 1.47143 4.031 180.0 N 105 1 1
TOP 1 1.45057 4.031 180.0 N 90 2 2
#
# CMP 456
CMP 59 1.461 3.901 0.0 N C75 ??? ;0=1,1=0.012990
PRP REUSE_ID '24' 
PRP ALT_SYMBOLS '(SMC_0201R_C)' 
PRP PARENT_PART_TYPE 'CAPACITOR' 
PRP PARENT_PPT 'CAPACITOR' 
PRP PARENT_PPT_PART 'CAPACITOR-G104-0B103-EK,0.01UF,10%' 
PRP PART_NAME 'CAPACITOR' 
TOP 0 1.45057 3.901 0.0 N 2 302 1
TOP 1 1.47143 3.901 0.0 N 126 2 2
#
# CMP 457
CMP 59 1.28 3.79 180.0 N C86 ??? ;0=1,1=0.012990
PRP ALT_SYMBOLS '(SMC_0201R_C)' 
PRP PARENT_PART_TYPE 'CAPACITOR' 
PRP PARENT_PPT 'CAPACITOR' 
PRP PARENT_PPT_PART 'CAPACITOR-G104-0A180-FJ,18PF,5%' 
PRP PART_NAME 'CAPACITOR' 
TOP 0 1.29043 3.79 180.0 N 2 303 1
TOP 1 1.26957 3.79 180.0 N 129 2 2
#
# CMP 458
CMP 59 1.225 3.79 0.0 N C87 ??? ;0=1,1=0.012990
PRP ALT_SYMBOLS '(SMC_0201R_C)' 
PRP PARENT_PART_TYPE 'CAPACITOR' 
PRP PARENT_PPT 'CAPACITOR' 
PRP PARENT_PPT_PART 'CAPACITOR-G104-0A180-FJ,18PF,5%' 
PRP PART_NAME 'CAPACITOR' 
TOP 0 1.21457 3.79 0.0 N 2 304 1
TOP 1 1.23543 3.79 0.0 N 130 2 2
#
# CMP 459
CMP 59 3.63673 2.402 270.0 N C51 ??? ;0=1,1=0.012990
PRP ALT_SYMBOLS '(SMC_0201R_C)' 
PRP PARENT_PART_TYPE 'CAPACITOR' 
PRP PARENT_PPT 'CAPACITOR' 
PRP PARENT_PPT_PART 'CAPACITOR-G104-0A120-FJ,12PF,5%' 
PRP PART_NAME 'CAPACITOR' 
TOP 0 3.63673 2.39157 270.0 N 114 2 1
TOP 1 3.63673 2.41243 270.0 N 2 305 2
#
# CMP 460
CMP 59 3.63673 2.336 90.0 N C47 ??? ;0=1,1=0.012990
PRP HARD_LOCATION 'YES' 
PRP ALT_SYMBOLS '(SMC_0201R_C)' 
PRP PARENT_PART_TYPE 'CAPACITOR' 
PRP PARENT_PPT 'CAPACITOR' 
PRP PARENT_PPT_PART 'CAPACITOR-G104-0A120-FJ,12PF,5%' 
PRP PART_NAME 'CAPACITOR' 
TOP 0 3.63673 2.34643 90.0 N 109 2 1
TOP 1 3.63673 2.32557 90.0 N 2 306 2
#
# CMP 461
CMP 59 5.45 0.635 180.0 N C234 ??? ;0=1,1=0.012990
PRP REUSE_ID '17' 
PRP ALT_SYMBOLS '(SMC_0201R_C)' 
PRP PARENT_PART_TYPE 'CAPACITOR' 
PRP PARENT_PPT 'CAPACITOR' 
PRP PARENT_PPT_PART 'CAPACITOR-G104-0B103-EK,0.01UF,10%' 
PRP PART_NAME 'CAPACITOR' 
TOP 0 5.46043 0.635 180.0 N 37 1 1
TOP 1 5.43957 0.635 180.0 N 2 307 2
#
# CMP 462
CMP 59 5.77 0.609 0.0 N C231 ??? ;0=1,1=0.012990
PRP REUSE_ID '13' 
PRP ALT_SYMBOLS '(SMC_0201R_C)' 
PRP PARENT_PART_TYPE 'CAPACITOR' 
PRP PARENT_PPT 'CAPACITOR' 
PRP PARENT_PPT_PART 'CAPACITOR-G104-0B103-EK,0.01UF,10%' 
PRP PART_NAME 'CAPACITOR' 
TOP 0 5.75957 0.609 0.0 N 36 1 1
TOP 1 5.78043 0.609 0.0 N 2 308 2
#
# CMP 463
CMP 59 3.952 2.774 0.0 N C192 ??? ;0=1,1=0.012990
PRP REUSE_ID '9' 
PRP ALT_SYMBOLS '(SMC_0201R_C)' 
PRP PARENT_PART_TYPE 'CAPACITOR' 
PRP PARENT_PPT 'CAPACITOR' 
PRP PARENT_PPT_PART 'CAPACITOR-G104-0B103-EK,0.01UF,10%' 
PRP PART_NAME 'CAPACITOR' 
TOP 0 3.94157 2.774 0.0 N 28 3 1
TOP 1 3.96243 2.774 0.0 N 2 309 2
#
# CMP 464
CMP 59 4.963 2.777 180.0 N C191 ??? ;0=1,1=0.012990
PRP ALT_SYMBOLS '(SMC_0201R_C)' 
PRP PARENT_PART_TYPE 'CAPACITOR' 
PRP PARENT_PPT 'CAPACITOR' 
PRP PARENT_PPT_PART 'CAPACITOR-G104-0B103-EK,0.01UF,10%' 
PRP PART_NAME 'CAPACITOR' 
TOP 0 4.97343 2.777 180.0 N 27 1 1
TOP 1 4.95257 2.777 180.0 N 2 310 2
#
# CMP 465
CMP 59 3.982 3.09 270.0 N C190 ??? ;0=1,1=0.012990
PRP REUSE_ID '13' 
PRP ALT_SYMBOLS '(SMC_0201R_C)' 
PRP PARENT_PART_TYPE 'CAPACITOR' 
PRP PARENT_PPT 'CAPACITOR' 
PRP PARENT_PPT_PART 'CAPACITOR-G104-0B103-EK,0.01UF,10%' 
PRP PART_NAME 'CAPACITOR' 
TOP 0 3.982 3.07957 270.0 N 26 1 1
TOP 1 3.982 3.10043 270.0 N 2 311 2
#
# CMP 466
CMP 59 3.538 3.947 0.0 N C55 ??? ;0=1,1=0.012990
PRP REUSE_ID '29' 
PRP ALT_SYMBOLS '(SMC_0201R_C)' 
PRP PARENT_PART_TYPE 'CAPACITOR' 
PRP PARENT_PPT 'CAPACITOR' 
PRP PARENT_PPT_PART 'CAPACITOR-G104-0A180-FJ,18PF,5%' 
PRP PART_NAME 'CAPACITOR' 
TOP 0 3.52757 3.947 0.0 N 116 1 1
TOP 1 3.54843 3.947 0.0 N 112 3 2
#
# CMP 467
CMP 59 3.538 3.892 180.0 N C16 ??? ;0=1,1=0.012990
PRP REUSE_ID '28' 
PRP ALT_SYMBOLS '(SMC_0201R_C)' 
PRP PARENT_PART_TYPE 'CAPACITOR' 
PRP PARENT_PPT 'CAPACITOR' 
PRP PARENT_PPT_PART 'CAPACITOR-G104-0B101-FK,100PF,10%' 
PRP PART_NAME 'CAPACITOR' 
TOP 0 3.54843 3.892 180.0 N 17 2 1
TOP 1 3.52757 3.892 180.0 N 18 3 2
#
# CMP 468
CMP 59 3.537 4.121 180.0 N C77 ??? ;0=1,1=0.012990
PRP REUSE_ID '13' 
PRP ALT_SYMBOLS '(SMC_0201R_C)' 
PRP PARENT_PART_TYPE 'CAPACITOR' 
PRP PARENT_PPT 'CAPACITOR' 
PRP PARENT_PPT_PART 'CAPACITOR-G104-0B103-EK,0.01UF,10%' 
PRP PART_NAME 'CAPACITOR' 
TOP 0 3.54743 4.121 180.0 N 2 312 1
TOP 1 3.52657 4.121 180.0 N 127 1 2
#
# CMP 469
CMP 59 5.28 2.725 0.0 N C193 ??? ;0=1,1=0.012990
PRP ALT_SYMBOLS '(SMC_0201R_C)' 
PRP PARENT_PART_TYPE 'CAPACITOR' 
PRP PARENT_PPT 'CAPACITOR' 
PRP PARENT_PPT_PART 'CAPACITOR-G104-0B103-EK,0.01UF,10%' 
PRP PART_NAME 'CAPACITOR' 
TOP 0 5.26957 2.725 0.0 N 29 3 1
TOP 1 5.29043 2.725 0.0 N 2 313 2
#
# CMP 470
CMP 59 5.51 2.34 90.0 N C258 ??? ;0=1,1=0.012990
PRP ALT_SYMBOLS '(SMC_0201R_C)' 
PRP PARENT_PART_TYPE 'CAPACITOR' 
PRP PARENT_PPT 'CAPACITOR' 
PRP PARENT_PPT_PART 'CAPACITOR-G104-0B103-EK,0.01UF,10%' 
PRP PART_NAME 'CAPACITOR' 
TOP 0 5.51 2.35043 90.0 N 2 314 1
TOP 1 5.51 2.32957 90.0 N 56 2 2
#
# CMP 471
CMP 59 5.64 2.34 270.0 N C264 ??? ;0=1,1=0.012990
PRP ALT_SYMBOLS '(SMC_0201R_C)' 
PRP PARENT_PART_TYPE 'CAPACITOR' 
PRP PARENT_PPT 'CAPACITOR' 
PRP PARENT_PPT_PART 'CAPACITOR-G104-0A180-FJ,18PF,5%' 
PRP PART_NAME 'CAPACITOR' 
TOP 0 5.64 2.32957 270.0 N 62 1 1
TOP 1 5.64 2.35043 270.0 N 58 2 2
#
# CMP 472
CMP 59 5.695 2.345 90.0 N C267 ??? ;0=1,1=0.012990
PRP ALT_SYMBOLS '(SMC_0201R_C)' 
PRP PARENT_PART_TYPE 'CAPACITOR' 
PRP PARENT_PPT 'CAPACITOR' 
PRP PARENT_PPT_PART 'CAPACITOR-G104-0B101-FK,100PF,10%' 
PRP PART_NAME 'CAPACITOR' 
TOP 0 5.695 2.35543 90.0 N 66 2 1
TOP 1 5.695 2.33457 90.0 N 67 2 2
#
# CMP 473
CMP 60 3.765 1.06 0.0 N C291 ??? ;0=1,1=0.057000
PRP ALT_SYMBOLS '(SMC_0805R_H057)' 
PRP PARENT_PART_TYPE 'CAPACITOR' 
PRP PARENT_PPT 'CAPACITOR' 
PRP PARENT_PPT_PART 'CAPACITOR-G107-0F226-CM,22UF,20%' 
PRP PART_NAME 'CAPACITOR' 
TOP 0 3.732 1.06 0.0 N 9 18 1
TOP 1 3.798 1.06 0.0 N 2 315 2
#
# CMP 474
CMP 60 3.515 1.615 270.0 N C155 ??? ;0=1,1=0.057000
PRP ALT_SYMBOLS '(SMC_0805R_H057)' 
PRP PARENT_PART_TYPE 'CAPACITOR' 
PRP PARENT_PPT 'CAPACITOR' 
PRP PARENT_PPT_PART 'CAPACITOR-G107-0F476-AM,47UF,20%' 
PRP PART_NAME 'CAPACITOR' 
TOP 0 3.515 1.582 270.0 N 15 5 1
TOP 1 3.515 1.648 270.0 N 2 316 2
#
# CMP 475
CMP 60 3.705 1.615 270.0 N C137 ??? ;0=1,1=0.057000
PRP ALT_SYMBOLS '(SMC_0805R_H057)' 
PRP PARENT_PART_TYPE 'CAPACITOR' 
PRP PARENT_PPT 'CAPACITOR' 
PRP PARENT_PPT_PART 'CAPACITOR-G107-0F476-AM,47UF,20%' 
PRP PART_NAME 'CAPACITOR' 
TOP 0 3.705 1.582 270.0 N 7 6 1
TOP 1 3.705 1.648 270.0 N 2 317 2
#
# CMP 476
CMP 60 1.46 3.04 90.0 N C308 ??? ;0=1,1=0.057000
PRP ALT_SYMBOLS '(SMC_0805R_H057)' 
PRP PARENT_PART_TYPE 'CAPACITOR' 
PRP PARENT_PPT 'CAPACITOR' 
PRP PARENT_PPT_PART 'CAPACITOR-G107-0F106-EM,10UF,20%' 
PRP PART_NAME 'CAPACITOR' 
TOP 0 1.46 3.073 90.0 N 88 12 1
TOP 1 1.46 3.007 90.0 N 2 318 2
#
# CMP 477
CMP 60 1.815 3.26 0.0 N C284 ??? ;0=1,1=0.057000
PRP ALT_SYMBOLS '(SMC_0805R_H057)' 
PRP PARENT_PART_TYPE 'CAPACITOR' 
PRP PARENT_PPT 'CAPACITOR' 
PRP PARENT_PPT_PART 'CAPACITOR-G107-0F226-CM,22UF,20%' 
PRP PART_NAME 'CAPACITOR' 
TOP 0 1.782 3.26 0.0 N 77 3 1
TOP 1 1.848 3.26 0.0 N 2 319 2
#
# CMP 478
CMP 60 5.336 3.705 270.0 N C9 ??? ;0=1,1=0.057000
PRP REUSE_ID '24' 
PRP ALT_SYMBOLS '(SMC_0805R_H057)' 
PRP PARENT_PART_TYPE 'CAPACITOR' 
PRP PARENT_PPT 'CAPACITOR' 
PRP PARENT_PPT_PART 'CAPACITOR-G107-0F106-EM,10UF,20%' 
PRP PART_NAME 'CAPACITOR' 
TOP 0 5.336 3.672 270.0 N 3 15 1
TOP 1 5.336 3.738 270.0 N 2 320 2
#
# CMP 479
CMP 60 5.254 3.705 270.0 N C10 ??? ;0=1,1=0.057000
PRP REUSE_ID '17' 
PRP ALT_SYMBOLS '(SMC_0805R_H057)' 
PRP PARENT_PART_TYPE 'CAPACITOR' 
PRP PARENT_PPT 'CAPACITOR' 
PRP PARENT_PPT_PART 'CAPACITOR-G107-0F106-EM,10UF,20%' 
PRP PART_NAME 'CAPACITOR' 
TOP 0 5.254 3.672 270.0 N 3 16 1
TOP 1 5.254 3.738 270.0 N 2 321 2
#
# CMP 480
CMP 60 5.331 3.827 180.0 N C6 ??? ;0=1,1=0.057000
PRP REUSE_ID '7' 
PRP ALT_SYMBOLS '(SMC_0805R_H057)' 
PRP PARENT_PART_TYPE 'CAPACITOR' 
PRP PARENT_PPT 'CAPACITOR' 
PRP PARENT_PPT_PART 'CAPACITOR-G107-0F106-EM,10UF,20%' 
PRP PART_NAME 'CAPACITOR' 
TOP 0 5.364 3.827 180.0 N 120 2 1
TOP 1 5.298 3.827 180.0 N 2 322 2
#
# CMP 481
CMP 60 1.681 4.151 0.0 N C30 ??? ;0=1,1=0.057000
PRP REUSE_ID '14' 
PRP ALT_SYMBOLS '(SMC_0805R_H057)' 
PRP PARENT_PART_TYPE 'CAPACITOR' 
PRP PARENT_PPT 'CAPACITOR' 
PRP PARENT_PPT_PART 'CAPACITOR-G107-0F106-EM,10UF,20%' 
PRP PART_NAME 'CAPACITOR' 
TOP 0 1.648 4.151 0.0 N 84 3 1
TOP 1 1.714 4.151 0.0 N 2 323 2
#
# CMP 482
CMP 60 1.711 3.776 0.0 N C32 ??? ;0=1,1=0.057000
PRP REUSE_ID '10' 
PRP ALT_SYMBOLS '(SMC_0805R_H057)' 
PRP PARENT_PART_TYPE 'CAPACITOR' 
PRP PARENT_PPT 'CAPACITOR' 
PRP PARENT_PPT_PART 'CAPACITOR-G107-0F106-EM,10UF,20%' 
PRP PART_NAME 'CAPACITOR' 
TOP 0 1.678 3.776 0.0 N 84 4 1
TOP 1 1.744 3.776 0.0 N 2 324 2
#
# CMP 483
CMP 60 2.186 4.071 270.0 N C14 ??? ;0=1,1=0.057000
PRP REUSE_ID '2' 
PRP ALT_SYMBOLS '(SMC_0805R_H057)' 
PRP PARENT_PART_TYPE 'CAPACITOR' 
PRP PARENT_PPT 'CAPACITOR' 
PRP PARENT_PPT_PART 'CAPACITOR-G107-0F226-CM,22UF,20%' 
PRP PART_NAME 'CAPACITOR' 
TOP 0 2.186 4.038 270.0 N 13 5 1
TOP 1 2.186 4.104 270.0 N 2 325 2
#
# CMP 484
CMP 60 2.261 4.071 270.0 N C15 ??? ;0=1,1=0.057000
PRP REUSE_ID '1' 
PRP ALT_SYMBOLS '(SMC_0805R_H057)' 
PRP PARENT_PART_TYPE 'CAPACITOR' 
PRP PARENT_PPT 'CAPACITOR' 
PRP PARENT_PPT_PART 'CAPACITOR-G107-0F226-CM,22UF,20%' 
PRP PART_NAME 'CAPACITOR' 
TOP 0 2.261 4.038 270.0 N 13 6 1
TOP 1 2.261 4.104 270.0 N 2 326 2
#
# CMP 485
CMP 60 2.236 3.861 90.0 N C13 ??? ;0=1,1=0.057000
PRP REUSE_ID '4' 
PRP ALT_SYMBOLS '(SMC_0805R_H057)' 
PRP PARENT_PART_TYPE 'CAPACITOR' 
PRP PARENT_PPT 'CAPACITOR' 
PRP PARENT_PPT_PART 'CAPACITOR-G107-0F226-CM,22UF,20%' 
PRP PART_NAME 'CAPACITOR' 
TOP 0 2.236 3.894 90.0 N 13 7 1
TOP 1 2.236 3.828 90.0 N 2 327 2
#
# CMP 486
CMP 60 5.24 1.24 0.0 N C173 ??? ;0=1,1=0.057000
PRP REUSE_ID '18' 
PRP ALT_SYMBOLS '(SMC_0805R_H057)' 
PRP PARENT_PART_TYPE 'CAPACITOR' 
PRP PARENT_PPT 'CAPACITOR' 
PRP PARENT_PPT_PART 'CAPACITOR-G107-0F476-AM,47UF,20%' 
PRP PART_NAME 'CAPACITOR' 
TOP 0 5.207 1.24 0.0 N 10 21 1
TOP 1 5.273 1.24 0.0 N 2 328 2
#
# CMP 487
CMP 60 5.69 1.61 0.0 N C269 ??? ;0=1,1=0.057000
PRP ALT_SYMBOLS '(SMC_0805R_H057)' 
PRP PARENT_PART_TYPE 'CAPACITOR' 
PRP PARENT_PPT 'CAPACITOR' 
PRP PARENT_PPT_PART 'CAPACITOR-G107-0F476-AM,47UF,20%' 
PRP PART_NAME 'CAPACITOR' 
TOP 0 5.657 1.61 0.0 N 15 6 1
TOP 1 5.723 1.61 0.0 N 2 329 2
#
# CMP 488
CMP 60 5.385 2.09 90.0 N C260 ??? ;0=1,1=0.057000
PRP ALT_SYMBOLS '(SMC_0805R_H057)' 
PRP PARENT_PART_TYPE 'CAPACITOR' 
PRP PARENT_PPT 'CAPACITOR' 
PRP PARENT_PPT_PART 'CAPACITOR-G107-0F106-EM,10UF,20%' 
PRP PART_NAME 'CAPACITOR' 
TOP 0 5.385 2.123 90.0 N 55 3 1
TOP 1 5.385 2.057 90.0 N 2 330 2
#
# CMP 489
CMP 60 5.39 1.63 90.0 N C271 ??? ;0=1,1=0.057000
PRP ALT_SYMBOLS '(SMC_0805R_H057)' 
PRP PARENT_PART_TYPE 'CAPACITOR' 
PRP PARENT_PPT 'CAPACITOR' 
PRP PARENT_PPT_PART 'CAPACITOR-G107-0F476-AM,47UF,20%' 
PRP PART_NAME 'CAPACITOR' 
TOP 0 5.39 1.663 90.0 N 15 7 1
TOP 1 5.39 1.597 90.0 N 2 331 2
#
# CMP 490
CMP 60 5.35 1.82 270.0 N C270 ??? ;0=1,1=0.057000
PRP ALT_SYMBOLS '(SMC_0805R_H057)' 
PRP PARENT_PART_TYPE 'CAPACITOR' 
PRP PARENT_PPT 'CAPACITOR' 
PRP PARENT_PPT_PART 'CAPACITOR-G107-0F476-AM,47UF,20%' 
PRP PART_NAME 'CAPACITOR' 
TOP 0 5.35 1.787 270.0 N 15 8 1
TOP 1 5.35 1.853 270.0 N 2 332 2
#
# CMP 491
CMP 60 4.966 1.264 180.0 N C292 ??? ;0=1,1=0.057000
PRP ALT_SYMBOLS '(SMC_0805R_H057)' 
PRP PARENT_PART_TYPE 'CAPACITOR' 
PRP PARENT_PPT 'CAPACITOR' 
PRP PARENT_PPT_PART 'CAPACITOR-G107-0F226-CM,22UF,20%' 
PRP PART_NAME 'CAPACITOR' 
TOP 0 4.999 1.264 180.0 N 9 19 1
TOP 1 4.933 1.264 180.0 N 2 333 2
#
# CMP 492
CMP 60 5.517 0.863 0.0 N C239 ??? ;0=1,1=0.057000
PRP REUSE_ID '10' 
PRP ALT_SYMBOLS '(SMC_0805R_H057)' 
PRP PARENT_PART_TYPE 'CAPACITOR' 
PRP PARENT_PPT 'CAPACITOR' 
PRP PARENT_PPT_PART 'CAPACITOR-G107-0F106-EM,10UF,20%' 
PRP PART_NAME 'CAPACITOR' 
TOP 0 5.484 0.863 0.0 N 9 20 1
TOP 1 5.55 0.863 0.0 N 2 334 2
#
# CMP 493
CMP 60 5.665 0.859 180.0 N C228 ??? ;0=1,1=0.057000
PRP REUSE_ID '12' 
PRP ALT_SYMBOLS '(SMC_0805R_H057)' 
PRP PARENT_PART_TYPE 'CAPACITOR' 
PRP PARENT_PPT 'CAPACITOR' 
PRP PARENT_PPT_PART 'CAPACITOR-G107-0F106-EM,10UF,20%' 
PRP PART_NAME 'CAPACITOR' 
TOP 0 5.698 0.859 180.0 N 32 4 1
TOP 1 5.632 0.859 180.0 N 2 335 2
#
# CMP 494
CMP 60 5.575 0.965 90.0 N C224 ??? ;0=1,1=0.057000
PRP REUSE_ID '7' 
PRP ALT_SYMBOLS '(SMC_0805R_H057)' 
PRP PARENT_PART_TYPE 'CAPACITOR' 
PRP PARENT_PPT 'CAPACITOR' 
PRP PARENT_PPT_PART 'CAPACITOR-G107-0F226-CM,22UF,20%' 
PRP PART_NAME 'CAPACITOR' 
TOP 0 5.575 0.998 90.0 N 19 13 1
TOP 1 5.575 0.932 90.0 N 2 336 2
#
# CMP 495
CMP 60 3.318 3.827 180.0 N C48 ??? ;0=1,1=0.057000
PRP REUSE_ID '20' 
PRP ALT_SYMBOLS '(SMC_0805R_H057)' 
PRP PARENT_PART_TYPE 'CAPACITOR' 
PRP PARENT_PPT 'CAPACITOR' 
PRP PARENT_PPT_PART 'CAPACITOR-G107-0F106-EM,10UF,20%' 
PRP PART_NAME 'CAPACITOR' 
TOP 0 3.351 3.827 180.0 N 110 3 1
TOP 1 3.285 3.827 180.0 N 2 337 2
#
# CMP 496
CMP 60 3.32 3.685 270.0 N C21 ??? ;0=1,1=0.057000
PRP REUSE_ID '18' 
PRP ALT_SYMBOLS '(SMC_0805R_H057)' 
PRP PARENT_PART_TYPE 'CAPACITOR' 
PRP PARENT_PPT 'CAPACITOR' 
PRP PARENT_PPT_PART 'CAPACITOR-G107-0F226-CM,22UF,20%' 
PRP PART_NAME 'CAPACITOR' 
TOP 0 3.32 3.652 270.0 N 19 14 1
TOP 1 3.32 3.718 270.0 N 2 338 2
#
# CMP 497
CMP 60 3.48 3.685 270.0 N C20 ??? ;0=1,1=0.057000
PRP REUSE_ID '3' 
PRP ALT_SYMBOLS '(SMC_0805R_H057)' 
PRP PARENT_PART_TYPE 'CAPACITOR' 
PRP PARENT_PPT 'CAPACITOR' 
PRP PARENT_PPT_PART 'CAPACITOR-G107-0F226-CM,22UF,20%' 
PRP PART_NAME 'CAPACITOR' 
TOP 0 3.48 3.652 270.0 N 19 15 1
TOP 1 3.48 3.718 270.0 N 2 339 2
#
# CMP 498
CMP 60 4.455 2.705 90.0 N C232 ??? ;0=1,1=0.057000
PRP ALT_SYMBOLS '(SMC_0805R_H057)' 
PRP PARENT_PART_TYPE 'CAPACITOR' 
PRP PARENT_PPT 'CAPACITOR' 
PRP PARENT_PPT_PART 'CAPACITOR-G107-0F226-CM,22UF,20%' 
PRP PART_NAME 'CAPACITOR' 
TOP 0 4.455 2.738 90.0 N 19 16 1
TOP 1 4.455 2.672 90.0 N 2 340 2
#
# CMP 499
CMP 60 4.167 2.936 180.0 N C238 ??? ;0=1,1=0.057000
PRP ALT_SYMBOLS '(SMC_0805R_H057)' 
PRP PARENT_PART_TYPE 'CAPACITOR' 
PRP PARENT_PPT 'CAPACITOR' 
PRP PARENT_PPT_PART 'CAPACITOR-G107-0F226-CM,22UF,20%' 
PRP PART_NAME 'CAPACITOR' 
TOP 0 4.2 2.936 180.0 N 1 114 1
TOP 1 4.134 2.936 180.0 N 2 341 2
#
# CMP 500
CMP 60 3.4 3.685 270.0 N C22 ??? ;0=1,1=0.057000
PRP REUSE_ID '19' 
PRP ALT_SYMBOLS '(SMC_0805R_H057)' 
PRP PARENT_PART_TYPE 'CAPACITOR' 
PRP PARENT_PPT 'CAPACITOR' 
PRP PARENT_PPT_PART 'CAPACITOR-G107-0F226-CM,22UF,20%' 
PRP PART_NAME 'CAPACITOR' 
TOP 0 3.4 3.652 270.0 N 19 17 1
TOP 1 3.4 3.718 270.0 N 2 342 2
#
# CMP 501
CMP 60 4.167 2.855 180.0 N C240 ??? ;0=1,1=0.057000
PRP ALT_SYMBOLS '(SMC_0805R_H057)' 
PRP PARENT_PART_TYPE 'CAPACITOR' 
PRP PARENT_PPT 'CAPACITOR' 
PRP PARENT_PPT_PART 'CAPACITOR-G107-0F226-CM,22UF,20%' 
PRP PART_NAME 'CAPACITOR' 
TOP 0 4.2 2.855 180.0 N 1 115 1
TOP 1 4.134 2.855 180.0 N 2 343 2
#
# CMP 502
CMP 60 3.729 2.837 270.0 N C194 ??? ;0=1,1=0.057000
PRP REUSE_ID '5' 
PRP ALT_SYMBOLS '(SMC_0805R_H057)' 
PRP PARENT_PART_TYPE 'CAPACITOR' 
PRP PARENT_PPT 'CAPACITOR' 
PRP PARENT_PPT_PART 'CAPACITOR-G107-0F106-EM,10UF,20%' 
PRP PART_NAME 'CAPACITOR' 
TOP 0 3.729 2.804 270.0 N 14 4 1
TOP 1 3.729 2.87 270.0 N 2 344 2
#
# CMP 503
CMP 60 5.05 3.87 90.0 N C72 ??? ;0=1,1=0.057000
PRP ALT_SYMBOLS '(SMC_0805R_H057)' 
PRP PARENT_PART_TYPE 'CAPACITOR' 
PRP PARENT_PPT 'CAPACITOR' 
PRP PARENT_PPT_PART 'CAPACITOR-G107-0F106-EM,10UF,20%' 
PRP PART_NAME 'CAPACITOR' 
TOP 0 5.05 3.903 90.0 N 125 2 1
TOP 1 5.05 3.837 90.0 N 2 345 2
#
# CMP 504
CMP 60 3.732 2.985 90.0 N C185 ??? ;0=1,1=0.057000
PRP REUSE_ID '3' 
PRP ALT_SYMBOLS '(SMC_0805R_H057)' 
PRP PARENT_PART_TYPE 'CAPACITOR' 
PRP PARENT_PPT 'CAPACITOR' 
PRP PARENT_PPT_PART 'CAPACITOR-G107-0F106-EM,10UF,20%' 
PRP PART_NAME 'CAPACITOR' 
TOP 0 3.732 3.018 90.0 N 21 3 1
TOP 1 3.732 2.952 90.0 N 2 346 2
#
# CMP 505
CMP 60 3.288 4.202 180.0 N C50 ??? ;0=1,1=0.057000
PRP REUSE_ID '4' 
PRP ALT_SYMBOLS '(SMC_0805R_H057)' 
PRP PARENT_PART_TYPE 'CAPACITOR' 
PRP PARENT_PPT 'CAPACITOR' 
PRP PARENT_PPT_PART 'CAPACITOR-G107-0F106-EM,10UF,20%' 
PRP PART_NAME 'CAPACITOR' 
TOP 0 3.321 4.202 180.0 N 110 4 1
TOP 1 3.255 4.202 180.0 N 2 347 2
#
# CMP 506
CMP 60 4.621 3.927 180.0 N C79 ??? ;0=1,1=0.057000
PRP REUSE_ID '5' 
PRP ALT_SYMBOLS '(SMC_0805R_H057)' 
PRP PARENT_PART_TYPE 'CAPACITOR' 
PRP PARENT_PPT 'CAPACITOR' 
PRP PARENT_PPT_PART 'CAPACITOR-G107-0F106-EM,10UF,20%' 
PRP PART_NAME 'CAPACITOR' 
TOP 0 4.654 3.927 180.0 N 70 2 1
TOP 1 4.588 3.927 180.0 N 2 348 2
#
# CMP 507
CMP 60 5.047 2.534 0.0 N C186 ??? ;0=1,1=0.057000
PRP ALT_SYMBOLS '(SMC_0805R_H057)' 
PRP PARENT_PART_TYPE 'CAPACITOR' 
PRP PARENT_PPT 'CAPACITOR' 
PRP PARENT_PPT_PART 'CAPACITOR-G107-0F106-EM,10UF,20%' 
PRP PART_NAME 'CAPACITOR' 
TOP 0 5.014 2.534 0.0 N 22 4 1
TOP 1 5.08 2.534 0.0 N 2 349 2
#
# CMP 508
CMP 60 1.855 3.105 0.0 N C300 ??? ;0=1,1=0.057000
PRP ALT_SYMBOLS '(SMC_0805R_H057)' 
PRP PARENT_PART_TYPE 'CAPACITOR' 
PRP PARENT_PPT 'CAPACITOR' 
PRP PARENT_PPT_PART 'CAPACITOR-G107-0F106-EM,10UF,20%' 
PRP PART_NAME 'CAPACITOR' 
TOP 0 1.822 3.105 0.0 N 85 4 1
TOP 1 1.888 3.105 0.0 N 2 350 2
#
# CMP 509
CMP 60 5.195 2.521 180.0 N C195 ??? ;0=1,1=0.057000
PRP ALT_SYMBOLS '(SMC_0805R_H057)' 
PRP PARENT_PART_TYPE 'CAPACITOR' 
PRP PARENT_PPT 'CAPACITOR' 
PRP PARENT_PPT_PART 'CAPACITOR-G107-0F106-EM,10UF,20%' 
PRP PART_NAME 'CAPACITOR' 
TOP 0 5.228 2.521 180.0 N 16 6 1
TOP 1 5.162 2.521 180.0 N 2 351 2
#
# CMP 510
CMP 60 5.76 2.12 90.0 N C257 ??? ;0=1,1=0.057000
PRP ALT_SYMBOLS '(SMC_0805R_H057)' 
PRP PARENT_PART_TYPE 'CAPACITOR' 
PRP PARENT_PPT 'CAPACITOR' 
PRP PARENT_PPT_PART 'CAPACITOR-G107-0F106-EM,10UF,20%' 
PRP PART_NAME 'CAPACITOR' 
TOP 0 5.76 2.153 90.0 N 55 4 1
TOP 1 5.76 2.087 90.0 N 2 352 2
#
# CMP 511
CMP 60 6.225 2.00374 90.0 N C61 ??? ;0=1,1=0.057000
PRP ALT_SYMBOLS '(SMC_0805R_H057)' 
PRP PARENT_PART_TYPE 'CAPACITOR' 
PRP PARENT_PPT 'CAPACITOR' 
PRP PARENT_PPT_PART 'CAPACITOR-G107-0F106-EM,10UF,20%' 
PRP PART_NAME 'CAPACITOR' 
TOP 0 6.225 2.03674 90.0 N 121 0 1
TOP 1 6.225 1.97074 90.0 N 2 353 2
#
# CMP 512
CMP 61 4.055 1.05 270.0 N C253 ??? ;0=1,1=0.022000
PRP SIGNAL_MODEL 'DEFAULT_CAPACITOR_100000pF_1_2' 
PRP ALT_SYMBOLS '(SMC_0402R_C_H022,C0402_BGA,C0402-0P8MM-45DG,C0402-1MM-TRIANGLE-S0)' 
PRP PARENT_PART_TYPE 'CAPACITOR' 
PRP PARENT_PPT 'CAPACITOR' 
PRP PARENT_PPT_PART 'CAPACITOR-G105-0B104-CK,0.1UF,10%' 
PRP PART_NAME 'CAPACITOR' 
TOP 0 4.055 1.029 270.0 N 50 2 1
TOP 1 4.055 1.071 270.0 N 51 1 2
#
# CMP 513
CMP 61 4.01 1.05 270.0 N C254 ??? ;0=1,1=0.022000
PRP SIGNAL_MODEL 'DEFAULT_CAPACITOR_100000pF_1_2' 
PRP ALT_SYMBOLS '(SMC_0402R_C_H022,C0402_BGA,C0402-0P8MM-45DG,C0402-1MM-TRIANGLE-S0)' 
PRP PARENT_PART_TYPE 'CAPACITOR' 
PRP PARENT_PPT 'CAPACITOR' 
PRP PARENT_PPT_PART 'CAPACITOR-G105-0B104-CK,0.1UF,10%' 
PRP PART_NAME 'CAPACITOR' 
TOP 0 4.01 1.029 270.0 N 52 2 1
TOP 1 4.01 1.071 270.0 N 53 1 2
#
# CMP 514
CMP 61 3.79 0.97 180.0 N C247 ??? ;0=1,1=0.022000
PRP ALT_SYMBOLS '(SMC_0402R_C_H022,C0402_BGA,C0402-0P8MM-45DG,C0402-P8MM-S0,C0402-1MM-TRIANGLE-S0)' 
PRP PARENT_PART_TYPE 'CAPACITOR' 
PRP PARENT_PPT 'CAPACITOR' 
PRP PARENT_PPT_PART 'CAPACITOR-G105-0C106-BM,10UF,20%' 
PRP PART_NAME 'CAPACITOR' 
TOP 0 3.811 0.97 180.0 N 42 2 1
TOP 1 3.769 0.97 180.0 N 2 354 2
#
# CMP 515
CMP 61 3.575 1.6 270.0 N C148 ??? ;0=1,1=0.022000
PRP SIGNAL_MODEL 'DEFAULT_CAPACITOR_100000pF_1_2' 
PRP ALT_SYMBOLS '(SMC_0402R_C_H022,C0402_BGA,C0402-0P8MM-45DG,C0402-1MM-TRIANGLE-S0)' 
PRP PARENT_PART_TYPE 'CAPACITOR' 
PRP PARENT_PPT 'CAPACITOR' 
PRP PARENT_PPT_PART 'CAPACITOR-G105-0B104-CK,0.1UF,10%' 
PRP PART_NAME 'CAPACITOR' 
TOP 0 3.575 1.579 270.0 N 15 9 1
TOP 1 3.575 1.621 270.0 N 2 355 2
#
# CMP 516
CMP 61 2.9762 0.6678 0.0 N C37 ??? ;0=1,1=0.022000
PRP SIGNAL_MODEL 'DEFAULT_CAPACITOR_100000pF_1_2' 
PRP ALT_SYMBOLS '(SMC_0402R_C_H022,C0402_BGA,C0402-0P8MM-45DG,C0402-1MM-TRIANGLE-S0)' 
PRP PARENT_PART_TYPE 'CAPACITOR' 
PRP PARENT_PPT 'CAPACITOR' 
PRP PARENT_PPT_PART 'CAPACITOR-G105-0B104-CK,0.1UF,10%' 
PRP PART_NAME 'CAPACITOR' 
TOP 0 2.9552 0.6678 0.0 N 1 116 1
TOP 1 2.9972 0.6678 0.0 N 2 356 2
#
# CMP 517
CMP 61 2.15 0.615 270.0 N C288 ??? ;0=1,1=0.022000
PRP SIGNAL_MODEL 'DEFAULT_CAPACITOR_100000pF_1_2' 
PRP ALT_SYMBOLS '(SMC_0402R_C_H022,C0402-1MM-TRIANGLE-S0,C0402-P8MM-S0)' 
PRP PARENT_PART_TYPE 'CAPACITOR' 
PRP PARENT_PPT 'CAPACITOR' 
PRP PARENT_PPT_PART 'CAPACITOR-G105-0B104-EK,0.1UF,10%' 
PRP PART_NAME 'CAPACITOR' 
TOP 0 2.15 0.594 270.0 N 80 0 1
TOP 1 2.15 0.636 270.0 N 2 357 2
#
# CMP 518
CMP 61 2.105 0.615 270.0 N C287 ??? ;0=1,1=0.022000
PRP ALT_SYMBOLS '(SMC_0402R_C_H022,C0402_BGA,C0402-0P8MM-45DG,C0402-P8MM-S0,C0402-1MM-TRIANGLE-S0)' 
PRP PARENT_PART_TYPE 'CAPACITOR' 
PRP PARENT_PPT 'CAPACITOR' 
PRP PARENT_PPT_PART 'CAPACITOR-G105-0C106-BM,10UF,20%' 
PRP PART_NAME 'CAPACITOR' 
TOP 0 2.105 0.594 270.0 N 80 1 1
TOP 1 2.105 0.636 270.0 N 2 358 2
#
# CMP 519
CMP 61 3.89 0.97 0.0 N C249 ??? ;0=1,1=0.022000
PRP SIGNAL_MODEL 'DEFAULT_CAPACITOR_100000pF_1_2' 
PRP ALT_SYMBOLS '(SMC_0402R_C_H022,C0402-1MM-TRIANGLE-S0,C0402-P8MM-S0)' 
PRP PARENT_PART_TYPE 'CAPACITOR' 
PRP PARENT_PPT 'CAPACITOR' 
PRP PARENT_PPT_PART 'CAPACITOR-G105-0B104-EK,0.1UF,10%' 
PRP PART_NAME 'CAPACITOR' 
TOP 0 3.869 0.97 0.0 N 42 3 1
TOP 1 3.911 0.97 0.0 N 2 359 2
#
# CMP 520
CMP 61 3.705 2.405 90.0 N C250 ??? ;0=1,1=0.022000
PRP SIGNAL_MODEL 'DEFAULT_CAPACITOR_100000pF_1_2' 
PRP ALT_SYMBOLS '(SMC_0402R_C_H022,C0402-1MM-TRIANGLE-S0,C0402-P8MM-S0)' 
PRP PARENT_PART_TYPE 'CAPACITOR' 
PRP PARENT_PPT 'CAPACITOR' 
PRP PARENT_PPT_PART 'CAPACITOR-G105-0B104-EK,0.1UF,10%' 
PRP PART_NAME 'CAPACITOR' 
TOP 0 3.705 2.426 90.0 N 45 1 1
TOP 1 3.705 2.384 90.0 N 2 360 2
#
# CMP 521
CMP 61 1.51 3.185 270.0 N C309 ??? ;0=1,1=0.022000
PRP SIGNAL_MODEL 'DEFAULT_CAPACITOR_100000pF_1_2' 
PRP ALT_SYMBOLS '(SMC_0402R_C_H022,C0402-1MM-TRIANGLE-S0,C0402-P8MM-S0)' 
PRP PARENT_PART_TYPE 'CAPACITOR' 
PRP PARENT_PPT 'CAPACITOR' 
PRP PARENT_PPT_PART 'CAPACITOR-G105-0B104-EK,0.1UF,10%' 
PRP PART_NAME 'CAPACITOR' 
TOP 0 1.51 3.164 270.0 N 88 13 1
TOP 1 1.51 3.206 270.0 N 2 361 2
#
# CMP 522
CMP 61 4.53 3.27 0.0 N C97 ??? ;0=1,1=0.022000
PRP SIGNAL_MODEL 'DEFAULT_CAPACITOR_100000pF_1_2' 
PRP REUSE_ID '25' 
PRP ALT_SYMBOLS '(SMC_0402R_C_H022,C0402-1MM-TRIANGLE-S0,C0402-P8MM-S0)' 
PRP PARENT_PART_TYPE 'CAPACITOR' 
PRP PARENT_PPT 'CAPACITOR' 
PRP PARENT_PPT_PART 'CAPACITOR-G105-0B104-EK,0.1UF,10%' 
PRP PART_NAME 'CAPACITOR' 
TOP 0 4.509 3.27 0.0 N 1 117 1
TOP 1 4.551 3.27 0.0 N 2 362 2
#
# CMP 523
CMP 61 1.84 3.19 0.0 N C298 ??? ;0=1,1=0.022000
PRP SIGNAL_MODEL 'DEFAULT_CAPACITOR_100000pF_1_2' 
PRP ALT_SYMBOLS '(SMC_0402R_C_H022,C0402-1MM-TRIANGLE-S0,C0402-P8MM-S0)' 
PRP PARENT_PART_TYPE 'CAPACITOR' 
PRP PARENT_PPT 'CAPACITOR' 
PRP PARENT_PPT_PART 'CAPACITOR-G105-0B104-EK,0.1UF,10%' 
PRP PART_NAME 'CAPACITOR' 
TOP 0 1.819 3.19 0.0 N 77 4 1
TOP 1 1.861 3.19 0.0 N 2 363 2
#
# CMP 524
CMP 61 1.885 2.96 270.0 N C302 ??? ;0=1,1=0.022000
PRP SIGNAL_MODEL 'DEFAULT_CAPACITOR_100000pF_1_2' 
PRP ALT_SYMBOLS '(SMC_0402R_C_H022,C0402-1MM-TRIANGLE-S0,C0402-P8MM-S0)' 
PRP PARENT_PART_TYPE 'CAPACITOR' 
PRP PARENT_PPT 'CAPACITOR' 
PRP PARENT_PPT_PART 'CAPACITOR-G105-0B104-EK,0.1UF,10%' 
PRP PART_NAME 'CAPACITOR' 
TOP 0 1.885 2.939 270.0 N 86 2 1
TOP 1 1.885 2.981 270.0 N 2 364 2
#
# CMP 525
CMP 61 1.845 3.04 0.0 N C304 ??? ;0=1,1=0.022000
PRP SIGNAL_MODEL 'DEFAULT_CAPACITOR_100000pF_1_2' 
PRP ALT_SYMBOLS '(SMC_0402R_C_H022,C0402-1MM-TRIANGLE-S0,C0402-P8MM-S0)' 
PRP PARENT_PART_TYPE 'CAPACITOR' 
PRP PARENT_PPT 'CAPACITOR' 
PRP PARENT_PPT_PART 'CAPACITOR-G105-0B104-EK,0.1UF,10%' 
PRP PART_NAME 'CAPACITOR' 
TOP 0 1.824 3.04 0.0 N 85 5 1
TOP 1 1.866 3.04 0.0 N 2 365 2
#
# CMP 526
CMP 61 0.64 2.25 90.0 N C85 ??? ;0=1,1=0.022000
PRP SIGNAL_MODEL 'DEFAULT_CAPACITOR_100000pF_1_2' 
PRP REUSE_ID '2' 
PRP ALT_SYMBOLS '(SMC_0402R_C_H022,C0402_BGA,C0402-0P8MM-45DG,C0402-1MM-TRIANGLE-S0)' 
PRP PARENT_PART_TYPE 'CAPACITOR' 
PRP PARENT_PPT 'CAPACITOR' 
PRP PARENT_PPT_PART 'CAPACITOR-G105-0B104-CK,0.1UF,10%' 
PRP PART_NAME 'CAPACITOR' 
TOP 0 0.64 2.271 90.0 N 1 118 1
TOP 1 0.64 2.229 90.0 N 2 366 2
#
# CMP 527
CMP 61 0.606 1.66845 90.0 N C84 ??? ;0=1,1=0.022000
PRP SIGNAL_MODEL 'DEFAULT_CAPACITOR_100000pF_1_2' 
PRP ALT_SYMBOLS '(SMC_0402R_C_H022,C0402_BGA,C0402-0P8MM-45DG,C0402-1MM-TRIANGLE-S0)' 
PRP PARENT_PART_TYPE 'CAPACITOR' 
PRP PARENT_PPT 'CAPACITOR' 
PRP PARENT_PPT_PART 'CAPACITOR-G105-0B104-CK,0.1UF,10%' 
PRP PART_NAME 'CAPACITOR' 
TOP 0 0.606 1.68945 90.0 N 1 119 1
TOP 1 0.606 1.64745 90.0 N 2 367 2
#
# CMP 528
CMP 61 0.625 1.105 90.0 N C83 ??? ;0=1,1=0.022000
PRP SIGNAL_MODEL 'DEFAULT_CAPACITOR_100000pF_1_2' 
PRP REUSE_ID '10' 
PRP ALT_SYMBOLS '(SMC_0402R_C_H022,C0402_BGA,C0402-0P8MM-45DG,C0402-1MM-TRIANGLE-S0)' 
PRP PARENT_PART_TYPE 'CAPACITOR' 
PRP PARENT_PPT 'CAPACITOR' 
PRP PARENT_PPT_PART 'CAPACITOR-G105-0B104-CK,0.1UF,10%' 
PRP PART_NAME 'CAPACITOR' 
TOP 0 0.625 1.126 90.0 N 1 120 1
TOP 1 0.625 1.084 90.0 N 2 368 2
#
# CMP 529
CMP 61 5.741 3.567 0.0 N C3 ??? ;0=1,1=0.022000
PRP SIGNAL_MODEL 'DEFAULT_CAPACITOR_100000pF_1_2' 
PRP REUSE_ID '28' 
PRP ALT_SYMBOLS '(SMC_0402R_C_H022,C0402-1MM-TRIANGLE-S0,C0402-P8MM-S0)' 
PRP PARENT_PART_TYPE 'CAPACITOR' 
PRP PARENT_PPT 'CAPACITOR' 
PRP PARENT_PPT_PART 'CAPACITOR-G105-0B104-EK,0.1UF,10%' 
PRP PART_NAME 'CAPACITOR' 
TOP 0 5.72 3.567 0.0 N 83 4 1
TOP 1 5.762 3.567 0.0 N 2 369 2
#
# CMP 530
CMP 61 5.616 3.569 0.0 N C2 ??? ;0=1,1=0.022000
PRP SIGNAL_MODEL 'DEFAULT_CAPACITOR_100000pF_1_2' 
PRP REUSE_ID '27' 
PRP ALT_SYMBOLS '(SMC_0402R_C_H022,C0402-1MM-TRIANGLE-S0,C0402-P8MM-S0)' 
PRP PARENT_PART_TYPE 'CAPACITOR' 
PRP PARENT_PPT 'CAPACITOR' 
PRP PARENT_PPT_PART 'CAPACITOR-G105-0B104-EK,0.1UF,10%' 
PRP PART_NAME 'CAPACITOR' 
TOP 0 5.595 3.569 0.0 N 30 14 1
TOP 1 5.637 3.569 0.0 N 2 370 2
#
# CMP 531
CMP 61 5.741 3.807 0.0 N C5 ??? ;0=1,1=0.022000
PRP SIGNAL_MODEL 'DEFAULT_CAPACITOR_100000pF_1_2' 
PRP REUSE_ID '19' 
PRP ALT_SYMBOLS '(SMC_0402R_C_H022,C0402-1MM-TRIANGLE-S0,C0402-P8MM-S0)' 
PRP PARENT_PART_TYPE 'CAPACITOR' 
PRP PARENT_PPT 'CAPACITOR' 
PRP PARENT_PPT_PART 'CAPACITOR-G105-0B104-EK,0.1UF,10%' 
PRP PART_NAME 'CAPACITOR' 
TOP 0 5.72 3.807 0.0 N 113 1 1
TOP 1 5.762 3.807 0.0 N 2 371 2
#
# CMP 532
CMP 61 5.741 3.857 0.0 N C7 ??? ;0=1,1=0.022000
PRP SIGNAL_MODEL 'DEFAULT_CAPACITOR_100000pF_1_2' 
PRP REUSE_ID '13' 
PRP ALT_SYMBOLS '(SMC_0402R_C_H022,C0402-1MM-TRIANGLE-S0,C0402-P8MM-S0)' 
PRP PARENT_PART_TYPE 'CAPACITOR' 
PRP PARENT_PPT 'CAPACITOR' 
PRP PARENT_PPT_PART 'CAPACITOR-G105-0B104-EK,0.1UF,10%' 
PRP PART_NAME 'CAPACITOR' 
TOP 0 5.72 3.857 0.0 N 124 1 1
TOP 1 5.762 3.857 0.0 N 2 372 2
#
# CMP 533
CMP 61 0.92948 2.683 0.0 N C278 ??? ;0=1,1=0.022000
PRP SIGNAL_MODEL 'DEFAULT_CAPACITOR_100000pF_1_2' 
PRP ALT_SYMBOLS '(SMC_0402R_C_H022,C0402-1MM-TRIANGLE-S0,C0402-P8MM-S0)' 
PRP PARENT_PART_TYPE 'CAPACITOR' 
PRP PARENT_PPT 'CAPACITOR' 
PRP PARENT_PPT_PART 'CAPACITOR-G105-0B104-EK,0.1UF,10%' 
PRP PART_NAME 'CAPACITOR' 
TOP 0 0.90848 2.683 0.0 N 72 7 1
TOP 1 0.95048 2.683 0.0 N 2 373 2
#
# CMP 534
CMP 61 0.93 2.728 0.0 N C277 ??? ;0=1,1=0.022000
PRP ALT_SYMBOLS '(SMC_0402R_C_H022,C0402_BGA,C0402-0P8MM-45DG,C0402-P8MM-S0,C0402-1MM-TRIANGLE-S0)' 
PRP PARENT_PART_TYPE 'CAPACITOR' 
PRP PARENT_PPT 'CAPACITOR' 
PRP PARENT_PPT_PART 'CAPACITOR-G105-0C106-BM,10UF,20%' 
PRP PART_NAME 'CAPACITOR' 
TOP 0 0.909 2.728 0.0 N 72 8 1
TOP 1 0.951 2.728 0.0 N 2 374 2
#
# CMP 535
CMP 61 0.928 2.58048 180.0 N C276 ??? ;0=1,1=0.022000
PRP SIGNAL_MODEL 'DEFAULT_CAPACITOR_100000pF_1_2' 
PRP ALT_SYMBOLS '(SMC_0402R_C_H022,C0402-1MM-TRIANGLE-S0,C0402-P8MM-S0)' 
PRP PARENT_PART_TYPE 'CAPACITOR' 
PRP PARENT_PPT 'CAPACITOR' 
PRP PARENT_PPT_PART 'CAPACITOR-G105-0B104-EK,0.1UF,10%' 
PRP PART_NAME 'CAPACITOR' 
TOP 0 0.949 2.58048 180.0 N 16 7 1
TOP 1 0.907 2.58048 180.0 N 2 375 2
#
# CMP 536
CMP 61 1.1947 0.6136 0.0 N C225 ??? ;0=1,1=0.022000
PRP SIGNAL_MODEL 'DEFAULT_CAPACITOR_100000pF_1_2' 
PRP ALT_SYMBOLS '(SMC_0402R_C_H022,C0402-1MM-TRIANGLE-S0,C0402-P8MM-S0)' 
PRP PARENT_PART_TYPE 'CAPACITOR' 
PRP PARENT_PPT 'CAPACITOR' 
PRP PARENT_PPT_PART 'CAPACITOR-G105-0B104-EK,0.1UF,10%' 
PRP PART_NAME 'CAPACITOR' 
TOP 0 1.1737 0.6136 0.0 N 1 121 1
TOP 1 1.2157 0.6136 0.0 N 2 376 2
#
# CMP 537
CMP 61 0.715 2.423 270.0 N C312 ??? ;0=1,1=0.022000
PRP SIGNAL_MODEL 'DEFAULT_CAPACITOR_100000pF_1_2' 
PRP ALT_SYMBOLS '(SMC_0402R_C_H022,C0402_BGA,C0402-0P8MM-45DG,C0402-1MM-TRIANGLE-S0)' 
PRP PARENT_PART_TYPE 'CAPACITOR' 
PRP PARENT_PPT 'CAPACITOR' 
PRP PARENT_PPT_PART 'CAPACITOR-G105-0B104-CK,0.1UF,10%' 
PRP PART_NAME 'CAPACITOR' 
TOP 0 0.715 2.402 270.0 N 19 18 1
TOP 1 0.715 2.444 270.0 N 2 377 2
#
# CMP 538
CMP 61 0.714 2.273 90.0 N C313 ??? ;0=1,1=0.022000
PRP SIGNAL_MODEL 'DEFAULT_CAPACITOR_100000pF_1_2' 
PRP ALT_SYMBOLS '(SMC_0402R_C_H022,C0402_BGA,C0402-0P8MM-45DG,C0402-1MM-TRIANGLE-S0)' 
PRP PARENT_PART_TYPE 'CAPACITOR' 
PRP PARENT_PPT 'CAPACITOR' 
PRP PARENT_PPT_PART 'CAPACITOR-G105-0B104-CK,0.1UF,10%' 
PRP PART_NAME 'CAPACITOR' 
TOP 0 0.714 2.294 90.0 N 72 9 1
TOP 1 0.714 2.252 90.0 N 2 378 2
#
# CMP 539
CMP 61 1.671 4.091 0.0 N C33 ??? ;0=1,1=0.022000
PRP SIGNAL_MODEL 'DEFAULT_CAPACITOR_100000pF_1_2' 
PRP REUSE_ID '13' 
PRP ALT_SYMBOLS '(SMC_0402R_C_H022,C0402-1MM-TRIANGLE-S0,C0402-P8MM-S0)' 
PRP PARENT_PART_TYPE 'CAPACITOR' 
PRP PARENT_PPT 'CAPACITOR' 
PRP PARENT_PPT_PART 'CAPACITOR-G105-0B104-EK,0.1UF,10%' 
PRP PART_NAME 'CAPACITOR' 
TOP 0 1.65 4.091 0.0 N 84 5 1
TOP 1 1.692 4.091 0.0 N 2 379 2
#
# CMP 540
CMP 61 1.691 3.841 0.0 N C41 ??? ;0=1,1=0.022000
PRP SIGNAL_MODEL 'DEFAULT_CAPACITOR_100000pF_1_2' 
PRP REUSE_ID '15' 
PRP ALT_SYMBOLS '(SMC_0402R_C_H022,C0402-1MM-TRIANGLE-S0,C0402-P8MM-S0)' 
PRP PARENT_PART_TYPE 'CAPACITOR' 
PRP PARENT_PPT 'CAPACITOR' 
PRP PARENT_PPT_PART 'CAPACITOR-G105-0B104-EK,0.1UF,10%' 
PRP PART_NAME 'CAPACITOR' 
TOP 0 1.67 3.841 0.0 N 84 6 1
TOP 1 1.712 3.841 0.0 N 2 380 2
#
# CMP 541
CMP 61 1.456 3.946 180.0 N C29 ??? ;0=1,1=0.022000
PRP SIGNAL_MODEL 'DEFAULT_CAPACITOR_100000pF_1_2' 
PRP REUSE_ID '27' 
PRP ALT_SYMBOLS '(SMC_0402R_C_H022,C0402_BGA,C0402-0P8MM-45DG,C0402-1MM-TRIANGLE-S0)' 
PRP PARENT_PART_TYPE 'CAPACITOR' 
PRP PARENT_PPT 'CAPACITOR' 
PRP PARENT_PPT_PART 'CAPACITOR-G105-0B104-CK,0.1UF,10%' 
PRP PART_NAME 'CAPACITOR' 
TOP 0 1.477 3.946 180.0 N 82 1 1
TOP 1 1.435 3.946 180.0 N 2 381 2
#
# CMP 542
CMP 61 1.456 3.991 180.0 N C31 ??? ;0=1,1=0.022000
PRP REUSE_ID '28' 
PRP ALT_SYMBOLS '(SMC_0402R_C_H022)' 
PRP PARENT_PART_TYPE 'CAPACITOR' 
PRP PARENT_PPT 'CAPACITOR' 
PRP PARENT_PPT_PART 'CAPACITOR-G105-0B223-EK,0.022UF,10%' 
PRP PART_NAME 'CAPACITOR' 
TOP 0 1.477 3.991 180.0 N 89 1 1
TOP 1 1.435 3.991 180.0 N 90 3 2
#
# CMP 543
CMP 61 1.445 3.725 90.0 N C74 ??? ;0=1,1=0.022000
PRP SIGNAL_MODEL 'DEFAULT_CAPACITOR_100000pF_1_2' 
PRP REUSE_ID '29' 
PRP ALT_SYMBOLS '(SMC_0402R_C_H022,C0402-1MM-TRIANGLE-S0,C0402-P8MM-S0)' 
PRP PARENT_PART_TYPE 'CAPACITOR' 
PRP PARENT_PPT 'CAPACITOR' 
PRP PARENT_PPT_PART 'CAPACITOR-G105-0B104-EK,0.1UF,10%' 
PRP PART_NAME 'CAPACITOR' 
TOP 0 1.445 3.746 90.0 N 3 17 1
TOP 1 1.445 3.704 90.0 N 2 382 2
#
# CMP 544
CMP 61 1.548 0.6422 270.0 N C17 ??? ;0=1,1=0.022000
PRP SIGNAL_MODEL 'DEFAULT_CAPACITOR_100000pF_1_2' 
PRP ALT_SYMBOLS '(SMC_0402R_C_H022,C0402_BGA,C0402-0P8MM-45DG,C0402-1MM-TRIANGLE-S0)' 
PRP PARENT_PART_TYPE 'CAPACITOR' 
PRP PARENT_PPT 'CAPACITOR' 
PRP PARENT_PPT_PART 'CAPACITOR-G105-0B104-CK,0.1UF,10%' 
PRP PART_NAME 'CAPACITOR' 
TOP 0 1.548 0.6212 270.0 N 1 122 1
TOP 1 1.548 0.6632 270.0 N 2 383 2
#
# CMP 545
CMP 61 2.176 3.866 90.0 N C12 ??? ;0=1,1=0.022000
PRP SIGNAL_MODEL 'DEFAULT_CAPACITOR_100000pF_1_2' 
PRP REUSE_ID '5' 
PRP ALT_SYMBOLS '(SMC_0402R_C_H022,C0402_BGA,C0402-0P8MM-45DG,C0402-1MM-TRIANGLE-S0)' 
PRP PARENT_PART_TYPE 'CAPACITOR' 
PRP PARENT_PPT 'CAPACITOR' 
PRP PARENT_PPT_PART 'CAPACITOR-G105-0B104-CK,0.1UF,10%' 
PRP PART_NAME 'CAPACITOR' 
TOP 0 2.176 3.887 90.0 N 13 8 1
TOP 1 2.176 3.845 90.0 N 2 384 2
#
# CMP 546
CMP 61 2.218 2.952 270.0 N C306 ??? ;0=1,1=0.022000
PRP SIGNAL_MODEL 'DEFAULT_CAPACITOR_100000pF_1_2' 
PRP REUSE_ID '5' 
PRP ALT_SYMBOLS '(SMC_0402R_C_H022,C0402-1MM-TRIANGLE-S0,C0402-P8MM-S0)' 
PRP PARENT_PART_TYPE 'CAPACITOR' 
PRP PARENT_PPT 'CAPACITOR' 
PRP PARENT_PPT_PART 'CAPACITOR-G105-0B104-EK,0.1UF,10%' 
PRP PART_NAME 'CAPACITOR' 
TOP 0 2.218 2.931 270.0 N 2 385 1
TOP 1 2.218 2.973 270.0 N 1 123 2
#
# CMP 547
CMP 61 5.41 1.815 270.0 N C268 ??? ;0=1,1=0.022000
PRP SIGNAL_MODEL 'DEFAULT_CAPACITOR_100000pF_1_2' 
PRP ALT_SYMBOLS '(SMC_0402R_C_H022,C0402_BGA,C0402-0P8MM-45DG,C0402-1MM-TRIANGLE-S0)' 
PRP PARENT_PART_TYPE 'CAPACITOR' 
PRP PARENT_PPT 'CAPACITOR' 
PRP PARENT_PPT_PART 'CAPACITOR-G105-0B104-CK,0.1UF,10%' 
PRP PART_NAME 'CAPACITOR' 
TOP 0 5.41 1.794 270.0 N 15 10 1
TOP 1 5.41 1.836 270.0 N 2 386 2
#
# CMP 548
CMP 61 5.27 0.92 0.0 N C92 ??? ;0=1,1=0.022000
PRP SIGNAL_MODEL 'DEFAULT_CAPACITOR_100000pF_1_2' 
PRP ALT_SYMBOLS '(SMC_0402R_C_H022,C0402-1MM-TRIANGLE-S0,C0402-P8MM-S0)' 
PRP PARENT_PART_TYPE 'CAPACITOR' 
PRP PARENT_PPT 'CAPACITOR' 
PRP PARENT_PPT_PART 'CAPACITOR-G105-0B104-EK,0.1UF,10%' 
PRP PART_NAME 'CAPACITOR' 
TOP 0 5.249 0.92 0.0 N 1 124 1
TOP 1 5.291 0.92 0.0 N 2 387 2
#
# CMP 549
CMP 61 3.18 2.524 180.0 N C285 ??? ;0=1,1=0.022000
PRP SIGNAL_MODEL 'DEFAULT_CAPACITOR_100000pF_1_2' 
PRP ALT_SYMBOLS '(SMC_0402R_C_H022,C0402_BGA,C0402-0P8MM-45DG,C0402-1MM-TRIANGLE-S0)' 
PRP PARENT_PART_TYPE 'CAPACITOR' 
PRP PARENT_PPT 'CAPACITOR' 
PRP PARENT_PPT_PART 'CAPACITOR-G105-0B104-CK,0.1UF,10%' 
PRP PART_NAME 'CAPACITOR' 
TOP 0 3.201 2.524 180.0 N 78 1 1
TOP 1 3.159 2.524 180.0 N 2 388 2
#
# CMP 550
CMP 61 5.035 2.474 0.0 N C183 ??? ;0=1,1=0.022000
PRP SIGNAL_MODEL 'DEFAULT_CAPACITOR_100000pF_1_2' 
PRP ALT_SYMBOLS '(SMC_0402R_C_H022,C0402-1MM-TRIANGLE-S0,C0402-P8MM-S0)' 
PRP PARENT_PART_TYPE 'CAPACITOR' 
PRP PARENT_PPT 'CAPACITOR' 
PRP PARENT_PPT_PART 'CAPACITOR-G105-0B104-EK,0.1UF,10%' 
PRP PART_NAME 'CAPACITOR' 
TOP 0 5.014 2.474 0.0 N 19 19 1
TOP 1 5.056 2.474 0.0 N 2 389 2
#
# CMP 551
CMP 61 5.772 0.679 90.0 N C227 ??? ;0=1,1=0.022000
PRP SIGNAL_MODEL 'DEFAULT_CAPACITOR_100000pF_1_2' 
PRP REUSE_ID '4' 
PRP ALT_SYMBOLS '(SMC_0402R_C_H022,C0402-1MM-TRIANGLE-S0,C0402-P8MM-S0)' 
PRP PARENT_PART_TYPE 'CAPACITOR' 
PRP PARENT_PPT 'CAPACITOR' 
PRP PARENT_PPT_PART 'CAPACITOR-G105-0B104-EK,0.1UF,10%' 
PRP PART_NAME 'CAPACITOR' 
TOP 0 5.772 0.7 90.0 N 31 2 1
TOP 1 5.772 0.658 90.0 N 2 390 2
#
# CMP 552
CMP 61 4.414 1.052 270.0 N C251 ??? ;0=1,1=0.022000
PRP SIGNAL_MODEL 'DEFAULT_CAPACITOR_100000pF_1_2' 
PRP ALT_SYMBOLS '(SMC_0402R_C_H022,C0402_BGA,C0402-0P8MM-45DG,C0402-1MM-TRIANGLE-S0)' 
PRP PARENT_PART_TYPE 'CAPACITOR' 
PRP PARENT_PPT 'CAPACITOR' 
PRP PARENT_PPT_PART 'CAPACITOR-G105-0B104-CK,0.1UF,10%' 
PRP PART_NAME 'CAPACITOR' 
TOP 0 4.414 1.031 270.0 N 46 2 1
TOP 1 4.414 1.073 270.0 N 47 2 2
#
# CMP 553
CMP 61 4.369 1.052 270.0 N C252 ??? ;0=1,1=0.022000
PRP SIGNAL_MODEL 'DEFAULT_CAPACITOR_100000pF_1_2' 
PRP ALT_SYMBOLS '(SMC_0402R_C_H022,C0402_BGA,C0402-0P8MM-45DG,C0402-1MM-TRIANGLE-S0)' 
PRP PARENT_PART_TYPE 'CAPACITOR' 
PRP PARENT_PPT 'CAPACITOR' 
PRP PARENT_PPT_PART 'CAPACITOR-G105-0B104-CK,0.1UF,10%' 
PRP PART_NAME 'CAPACITOR' 
TOP 0 4.369 1.031 270.0 N 48 2 1
TOP 1 4.369 1.073 270.0 N 49 2 2
#
# CMP 554
CMP 61 5.548 0.792 0.0 N C242 ??? ;0=1,1=0.022000
PRP SIGNAL_MODEL 'DEFAULT_CAPACITOR_100000pF_1_2' 
PRP REUSE_ID '9' 
PRP ALT_SYMBOLS '(SMC_0402R_C_H022,C0402-1MM-TRIANGLE-S0,C0402-P8MM-S0)' 
PRP PARENT_PART_TYPE 'CAPACITOR' 
PRP PARENT_PPT 'CAPACITOR' 
PRP PARENT_PPT_PART 'CAPACITOR-G105-0B104-EK,0.1UF,10%' 
PRP PART_NAME 'CAPACITOR' 
TOP 0 5.527 0.792 0.0 N 9 21 1
TOP 1 5.569 0.792 0.0 N 2 391 2
#
# CMP 555
CMP 61 5.67 0.792 180.0 N C230 ??? ;0=1,1=0.022000
PRP SIGNAL_MODEL 'DEFAULT_CAPACITOR_100000pF_1_2' 
PRP REUSE_ID '11' 
PRP ALT_SYMBOLS '(SMC_0402R_C_H022,C0402-1MM-TRIANGLE-S0,C0402-P8MM-S0)' 
PRP PARENT_PART_TYPE 'CAPACITOR' 
PRP PARENT_PPT 'CAPACITOR' 
PRP PARENT_PPT_PART 'CAPACITOR-G105-0B104-EK,0.1UF,10%' 
PRP PART_NAME 'CAPACITOR' 
TOP 0 5.691 0.792 180.0 N 32 5 1
TOP 1 5.649 0.792 180.0 N 2 392 2
#
# CMP 556
CMP 61 5.64 0.965 90.0 N C226 ??? ;0=1,1=0.022000
PRP SIGNAL_MODEL 'DEFAULT_CAPACITOR_100000pF_1_2' 
PRP REUSE_ID '8' 
PRP ALT_SYMBOLS '(SMC_0402R_C_H022,C0402-1MM-TRIANGLE-S0,C0402-P8MM-S0)' 
PRP PARENT_PART_TYPE 'CAPACITOR' 
PRP PARENT_PPT 'CAPACITOR' 
PRP PARENT_PPT_PART 'CAPACITOR-G105-0B104-EK,0.1UF,10%' 
PRP PART_NAME 'CAPACITOR' 
TOP 0 5.64 0.986 90.0 N 19 20 1
TOP 1 5.64 0.944 90.0 N 2 393 2
#
# CMP 557
CMP 61 3.255 3.685 270.0 N C18 ??? ;0=1,1=0.022000
PRP SIGNAL_MODEL 'DEFAULT_CAPACITOR_100000pF_1_2' 
PRP REUSE_ID '2' 
PRP ALT_SYMBOLS '(SMC_0402R_C_H022,C0402_BGA,C0402-0P8MM-45DG,C0402-1MM-TRIANGLE-S0)' 
PRP PARENT_PART_TYPE 'CAPACITOR' 
PRP PARENT_PPT 'CAPACITOR' 
PRP PARENT_PPT_PART 'CAPACITOR-G105-0B104-CK,0.1UF,10%' 
PRP PART_NAME 'CAPACITOR' 
TOP 0 3.255 3.664 270.0 N 19 21 1
TOP 1 3.255 3.706 270.0 N 2 394 2
#
# CMP 558
CMP 61 3.328 3.887 180.0 N C52 ??? ;0=1,1=0.022000
PRP SIGNAL_MODEL 'DEFAULT_CAPACITOR_100000pF_1_2' 
PRP REUSE_ID '11' 
PRP ALT_SYMBOLS '(SMC_0402R_C_H022,C0402-1MM-TRIANGLE-S0,C0402-P8MM-S0)' 
PRP PARENT_PART_TYPE 'CAPACITOR' 
PRP PARENT_PPT 'CAPACITOR' 
PRP PARENT_PPT_PART 'CAPACITOR-G105-0B104-EK,0.1UF,10%' 
PRP PART_NAME 'CAPACITOR' 
TOP 0 3.349 3.887 180.0 N 110 5 1
TOP 1 3.307 3.887 180.0 N 2 395 2
#
# CMP 559
CMP 61 4.545 2.945 0.0 N C236 ??? ;0=1,1=0.022000
PRP SIGNAL_MODEL 'DEFAULT_CAPACITOR_100000pF_1_2' 
PRP ALT_SYMBOLS '(SMC_0402R_C_H022,C0402-1MM-TRIANGLE-S0,C0402-P8MM-S0)' 
PRP PARENT_PART_TYPE 'CAPACITOR' 
PRP PARENT_PPT 'CAPACITOR' 
PRP PARENT_PPT_PART 'CAPACITOR-G105-0B104-EK,0.1UF,10%' 
PRP PART_NAME 'CAPACITOR' 
TOP 0 4.524 2.945 0.0 N 38 1 1
TOP 1 4.566 2.945 0.0 N 2 396 2
#
# CMP 560
CMP 61 4.545 2.895 0.0 N C235 ??? ;0=1,1=0.022000
PRP SIGNAL_MODEL 'DEFAULT_CAPACITOR_100000pF_1_2' 
PRP ALT_SYMBOLS '(SMC_0402R_C_H022,C0402_BGA,C0402-0P8MM-45DG,C0402-1MM-TRIANGLE-S0)' 
PRP PARENT_PART_TYPE 'CAPACITOR' 
PRP PARENT_PPT 'CAPACITOR' 
PRP PARENT_PPT_PART 'CAPACITOR-G105-0B104-CK,0.1UF,10%' 
PRP PART_NAME 'CAPACITOR' 
TOP 0 4.524 2.895 0.0 N 19 22 1
TOP 1 4.566 2.895 0.0 N 2 397 2
#
# CMP 561
CMP 61 4.39 2.72 90.0 N C233 ??? ;0=1,1=0.022000
PRP SIGNAL_MODEL 'DEFAULT_CAPACITOR_100000pF_1_2' 
PRP ALT_SYMBOLS '(SMC_0402R_C_H022,C0402_BGA,C0402-0P8MM-45DG,C0402-1MM-TRIANGLE-S0)' 
PRP PARENT_PART_TYPE 'CAPACITOR' 
PRP PARENT_PPT 'CAPACITOR' 
PRP PARENT_PPT_PART 'CAPACITOR-G105-0B104-CK,0.1UF,10%' 
PRP PART_NAME 'CAPACITOR' 
TOP 0 4.39 2.741 90.0 N 19 23 1
TOP 1 4.39 2.699 90.0 N 2 398 2
#
# CMP 562
CMP 61 4.166 2.792 180.0 N C237 ??? ;0=1,1=0.022000
PRP SIGNAL_MODEL 'DEFAULT_CAPACITOR_100000pF_1_2' 
PRP ALT_SYMBOLS '(SMC_0402R_C_H022,C0402_BGA,C0402-0P8MM-45DG,C0402-1MM-TRIANGLE-S0)' 
PRP PARENT_PART_TYPE 'CAPACITOR' 
PRP PARENT_PPT 'CAPACITOR' 
PRP PARENT_PPT_PART 'CAPACITOR-G105-0B104-CK,0.1UF,10%' 
PRP PART_NAME 'CAPACITOR' 
TOP 0 4.187 2.792 180.0 N 1 125 1
TOP 1 4.145 2.792 180.0 N 2 399 2
#
# CMP 563
CMP 61 4.961 2.707 270.0 N C187 ??? ;0=1,1=0.022000
PRP SIGNAL_MODEL 'DEFAULT_CAPACITOR_100000pF_1_2' 
PRP ALT_SYMBOLS '(SMC_0402R_C_H022,C0402-1MM-TRIANGLE-S0,C0402-P8MM-S0)' 
PRP PARENT_PART_TYPE 'CAPACITOR' 
PRP PARENT_PPT 'CAPACITOR' 
PRP PARENT_PPT_PART 'CAPACITOR-G105-0B104-EK,0.1UF,10%' 
PRP PART_NAME 'CAPACITOR' 
TOP 0 4.961 2.686 270.0 N 23 3 1
TOP 1 4.961 2.728 270.0 N 2 400 2
#
# CMP 564
CMP 61 5.11 3.775 180.0 N C272 ??? ;0=1,1=0.022000
PRP SIGNAL_MODEL 'DEFAULT_CAPACITOR_100000pF_1_2' 
PRP ALT_SYMBOLS '(SMC_0402R_C_H022,C0402-1MM-TRIANGLE-S0,C0402-P8MM-S0)' 
PRP PARENT_PART_TYPE 'CAPACITOR' 
PRP PARENT_PPT 'CAPACITOR' 
PRP PARENT_PPT_PART 'CAPACITOR-G105-0B104-EK,0.1UF,10%' 
PRP PART_NAME 'CAPACITOR' 
TOP 0 5.131 3.775 180.0 N 13 9 1
TOP 1 5.089 3.775 180.0 N 2 401 2
#
# CMP 565
CMP 61 4.375 3.965 0.0 N C314 ??? ;0=1,1=0.022000
PRP ALT_SYMBOLS '(SMC_0402R_C_H022,C0402_BGA,C0402-0P8MM-45DG,C0402-P8MM-S0,C0402-1MM-TRIANGLE-S0)' 
PRP PARENT_PART_TYPE 'CAPACITOR' 
PRP PARENT_PPT 'CAPACITOR' 
PRP PARENT_PPT_PART 'CAPACITOR-G105-0C106-BM,10UF,20%' 
PRP PART_NAME 'CAPACITOR' 
TOP 0 4.354 3.965 0.0 N 1 126 1
TOP 1 4.396 3.965 0.0 N 2 402 2
#
# CMP 566
CMP 61 2.916 3.206 180.0 N C38 ??? ;0=1,1=0.022000
PRP SIGNAL_MODEL 'DEFAULT_CAPACITOR_100000pF_1_2' 
PRP ALT_SYMBOLS '(SMC_0402R_C_H022,C0402_BGA,C0402-0P8MM-45DG,C0402-1MM-TRIANGLE-S0)' 
PRP PARENT_PART_TYPE 'CAPACITOR' 
PRP PARENT_PPT 'CAPACITOR' 
PRP PARENT_PPT_PART 'CAPACITOR-G105-0B104-CK,0.1UF,10%' 
PRP PART_NAME 'CAPACITOR' 
TOP 0 2.937 3.206 180.0 N 102 0 1
TOP 1 2.895 3.206 180.0 N 2 403 2
#
# CMP 567
CMP 61 3.797 2.87 270.0 N C196 ??? ;0=1,1=0.022000
PRP SIGNAL_MODEL 'DEFAULT_CAPACITOR_100000pF_1_2' 
PRP REUSE_ID '4' 
PRP ALT_SYMBOLS '(SMC_0402R_C_H022,C0402-1MM-TRIANGLE-S0,C0402-P8MM-S0)' 
PRP PARENT_PART_TYPE 'CAPACITOR' 
PRP PARENT_PPT 'CAPACITOR' 
PRP PARENT_PPT_PART 'CAPACITOR-G105-0B104-EK,0.1UF,10%' 
PRP PART_NAME 'CAPACITOR' 
TOP 0 3.797 2.849 270.0 N 14 5 1
TOP 1 3.797 2.891 270.0 N 2 404 2
#
# CMP 568
CMP 61 3.797 2.99 90.0 N C188 ??? ;0=1,1=0.022000
PRP SIGNAL_MODEL 'DEFAULT_CAPACITOR_100000pF_1_2' 
PRP REUSE_ID '19' 
PRP ALT_SYMBOLS '(SMC_0402R_C_H022,C0402-1MM-TRIANGLE-S0,C0402-P8MM-S0)' 
PRP PARENT_PART_TYPE 'CAPACITOR' 
PRP PARENT_PPT 'CAPACITOR' 
PRP PARENT_PPT_PART 'CAPACITOR-G105-0B104-EK,0.1UF,10%' 
PRP PART_NAME 'CAPACITOR' 
TOP 0 3.797 3.011 90.0 N 21 4 1
TOP 1 3.797 2.969 90.0 N 2 405 2
#
# CMP 569
CMP 61 3.912 3.092 0.0 N C184 ??? ;0=1,1=0.022000
PRP SIGNAL_MODEL 'DEFAULT_CAPACITOR_100000pF_1_2' 
PRP REUSE_ID '15' 
PRP ALT_SYMBOLS '(SMC_0402R_C_H022,C0402-1MM-TRIANGLE-S0,C0402-P8MM-S0)' 
PRP PARENT_PART_TYPE 'CAPACITOR' 
PRP PARENT_PPT 'CAPACITOR' 
PRP PARENT_PPT_PART 'CAPACITOR-G105-0B104-EK,0.1UF,10%' 
PRP PART_NAME 'CAPACITOR' 
TOP 0 3.891 3.092 0.0 N 20 2 1
TOP 1 3.933 3.092 0.0 N 2 406 2
#
# CMP 570
CMP 61 3.573 4.197 0.0 N C76 ??? ;0=1,1=0.022000
PRP SIGNAL_MODEL 'DEFAULT_CAPACITOR_100000pF_1_2' 
PRP REUSE_ID '9' 
PRP ALT_SYMBOLS '(SMC_0402R_C_H022,C0402-1MM-TRIANGLE-S0,C0402-P8MM-S0)' 
PRP PARENT_PART_TYPE 'CAPACITOR' 
PRP PARENT_PPT 'CAPACITOR' 
PRP PARENT_PPT_PART 'CAPACITOR-G105-0B104-EK,0.1UF,10%' 
PRP PART_NAME 'CAPACITOR' 
TOP 0 3.552 4.197 0.0 N 3 18 1
TOP 1 3.594 4.197 0.0 N 2 407 2
#
# CMP 571
CMP 61 3.543 3.987 0.0 N C49 ??? ;0=1,1=0.022000
PRP REUSE_ID '30' 
PRP ALT_SYMBOLS '(SMC_0402R_C_H022)' 
PRP PARENT_PART_TYPE 'CAPACITOR' 
PRP PARENT_PPT 'CAPACITOR' 
PRP PARENT_PPT_PART 'CAPACITOR-G105-0B223-EK,0.022UF,10%' 
PRP PART_NAME 'CAPACITOR' 
TOP 0 3.522 3.987 0.0 N 111 1 1
TOP 1 3.564 3.987 0.0 N 112 4 2
#
# CMP 572
CMP 61 3.543 4.032 0.0 N C46 ??? ;0=1,1=0.022000
PRP SIGNAL_MODEL 'DEFAULT_CAPACITOR_100000pF_1_2' 
PRP REUSE_ID '17' 
PRP ALT_SYMBOLS '(SMC_0402R_C_H022,C0402_BGA,C0402-0P8MM-45DG,C0402-1MM-TRIANGLE-S0)' 
PRP PARENT_PART_TYPE 'CAPACITOR' 
PRP PARENT_PPT 'CAPACITOR' 
PRP PARENT_PPT_PART 'CAPACITOR-G105-0B104-CK,0.1UF,10%' 
PRP PART_NAME 'CAPACITOR' 
TOP 0 3.522 4.032 0.0 N 79 3 1
TOP 1 3.564 4.032 0.0 N 2 408 2
#
# CMP 573
CMP 61 3.662 2.997 90.0 N C182 ??? ;0=1,1=0.022000
PRP SIGNAL_MODEL 'DEFAULT_CAPACITOR_100000pF_1_2' 
PRP REUSE_ID '11' 
PRP ALT_SYMBOLS '(SMC_0402R_C_H022,C0402-1MM-TRIANGLE-S0,C0402-P8MM-S0)' 
PRP PARENT_PART_TYPE 'CAPACITOR' 
PRP PARENT_PPT 'CAPACITOR' 
PRP PARENT_PPT_PART 'CAPACITOR-G105-0B104-EK,0.1UF,10%' 
PRP PART_NAME 'CAPACITOR' 
TOP 0 3.662 3.018 90.0 N 19 24 1
TOP 1 3.662 2.976 90.0 N 2 409 2
#
# CMP 574
CMP 61 3.582 2.877 270.0 N C199 ??? ;0=1,1=0.022000
PRP SIGNAL_MODEL 'DEFAULT_CAPACITOR_100000pF_1_2' 
PRP ALT_SYMBOLS '(SMC_0402R_C_H022,C0402_BGA,C0402-0P8MM-45DG,C0402-1MM-TRIANGLE-S0)' 
PRP PARENT_PART_TYPE 'CAPACITOR' 
PRP PARENT_PPT 'CAPACITOR' 
PRP PARENT_PPT_PART 'CAPACITOR-G105-0B104-CK,0.1UF,10%' 
PRP PART_NAME 'CAPACITOR' 
TOP 0 3.582 2.856 270.0 N 1 127 1
TOP 1 3.582 2.898 270.0 N 2 410 2
#
# CMP 575
CMP 61 3.308 4.137 180.0 N C53 ??? ;0=1,1=0.022000
PRP SIGNAL_MODEL 'DEFAULT_CAPACITOR_100000pF_1_2' 
PRP REUSE_ID '23' 
PRP ALT_SYMBOLS '(SMC_0402R_C_H022,C0402-1MM-TRIANGLE-S0,C0402-P8MM-S0)' 
PRP PARENT_PART_TYPE 'CAPACITOR' 
PRP PARENT_PPT 'CAPACITOR' 
PRP PARENT_PPT_PART 'CAPACITOR-G105-0B104-EK,0.1UF,10%' 
PRP PART_NAME 'CAPACITOR' 
TOP 0 3.329 4.137 180.0 N 110 6 1
TOP 1 3.287 4.137 180.0 N 2 411 2
#
# CMP 576
CMP 61 4.53 3.87 270.0 N C81 ??? ;0=1,1=0.022000
PRP SIGNAL_MODEL 'DEFAULT_CAPACITOR_100000pF_1_2' 
PRP REUSE_ID '1' 
PRP ALT_SYMBOLS '(SMC_0402R_C_H022,C0402_BGA,C0402-0P8MM-45DG,C0402-1MM-TRIANGLE-S0)' 
PRP PARENT_PART_TYPE 'CAPACITOR' 
PRP PARENT_PPT 'CAPACITOR' 
PRP PARENT_PPT_PART 'CAPACITOR-G105-0B104-CK,0.1UF,10%' 
PRP PART_NAME 'CAPACITOR' 
TOP 0 4.53 3.849 270.0 N 1 128 1
TOP 1 4.53 3.891 270.0 N 2 412 2
#
# CMP 577
CMP 61 5.183 2.592 180.0 N C197 ??? ;0=1,1=0.022000
PRP SIGNAL_MODEL 'DEFAULT_CAPACITOR_100000pF_1_2' 
PRP ALT_SYMBOLS '(SMC_0402R_C_H022,C0402-1MM-TRIANGLE-S0,C0402-P8MM-S0)' 
PRP PARENT_PART_TYPE 'CAPACITOR' 
PRP PARENT_PPT 'CAPACITOR' 
PRP PARENT_PPT_PART 'CAPACITOR-G105-0B104-EK,0.1UF,10%' 
PRP PART_NAME 'CAPACITOR' 
TOP 0 5.204 2.592 180.0 N 16 8 1
TOP 1 5.162 2.592 180.0 N 2 413 2
#
# CMP 578
CMP 61 5.063 2.597 0.0 N C189 ??? ;0=1,1=0.022000
PRP SIGNAL_MODEL 'DEFAULT_CAPACITOR_100000pF_1_2' 
PRP ALT_SYMBOLS '(SMC_0402R_C_H022,C0402-1MM-TRIANGLE-S0,C0402-P8MM-S0)' 
PRP PARENT_PART_TYPE 'CAPACITOR' 
PRP PARENT_PPT 'CAPACITOR' 
PRP PARENT_PPT_PART 'CAPACITOR-G105-0B104-EK,0.1UF,10%' 
PRP PART_NAME 'CAPACITOR' 
TOP 0 5.042 2.597 0.0 N 22 5 1
TOP 1 5.084 2.597 0.0 N 2 414 2
#
# CMP 579
CMP 61 5.6 2.345 270.0 N C259 ??? ;0=1,1=0.022000
PRP ALT_SYMBOLS '(SMC_0402R_C_H022)' 
PRP PARENT_PART_TYPE 'CAPACITOR' 
PRP PARENT_PPT 'CAPACITOR' 
PRP PARENT_PPT_PART 'CAPACITOR-G105-0B223-EK,0.022UF,10%' 
PRP PART_NAME 'CAPACITOR' 
TOP 0 5.6 2.324 270.0 N 57 1 1
TOP 1 5.6 2.366 270.0 N 58 3 2
#
# CMP 580
CMP 61 5.555 2.345 270.0 N C256 ??? ;0=1,1=0.022000
PRP SIGNAL_MODEL 'DEFAULT_CAPACITOR_100000pF_1_2' 
PRP ALT_SYMBOLS '(SMC_0402R_C_H022,C0402_BGA,C0402-0P8MM-45DG,C0402-1MM-TRIANGLE-S0)' 
PRP PARENT_PART_TYPE 'CAPACITOR' 
PRP PARENT_PPT 'CAPACITOR' 
PRP PARENT_PPT_PART 'CAPACITOR-G105-0B104-CK,0.1UF,10%' 
PRP PART_NAME 'CAPACITOR' 
TOP 0 5.555 2.324 270.0 N 54 1 1
TOP 1 5.555 2.366 270.0 N 2 415 2
#
# CMP 581
CMP 61 5.7 2.13 90.0 N C262 ??? ;0=1,1=0.022000
PRP SIGNAL_MODEL 'DEFAULT_CAPACITOR_100000pF_1_2' 
PRP ALT_SYMBOLS '(SMC_0402R_C_H022,C0402-1MM-TRIANGLE-S0,C0402-P8MM-S0)' 
PRP PARENT_PART_TYPE 'CAPACITOR' 
PRP PARENT_PPT 'CAPACITOR' 
PRP PARENT_PPT_PART 'CAPACITOR-G105-0B104-EK,0.1UF,10%' 
PRP PART_NAME 'CAPACITOR' 
TOP 0 5.7 2.151 90.0 N 55 5 1
TOP 1 5.7 2.109 90.0 N 2 416 2
#
# CMP 582
CMP 61 4.405 3.79 0.0 N C89 ??? ;0=1,1=0.022000
PRP SIGNAL_MODEL 'DEFAULT_CAPACITOR_100000pF_1_2' 
PRP ALT_SYMBOLS '(SMC_0402R_C_H022,C0402-1MM-TRIANGLE-S0,C0402-P8MM-S0)' 
PRP PARENT_PART_TYPE 'CAPACITOR' 
PRP PARENT_PPT 'CAPACITOR' 
PRP PARENT_PPT_PART 'CAPACITOR-G105-0B104-EK,0.1UF,10%' 
PRP PART_NAME 'CAPACITOR' 
TOP 0 4.384 3.79 0.0 N 1 129 1
TOP 1 4.426 3.79 0.0 N 2 417 2
#
# CMP 583
CMP 61 5.331 2.259 90.0 N C255 ??? ;0=1,1=0.022000
PRP SIGNAL_MODEL 'DEFAULT_CAPACITOR_100000pF_1_2' 
PRP ALT_SYMBOLS '(SMC_0402R_C_H022,C0402-1MM-TRIANGLE-S0,C0402-P8MM-S0)' 
PRP PARENT_PART_TYPE 'CAPACITOR' 
PRP PARENT_PPT 'CAPACITOR' 
PRP PARENT_PPT_PART 'CAPACITOR-G105-0B104-EK,0.1UF,10%' 
PRP PART_NAME 'CAPACITOR' 
TOP 0 5.331 2.28 90.0 N 3 19 1
TOP 1 5.331 2.238 90.0 N 2 418 2
#
# CMP 584
CMP 61 5.45 2.11 90.0 N C261 ??? ;0=1,1=0.022000
PRP SIGNAL_MODEL 'DEFAULT_CAPACITOR_100000pF_1_2' 
PRP ALT_SYMBOLS '(SMC_0402R_C_H022,C0402-1MM-TRIANGLE-S0,C0402-P8MM-S0)' 
PRP PARENT_PART_TYPE 'CAPACITOR' 
PRP PARENT_PPT 'CAPACITOR' 
PRP PARENT_PPT_PART 'CAPACITOR-G105-0B104-EK,0.1UF,10%' 
PRP PART_NAME 'CAPACITOR' 
TOP 0 5.45 2.131 90.0 N 55 6 1
TOP 1 5.45 2.089 90.0 N 2 419 2
#
# CMP 585
CMP 61 6.4 1.135 180.0 N C305 ??? ;0=1,1=0.022000
PRP SIGNAL_MODEL 'DEFAULT_CAPACITOR_100000pF_1_2' 
PRP REUSE_ID '10' 
PRP ALT_SYMBOLS '(SMC_0402R_C_H022,C0402-1MM-TRIANGLE-S0,C0402-P8MM-S0)' 
PRP PARENT_PART_TYPE 'CAPACITOR' 
PRP PARENT_PPT 'CAPACITOR' 
PRP PARENT_PPT_PART 'CAPACITOR-G105-0B104-EK,0.1UF,10%' 
PRP PART_NAME 'CAPACITOR' 
TOP 0 6.421 1.135 180.0 N 2 420 1
TOP 1 6.379 1.135 180.0 N 1 130 2
#
# CMP 586
CMP 61 6.289 1.99174 90.0 N C63 ??? ;0=1,1=0.022000
PRP SIGNAL_MODEL 'DEFAULT_CAPACITOR_100000pF_1_2' 
PRP ALT_SYMBOLS '(SMC_0402R_C_H022,C0402-1MM-TRIANGLE-S0,C0402-P8MM-S0)' 
PRP PARENT_PART_TYPE 'CAPACITOR' 
PRP PARENT_PPT 'CAPACITOR' 
PRP PARENT_PPT_PART 'CAPACITOR-G105-0B104-EK,0.1UF,10%' 
PRP PART_NAME 'CAPACITOR' 
TOP 0 6.289 2.01274 90.0 N 121 1 1
TOP 1 6.289 1.97074 90.0 N 2 421 2
#
# CMP 587
CMP 61 6.141 2.299 90.0 N C40 ??? ;0=1,1=0.022000
PRP SIGNAL_MODEL 'DEFAULT_CAPACITOR_100000pF_1_2' 
PRP ALT_SYMBOLS '(SMC_0402R_C_H022,C0402-1MM-TRIANGLE-S0,C0402-P8MM-S0)' 
PRP PARENT_PART_TYPE 'CAPACITOR' 
PRP PARENT_PPT 'CAPACITOR' 
PRP PARENT_PPT_PART 'CAPACITOR-G105-0B104-EK,0.1UF,10%' 
PRP PART_NAME 'CAPACITOR' 
TOP 0 6.141 2.32 90.0 N 1 131 1
TOP 1 6.141 2.278 90.0 N 2 422 2
#
# CMP 588
CMP 61 6.05 2.225 0.0 N C274 ??? ;0=1,1=0.022000
PRP ALT_SYMBOLS '(SMC_0402R_C_H022,C0402_BGA,C0402-0P8MM-45DG,C0402-P8MM-S0,C0402-1MM-TRIANGLE-S0)' 
PRP PARENT_PART_TYPE 'CAPACITOR' 
PRP PARENT_PPT 'CAPACITOR' 
PRP PARENT_PPT_PART 'CAPACITOR-G105-0C106-BM,10UF,20%' 
PRP PART_NAME 'CAPACITOR' 
TOP 0 6.029 2.225 0.0 N 71 2 1
TOP 1 6.071 2.225 0.0 N 2 423 2
#
# CMP 589
CMP 61 6.05 2.27 0.0 N C275 ??? ;0=1,1=0.022000
PRP SIGNAL_MODEL 'DEFAULT_CAPACITOR_100000pF_1_2' 
PRP ALT_SYMBOLS '(SMC_0402R_C_H022,C0402-1MM-TRIANGLE-S0,C0402-P8MM-S0)' 
PRP PARENT_PART_TYPE 'CAPACITOR' 
PRP PARENT_PPT 'CAPACITOR' 
PRP PARENT_PPT_PART 'CAPACITOR-G105-0B104-EK,0.1UF,10%' 
PRP PART_NAME 'CAPACITOR' 
TOP 0 6.029 2.27 0.0 N 71 3 1
TOP 1 6.071 2.27 0.0 N 2 424 2
#
# CMP 590
CMP 61 3.38484 2.532 270.0 N C280 ??? ;0=1,1=0.022000
PRP ALT_SYMBOLS '(SMC_0402R_C_H022,C0402_BGA,C0402-0P8MM-45DG,C0402-P8MM-S0,C0402-1MM-TRIANGLE-S0)' 
PRP PARENT_PART_TYPE 'CAPACITOR' 
PRP PARENT_PPT 'CAPACITOR' 
PRP PARENT_PPT_PART 'CAPACITOR-G105-0C106-BM,10UF,20%' 
PRP PART_NAME 'CAPACITOR' 
TOP 0 3.38484 2.511 270.0 N 75 3 1
TOP 1 3.38484 2.553 270.0 N 2 425 2
#
# CMP 591
CMP 61 3.435 2.532 270.0 N C281 ??? ;0=1,1=0.022000
PRP SIGNAL_MODEL 'DEFAULT_CAPACITOR_100000pF_1_2' 
PRP ALT_SYMBOLS '(SMC_0402R_C_H022,C0402-1MM-TRIANGLE-S0,C0402-P8MM-S0)' 
PRP PARENT_PART_TYPE 'CAPACITOR' 
PRP PARENT_PPT 'CAPACITOR' 
PRP PARENT_PPT_PART 'CAPACITOR-G105-0B104-EK,0.1UF,10%' 
PRP PART_NAME 'CAPACITOR' 
TOP 0 3.435 2.511 270.0 N 75 4 1
TOP 1 3.435 2.553 270.0 N 2 426 2
#
# CMP 592
CMP 61 3.546 2.534 90.0 N C279 ??? ;0=1,1=0.022000
PRP SIGNAL_MODEL 'DEFAULT_CAPACITOR_100000pF_1_2' 
PRP ALT_SYMBOLS '(SMC_0402R_C_H022,C0402-1MM-TRIANGLE-S0,C0402-P8MM-S0)' 
PRP PARENT_PART_TYPE 'CAPACITOR' 
PRP PARENT_PPT 'CAPACITOR' 
PRP PARENT_PPT_PART 'CAPACITOR-G105-0B104-EK,0.1UF,10%' 
PRP PART_NAME 'CAPACITOR' 
TOP 0 3.546 2.555 90.0 N 1 132 1
TOP 1 3.546 2.513 90.0 N 2 427 2
#
# CMP 593
CMP 62 0.804 2.091 180.0 N J18 ??? ;0=1,1=0.059060
PRP ALT_SYMBOLS '(S_M_H_3P_S_P058)' 
PRP PARENT_PART_TYPE 'CONN_HDR_1X3_M_S_SMT' 
PRP PARENT_PPT 'CONN_HDR_1X3_M_S_SMT' 
PRP PARENT_PPT_PART 'CONN_HDR_1X3_M_S_SMT-G205-10020-01' 
PRP PART_NAME 'CONN_HDR_1X3_M_S_SMT' 
TOP 0 0.86207 2.091 180.0 N 2 428 1
TOP 1 0.804 2.15104 180.0 N 213 0 2
TOP 2 0.74593 2.091 180.0 N 2 429 3
#
# CMP 594
CMP 63 0.235 1 270.0 N CR5 ??? ;0=1,1=0.047000
PRP REUSE_ID '4' 
PRP ALT_SYMBOLS '(SOT143)' 
PRP PARENT_PART_TYPE 'DIODE_4_V1' 
PRP PARENT_PPT 'DIODE_4_V1' 
PRP PARENT_PPT_PART 'DIODE_4_V1-G122-10123-01' 
PRP PART_NAME 'DIODE_4_V1' 
TOP 0 0.2055 0.9565 270.0 N 2 430 1
TOP 1 0.2725 0.9565 270.0 N 137 1 2
TOP 2 0.2725 1.0435 270.0 N 138 2 3
TOP 3 0.1975 1.0435 270.0 N 0 206 4
#
# CMP 595
CMP 63 0.235 2.14 270.0 N CR4 ??? ;0=1,1=0.047000
PRP HARD_LOCATION 'YES' 
PRP ALT_SYMBOLS '(SOT143)' 
PRP PARENT_PART_TYPE 'DIODE_4_V1' 
PRP PARENT_PPT 'DIODE_4_V1' 
PRP PARENT_PPT_PART 'DIODE_4_V1-G122-10123-01' 
PRP PART_NAME 'DIODE_4_V1' 
TOP 0 0.2055 2.0965 270.0 N 2 431 1
TOP 1 0.2725 2.0965 270.0 N 135 2 2
TOP 2 0.2725 2.1835 270.0 N 136 2 3
TOP 3 0.1975 2.1835 270.0 N 0 207 4
#
# CMP 596
CMP 64 1.255 3.885 180.0 N Y2 ??? ;0=1,1=0.031500
PRP ALT_SYMBOLS '(SMC_Y4_126X098_V5_H032)' 
PRP PARENT_PART_TYPE 'XTAL_4' 
PRP PARENT_PPT 'XTAL_4' 
PRP PARENT_PPT_PART 'XTAL_4-G131-10038-02' 
PRP PART_NAME 'XTAL_4' 
TOP 0 1.29831 3.91846 180.0 N 129 3 1
TOP 1 1.21169 3.91846 180.0 N 2 432 2
TOP 2 1.21169 3.85154 180.0 N 130 3 3
TOP 3 1.29831 3.85154 180.0 N 2 433 4
#
# CMP 597
CMP 65 2.801 0.605 0.0 N U3 ??? ;0=1,1=0.043300
PRP HARD_LOCATION 'YES' 
PRP ALT_SYMBOLS '(SC70_5V1)' 
PRP PARENT_PART_TYPE '74LVC1G07_SC70_5' 
PRP PARENT_PPT '74LVC1G07_SC70_5' 
PRP PARENT_PPT_PART '74LVC1G07_SC70_5-G220-10017-01' 
PRP PART_NAME '74LVC1G07_SC70_5' 
TOP 0 2.754 0.63059 0.0 N 0 208 1
TOP 1 2.754 0.605 0.0 N 184 2 2
TOP 2 2.754 0.57941 0.0 N 2 434 3
TOP 3 2.848 0.57941 0.0 N 423 2 4
TOP 4 2.848 0.63059 0.0 N 1 133 5
#
# CMP 598
CMP 66 3.695 2.57 90.0 N U34 ??? ;0=1,1=0.057000
PRP ALT_SYMBOLS '(SOT23_6)' 
PRP PARENT_PART_TYPE 'TPS3808G18DBVR_SOT23_6' 
PRP PARENT_PPT 'TPS3808G18DBVR_SOT23_6' 
PRP PARENT_PPT_PART 'TPS3808G18DBVR_SOT23_6-G222-00082-01' 
PRP PART_NAME 'TPS3808G18DBVR_SOT23_6' 
TOP 0 3.7324 2.6265 90.0 N 303 2 1
TOP 1 3.695 2.6265 90.0 N 2 435 2
TOP 2 3.6576 2.6265 90.0 N 518 2 3
TOP 3 3.6576 2.5135 90.0 N 45 2 4
TOP 4 3.695 2.5135 90.0 N 1 134 5
TOP 5 3.7324 2.5135 90.0 N 1 135 6
#
# CMP 599
CMP 66 0.72 3.45 270.0 N U17 ??? ;0=1,1=0.057000
PRP ALT_SYMBOLS '(SOT23_6)' 
PRP PARENT_PART_TYPE 'CL1001485A' 
PRP PARENT_PPT 'CL1001485A' 
PRP PARENT_PPT_PART 'CL1001485A-G122-00019-01' 
PRP PART_NAME 'CL1001485A' 
TOP 0 0.6826 3.3935 270.0 N 0 209 1
TOP 1 0.72 3.3935 270.0 N 2 436 2
TOP 2 0.7574 3.3935 270.0 N 0 210 3
TOP 3 0.7574 3.5065 270.0 N 208 3 4
TOP 4 0.72 3.5065 270.0 N 132 6 5
TOP 5 0.6826 3.5065 270.0 N 207 3 6
#
# CMP 600
CMP 66 6.26989 2.25834 90.0 N U9 ??? ;0=1,1=0.057000
PRP ALT_SYMBOLS '(SOT23_6)' 
PRP PARENT_PART_TYPE 'CL1001485A' 
PRP PARENT_PPT 'CL1001485A' 
PRP PARENT_PPT_PART 'CL1001485A-G122-00019-01' 
PRP PART_NAME 'CL1001485A' 
TOP 0 6.30729 2.31484 90.0 N 0 211 1
TOP 1 6.26989 2.31484 90.0 N 2 437 2
TOP 2 6.23249 2.31484 90.0 N 0 212 3
TOP 3 6.23249 2.20184 90.0 N 204 1 4
TOP 4 6.26989 2.20184 90.0 N 121 2 5
TOP 5 6.30729 2.20184 90.0 N 205 1 6
#
# CMP 601
CMP 67 6.121 2.815 270.0 N J10 ??? ;0=1,1=0.388190
PRP ALT_SYMBOLS '(S_M_DIL_2X5_P100_V1)' 
PRP PARENT_PART_TYPE 'G200_10283_01' 
PRP PARENT_PPT 'G200_10283_01' 
PRP PARENT_PPT_PART 'G200_10283_01-G200-10283-01' 
PRP PART_NAME 'G200_10283_01' 
TOP 0 6.22356 2.615 270.0 N 197 0 1
TOP 1 6.01844 2.615 270.0 N 198 0 2
TOP 2 6.22356 2.715 270.0 N 197 1 3
TOP 3 6.01844 2.715 270.0 N 199 1 4
TOP 4 6.22356 2.815 270.0 N 200 0 5
TOP 5 6.01844 2.815 270.0 N 201 0 6
TOP 6 6.22356 2.915 270.0 N 200 1 7
TOP 7 6.01844 2.915 270.0 N 202 1 8
TOP 8 6.22356 3.015 270.0 N 2 438 9
TOP 9 6.01844 3.015 270.0 N 203 4 10
#
# CMP 602
CMP 67 5.608 2.821 270.0 N J14 ??? ;0=1,1=0.388190
PRP ALT_SYMBOLS '(S_M_DIL_2X5_P100_V1)' 
PRP PARENT_PART_TYPE 'G200_10283_01' 
PRP PARENT_PPT 'G200_10283_01' 
PRP PARENT_PPT_PART 'G200_10283_01-G200-10283-01' 
PRP PART_NAME 'G200_10283_01' 
TOP 0 5.71056 2.621 270.0 N 141 1 1
TOP 1 5.50544 2.621 270.0 N 2 439 2
TOP 2 5.71056 2.721 270.0 N 142 1 3
TOP 3 5.50544 2.721 270.0 N 210 0 4
TOP 4 5.71056 2.821 270.0 N 139 1 5
TOP 5 5.50544 2.821 270.0 N 0 213 6
TOP 6 5.71056 2.921 270.0 N 0 214 7
TOP 7 5.50544 2.921 270.0 N 0 215 8
TOP 8 5.71056 3.021 270.0 N 140 1 9
TOP 9 5.50544 3.021 270.0 N 2 440 10
#
# CMP 603
CMP 68 6.45381 2.11024 270.0 N J11 ??? ;0=1,1=0.115160
PRP ALT_SYMBOLS '(S_F_USB_1X5_G2_GH4_RA_P0256)' 
PRP PARENT_PART_TYPE 'CONN_USB_1X5_G2_GH4_F_RA_SMT' 
PRP PARENT_PPT 'CONN_USB_1X5_G2_GH4_F_RA_SMT' 
PRP PARENT_PPT_PART 'CONN_USB_1X5_G2_GH4_F_RA_SMT-G200-12192-01,1050171001' 
PRP PART_NAME 'CONN_USB_1X5_G2_GH4_F_RA_SMT' 
TOP 0 6.4105 2.05906 270.0 N 121 3 1
TOP 1 6.4105 2.08465 270.0 N 204 2 2
TOP 2 6.4105 2.11024 270.0 N 205 2 3
TOP 3 6.4105 2.13583 270.0 N 0 216 4
TOP 4 6.4105 2.16142 270.0 N 2 441 5
TOP 5 6.51582 2.07087 270.0 N 2 442 G1
TOP 6 6.51582 2.14961 270.0 N 2 443 G2
TOP 7 6.40952 2.01181 270.0 N 2 444 GH1
TOP 8 6.40952 2.20867 270.0 N 2 445 GH2
TOP 9 6.51582 1.97244 270.0 N 2 446 GH3
TOP 10 6.51582 2.24804 270.0 N 2 447 GH4
#
# CMP 604
CMP 69 3.162 3.315 180.0 N U4 ??? ;0=1,1=0.043310
PRP ALT_SYMBOLS '(SOP16_173_P0256_H043)' 
PRP PARENT_PART_TYPE 'PCA9546APW_TSSOP16' 
PRP PARENT_PPT 'PCA9546APW_TSSOP16' 
PRP PARENT_PPT_PART 'PCA9546APW_TSSOP16-G223-10280-01' 
PRP PART_NAME 'PCA9546APW_TSSOP16' 
TOP 0 3.2815 3.22543 180.0 N 292 0 1
TOP 1 3.2815 3.25102 180.0 N 294 0 2
TOP 2 3.2815 3.27661 180.0 N 291 1 3
TOP 3 3.2815 3.3022 180.0 N 320 3 4
TOP 4 3.2815 3.3278 180.0 N 331 3 5
TOP 5 3.2815 3.35339 180.0 N 520 1 6
TOP 6 3.2815 3.37898 180.0 N 521 1 7
TOP 7 3.2815 3.40457 180.0 N 2 448 8
TOP 8 3.0425 3.40457 180.0 N 363 1 9
TOP 9 3.0425 3.37898 180.0 N 364 1 10
TOP 10 3.0425 3.35339 180.0 N 528 0 11
TOP 11 3.0425 3.3278 180.0 N 529 0 12
TOP 12 3.0425 3.3022 180.0 N 295 0 13
TOP 13 3.0425 3.27661 180.0 N 290 1 14
TOP 14 3.0425 3.25102 180.0 N 288 1 15
TOP 15 3.0425 3.22543 180.0 N 102 1 16
#
# CMP 605
CMP 70 1.79724 0.13781 0.0 N GF1 ??? ;0=1,1=0.000010
PRP ALT_SYMBOLS '(S_M_EF64_PCIE_P0394_V1)' 
PRP PARENT_PART_TYPE 'CONN_64P_GF' 
PRP PARENT_PPT 'CONN_64P_GF' 
PRP PARENT_PPT_PART 'CONN_64P_GF-S_M_EF64_PCIE_P0394_V1' 
PRP PART_NAME 'CONN_64P_GF' 
TOP 0 1.79724 0.15731 0.0 N 179 1 A1
TOP 1 1.83661 0.13781 0.0 N 133 2 A2
TOP 2 1.87598 0.13781 0.0 N 133 3 A3
TOP 3 1.91535 0.13781 0.0 N 2 449 A4
TOP 4 1.95472 0.13781 0.0 N 180 0 A5
TOP 5 1.99409 0.13781 0.0 N 181 0 A6
TOP 6 2.03346 0.13781 0.0 N 182 0 A7
TOP 7 2.07283 0.13781 0.0 N 183 0 A8
TOP 8 2.1122 0.13781 0.0 N 81 0 A9
TOP 9 2.15157 0.13781 0.0 N 81 1 A10
TOP 10 2.19094 0.13781 0.0 N 184 3 A11
TOP 11 2.30905 0.13781 0.0 N 2 450 A12
TOP 12 2.34842 0.13781 0.0 N 24 0 A13
TOP 13 2.38779 0.13781 0.0 N 34 0 A14
TOP 14 2.42716 0.13781 0.0 N 2 451 A15
TOP 15 2.46653 0.13781 0.0 N 39 0 A16
TOP 16 2.5059 0.13781 0.0 N 43 0 A17
TOP 17 2.54527 0.13781 0.0 N 2 452 A18
TOP 18 2.58464 0.13781 0.0 N 0 217 A19
TOP 19 2.62401 0.13781 0.0 N 2 453 A20
TOP 20 2.66338 0.13781 0.0 N 59 0 A21
TOP 21 2.70275 0.13781 0.0 N 68 0 A22
TOP 22 2.74212 0.13781 0.0 N 2 454 A23
TOP 23 2.78149 0.13781 0.0 N 2 455 A24
TOP 24 2.82086 0.13781 0.0 N 73 0 A25
TOP 25 2.86023 0.13781 0.0 N 96 0 A26
TOP 26 2.8996 0.13781 0.0 N 2 456 A27
TOP 27 2.93897 0.13781 0.0 N 2 457 A28
TOP 28 2.97834 0.13781 0.0 N 98 0 A29
TOP 29 3.01771 0.13781 0.0 N 100 0 A30
TOP 30 3.05708 0.13781 0.0 N 2 458 A31
TOP 31 3.09645 0.13781 0.0 N 0 218 A32
TOP 32 1.79724 0.13781 0.0 N 133 4 B1
TOP 33 1.83661 0.13781 0.0 N 133 5 B2
TOP 34 1.87598 0.13781 0.0 N 133 6 B3
TOP 35 1.91535 0.13781 0.0 N 2 459 B4
TOP 36 1.95472 0.13781 0.0 N 185 1 B5
TOP 37 1.99409 0.13781 0.0 N 186 1 B6
TOP 38 2.03346 0.13781 0.0 N 2 460 B7
TOP 39 2.07283 0.13781 0.0 N 81 2 B8
TOP 40 2.1122 0.13781 0.0 N 0 219 B9
TOP 41 2.15157 0.13781 0.0 N 80 2 B10
TOP 42 2.19094 0.13781 0.0 N 0 220 B11
TOP 43 2.30905 0.13781 0.0 N 0 221 B12
TOP 44 2.34842 0.13781 0.0 N 2 461 B13
TOP 45 2.38779 0.13781 0.0 N 187 1 B14
TOP 46 2.42716 0.13781 0.0 N 188 1 B15
TOP 47 2.46653 0.13781 0.0 N 2 462 B16
TOP 48 2.5059 0.13781 0.0 N 189 1 B17
TOP 49 2.54527 0.13781 0.0 N 2 463 B18
TOP 50 2.58464 0.13781 0.0 N 190 1 B19
TOP 51 2.62401 0.13781 0.0 N 191 1 B20
TOP 52 2.66338 0.13781 0.0 N 2 464 B21
TOP 53 2.70275 0.13781 0.0 N 2 465 B22
TOP 54 2.74212 0.13781 0.0 N 192 1 B23
TOP 55 2.78149 0.13781 0.0 N 193 1 B24
TOP 56 2.82086 0.13781 0.0 N 2 466 B25
TOP 57 2.86023 0.13781 0.0 N 2 467 B26
TOP 58 2.8996 0.13781 0.0 N 194 1 B27
TOP 59 2.93897 0.13781 0.0 N 195 1 B28
TOP 60 2.97834 0.13781 0.0 N 2 468 B29
TOP 61 3.01771 0.13781 0.0 N 0 222 B30
TOP 62 3.05708 0.15731 0.0 N 196 0 B31
TOP 63 3.09645 0.13781 0.0 N 2 469 B32
#
# CMP 606
CMP 71 1.105 4.145 0.0 N no_refdes+4 ?? ;0=1
TOP 0 1.105 4.145 0.0 N 0 223 1
#
# CMP 607
CMP 71 5.78 1.165 0.0 N no_refdes+5 ?? ;0=1
TOP 0 5.78 1.165 0.0 N 0 224 1
#
# CMP 608
CMP 71 0.95 0.845 0.0 N no_refdes+6 ?? ;0=1
TOP 0 0.95 0.845 0.0 N 0 225 1
#

### steps/pcb/layers/backdrill_l09_gnd4_bottom/tools
THICKNESS=0
USER_PARAMS=

TOOLS {
    NUM=1
    TYPE=PLATED
    TYPE2=STANDARD
    MIN_TOL=0
    MAX_TOL=0
    BIT=
    FINISH_SIZE=-9.84251968503937e-005
    DRILL_SIZE=8
}

### steps/pcb/layers/backdrill_top_l07_gnd3/tools
THICKNESS=0
USER_PARAMS=

TOOLS {
    NUM=1
    TYPE=PLATED
    TYPE2=STANDARD
    MIN_TOL=0
    MAX_TOL=0
    BIT=
    FINISH_SIZE=-9.84251968503937e-005
    DRILL_SIZE=8
}

### steps/pcb/layers/drill/tools
THICKNESS=0
USER_PARAMS=

TOOLS {
    NUM=1
    TYPE=VIA
    TYPE2=STANDARD
    MIN_TOL=8
    MAX_TOL=0
    BIT=
    FINISH_SIZE=8
    DRILL_SIZE=8
}

TOOLS {
    NUM=2
    TYPE=PLATED
    TYPE2=STANDARD
    MIN_TOL=10
    MAX_TOL=0
    BIT=
    FINISH_SIZE=10
    DRILL_SIZE=10
}

TOOLS {
    NUM=3
    TYPE=VIA
    TYPE2=STANDARD
    MIN_TOL=10
    MAX_TOL=0
    BIT=
    FINISH_SIZE=10
    DRILL_SIZE=10
}

TOOLS {
    NUM=4
    TYPE=PLATED
    TYPE2=STANDARD
    MIN_TOL=12
    MAX_TOL=0
    BIT=
    FINISH_SIZE=12
    DRILL_SIZE=12
}

TOOLS {
    NUM=5
    TYPE=PLATED
    TYPE2=STANDARD
    MIN_TOL=3
    MAX_TOL=3
    BIT=
    FINISH_SIZE=16
    DRILL_SIZE=16
}

TOOLS {
    NUM=6
    TYPE=PLATED
    TYPE2=STANDARD
    MIN_TOL=3
    MAX_TOL=3
    BIT=
    FINISH_SIZE=24
    DRILL_SIZE=24
}

TOOLS {
    NUM=7
    TYPE=PLATED
    TYPE2=STANDARD
    MIN_TOL=3
    MAX_TOL=3
    BIT=
    FINISH_SIZE=33
    DRILL_SIZE=33
}

TOOLS {
    NUM=8
    TYPE=PLATED
    TYPE2=STANDARD
    MIN_TOL=3
    MAX_TOL=3
    BIT=
    FINISH_SIZE=59
    DRILL_SIZE=59
}

TOOLS {
    NUM=9
    TYPE=PLATED
    TYPE2=STANDARD
    MIN_TOL=3
    MAX_TOL=3
    BIT=
    FINISH_SIZE=63
    DRILL_SIZE=63
}

TOOLS {
    NUM=10
    TYPE=PLATED
    TYPE2=STANDARD
    MIN_TOL=3
    MAX_TOL=3
    BIT=
    FINISH_SIZE=76
    DRILL_SIZE=76
}

TOOLS {
    NUM=11
    TYPE=PLATED
    TYPE2=STANDARD
    MIN_TOL=3
    MAX_TOL=3
    BIT=
    FINISH_SIZE=79
    DRILL_SIZE=79
}

TOOLS {
    NUM=12
    TYPE=NON_PLATED
    TYPE2=STANDARD
    MIN_TOL=2
    MAX_TOL=2
    BIT=
    FINISH_SIZE=100
    DRILL_SIZE=100
}

TOOLS {
    NUM=13
    TYPE=NON_PLATED
    TYPE2=STANDARD
    MIN_TOL=2
    MAX_TOL=2
    BIT=
    FINISH_SIZE=118
    DRILL_SIZE=118
}

TOOLS {
    NUM=14
    TYPE=NON_PLATED
    TYPE2=STANDARD
    MIN_TOL=2
    MAX_TOL=2
    BIT=
    FINISH_SIZE=125
    DRILL_SIZE=125
}

TOOLS {
    NUM=15
    TYPE=PLATED
    TYPE2=STANDARD
    MIN_TOL=3
    MAX_TOL=3
    BIT=
    FINISH_SIZE=166
    DRILL_SIZE=166
}

### steps/pcb/layers/rout/tools
THICKNESS=0
USER_PARAMS=

TOOLS {
    NUM=8191
    TYPE=NON_PLATED
    TYPE2=STANDARD
    MIN_TOL=0
    MAX_TOL=0
    BIT=
    FINISH_SIZE=0
    DRILL_SIZE=0
}

### symbols/024x051ob071x075p_l/features
#
#Num Features
#
F 1

#
#Units
#
U INCH

#
#Layer features
#
S P 0
OB 0.037990059055 -0.005 I
OC 0.0135 -0.025 0.013500098425 -0.000006003937 Y
OS 0.005 -0.025
OS 0.005 -0.02
OS 0.0135 -0.02
OC 0.03286003937 -0.005 0.0135 -0.000006299213 N
OS 0.037990059055 -0.005
OE
OB 0.037990059055 0.005 I
OS 0.03286003937 0.005
OC 0.0135 0.02 0.013500098425 0.000006397638 N
OS 0.005 0.02
OS 0.005 0.025
OS 0.0135 0.025
OC 0.037990059055 0.005 0.013500098425 0.000006003937 Y
OE
OB -0.005 -0.025 I
OS -0.0135 -0.025
OC -0.03798996063 -0.005 -0.0135 -0.000006003937 Y
OS -0.032859940945 -0.005
OC -0.0135 -0.02 -0.013499901575 -0.000006299213 N
OS -0.005 -0.02
OS -0.005 -0.025
OE
OB -0.005 0.02 I
OS -0.0135 0.02
OC -0.032859940945 0.005 -0.0135 0.000006397638 N
OS -0.03798996063 0.005
OC -0.0135 0.025 -0.0135 0.000006003937 Y
OS -0.005 0.025
OS -0.005 0.02
OE
SE

### symbols/024x051ob071x075p_r/features
#
#Num Features
#
F 1

#
#Units
#
U INCH

#
#Layer features
#
S P 0
OB 0.037990059055 -0.005 I
OC 0.0135 -0.025 0.013500098425 -0.000006003937 Y
OS 0.005 -0.025
OS 0.005 -0.02
OS 0.0135 -0.02
OC 0.03286003937 -0.005 0.0135 -0.000006299213 N
OS 0.037990059055 -0.005
OE
OB 0.037990059055 0.005 I
OS 0.03286003937 0.005
OC 0.0135 0.02 0.013500098425 0.000006397638 N
OS 0.005 0.02
OS 0.005 0.025
OS 0.0135 0.025
OC 0.037990059055 0.005 0.013500098425 0.000006003937 Y
OE
OB -0.005 -0.025 I
OS -0.0135 -0.025
OC -0.03798996063 -0.005 -0.0135 -0.000006003937 Y
OS -0.032859940945 -0.005
OC -0.0135 -0.02 -0.013499901575 -0.000006299213 N
OS -0.005 -0.02
OS -0.005 -0.025
OE
OB -0.005 0.02 I
OS -0.0135 0.02
OC -0.032859940945 0.005 -0.0135 0.000006397638 N
OS -0.03798996063 0.005
OC -0.0135 0.025 -0.0135 0.000006003937 Y
OS -0.005 0.025
OS -0.005 0.02
OE
SE

### symbols/024x063ob035x075p/features
#
#Num Features
#
F 1

#
#Units
#
U INCH

#
#Layer features
#
S P 0
OB -0.04398996063 0.005 I
OC -0.0195 0.025 -0.0195 0.000006003937 Y
OS -0.006 0.025
OS -0.006 0.02
OS -0.0195 0.02
OC -0.03886003937 0.005 -0.0195 0.000006299213 N
OS -0.04398996063 0.005
OE
OB -0.04398996063 -0.005 I
OS -0.03886003937 -0.005
OC -0.0195 -0.02 -0.019500098425 -0.000006397638 N
OS -0.006 -0.02
OS -0.006 -0.025
OS -0.0195 -0.025
OC -0.04398996063 -0.005 -0.0195 -0.000006003937 Y
OE
OB 0.006 0.025 I
OS 0.0195 0.025
OC 0.04398996063 0.005 0.0195 0.000006003937 Y
OS 0.03886003937 0.005
OC 0.0195 0.02 0.0195 0.000006299213 N
OS 0.006 0.02
OS 0.006 0.025
OE
OB 0.006 -0.02 I
OS 0.0195 -0.02
OC 0.03886003937 -0.005 0.019500098425 -0.000006397638 N
OS 0.04398996063 -0.005
OC 0.0195 -0.025 0.0195 -0.000006003937 Y
OS 0.006 -0.025
OS 0.006 -0.02
OE
SE

### symbols/sh041x021-l+1/features
#
#Num Features
#
F 1

#
#Units
#
U INCH

#
#Layer features
#
S P 0
OB -0.004519980315 0.0105 I
OS -0.004519980315 0.0015
OS 0.0205 0.0015
OS 0.0205 -0.0105
OS -0.0205 -0.0105
OS -0.0205 0.0105
OS -0.004519980315 0.0105
OE
SE

### symbols/sh041x021-l+2/features
#
#Num Features
#
F 1

#
#Units
#
U INCH

#
#Layer features
#
S P 0
OB 0.002519980315 -0.0125 I
OS 0.002519980315 -0.0035
OS -0.0225 -0.0035
OS -0.0225 0.0125
OS 0.0225 0.0125
OS 0.0225 -0.0125
OS 0.002519980315 -0.0125
OE
SE

### symbols/sh041x021-l+3/features
#
#Num Features
#
F 1

#
#Units
#
U INCH

#
#Layer features
#
S P 0
OB 0.004519980315 -0.0105 I
OS 0.004519980315 -0.0015
OS -0.0205 -0.0015
OS -0.0205 0.0105
OS 0.0205 0.0105
OS 0.0205 -0.0105
OS 0.004519980315 -0.0105
OE
SE

### symbols/sh041x021-l+4/features
#
#Num Features
#
F 1

#
#Units
#
U INCH

#
#Layer features
#
S P 0
OB -0.0125 -0.002519980315 I
OS -0.0035 -0.002519980315
OS -0.0035 0.0225
OS 0.0125 0.0225
OS 0.0125 -0.0225
OS -0.0125 -0.0225
OS -0.0125 -0.002519980315
OE
SE

### symbols/sh041x021-l+5/features
#
#Num Features
#
F 1

#
#Units
#
U INCH

#
#Layer features
#
S P 0
OB -0.0105 -0.004519980315 I
OS -0.0015 -0.004519980315
OS -0.0015 0.0205
OS 0.0105 0.0205
OS 0.0105 -0.0205
OS -0.0105 -0.0205
OS -0.0105 -0.004519980315
OE
SE

### symbols/sh041x021-l+6/features
#
#Num Features
#
F 1

#
#Units
#
U INCH

#
#Layer features
#
S P 0
OB 0.0125 0.002519980315 I
OS 0.0035 0.002519980315
OS 0.0035 -0.0225
OS -0.0125 -0.0225
OS -0.0125 0.0225
OS 0.0125 0.0225
OS 0.0125 0.002519980315
OE
SE

### symbols/sh041x021-l+7/features
#
#Num Features
#
F 1

#
#Units
#
U INCH

#
#Layer features
#
S P 0
OB 0.0105 0.004519980315 I
OS 0.0015 0.004519980315
OS 0.0015 -0.0205
OS -0.0105 -0.0205
OS -0.0105 0.0205
OS 0.0105 0.0205
OS 0.0105 0.004519980315
OE
SE

### symbols/sh041x021-l/features
#
#Num Features
#
F 1

#
#Units
#
U INCH

#
#Layer features
#
S P 0
OB -0.002519980315 0.0125 I
OS -0.002519980315 0.0035
OS 0.0225 0.0035
OS 0.0225 -0.0125
OS -0.0225 -0.0125
OS -0.0225 0.0125
OS -0.002519980315 0.0125
OE
SE

### symbols/sh041x021-r+1/features
#
#Num Features
#
F 1

#
#Units
#
U INCH

#
#Layer features
#
S P 0
OB 0.004519980315 0.0105 I
OS 0.0205 0.0105
OS 0.0205 -0.0105
OS -0.0205 -0.0105
OS -0.0205 0.0015
OS 0.004519980315 0.0015
OS 0.004519980315 0.0105
OE
SE

### symbols/sh041x021-r+2/features
#
#Num Features
#
F 1

#
#Units
#
U INCH

#
#Layer features
#
S P 0
OB -0.0225 -0.0125 I
OS -0.0225 0.0125
OS 0.0225 0.0125
OS 0.0225 -0.0035
OS -0.002519980315 -0.0035
OS -0.002519980315 -0.0125
OS -0.0225 -0.0125
OE
SE

### symbols/sh041x021-r+3/features
#
#Num Features
#
F 1

#
#Units
#
U INCH

#
#Layer features
#
S P 0
OB -0.004519980315 -0.0105 I
OS -0.0205 -0.0105
OS -0.0205 0.0105
OS 0.0205 0.0105
OS 0.0205 -0.0015
OS -0.004519980315 -0.0015
OS -0.004519980315 -0.0105
OE
SE

### symbols/sh041x021-r+4/features
#
#Num Features
#
F 1

#
#Units
#
U INCH

#
#Layer features
#
S P 0
OB 0.0125 -0.0225 I
OS -0.0125 -0.0225
OS -0.0125 0.0225
OS 0.0035 0.0225
OS 0.0035 -0.002519980315
OS 0.0125 -0.002519980315
OS 0.0125 -0.0225
OE
SE

### symbols/sh041x021-r+5/features
#
#Num Features
#
F 1

#
#Units
#
U INCH

#
#Layer features
#
S P 0
OB 0.0105 -0.004519980315 I
OS 0.0105 -0.0205
OS -0.0105 -0.0205
OS -0.0105 0.0205
OS 0.0015 0.0205
OS 0.0015 -0.004519980315
OS 0.0105 -0.004519980315
OE
SE

### symbols/sh041x021-r+6/features
#
#Num Features
#
F 1

#
#Units
#
U INCH

#
#Layer features
#
S P 0
OB -0.0125 0.0225 I
OS 0.0125 0.0225
OS 0.0125 -0.0225
OS -0.0035 -0.0225
OS -0.0035 0.002519980315
OS -0.0125 0.002519980315
OS -0.0125 0.0225
OE
SE

### symbols/sh041x021-r+7/features
#
#Num Features
#
F 1

#
#Units
#
U INCH

#
#Layer features
#
S P 0
OB -0.0105 0.004519980315 I
OS -0.0105 0.0205
OS 0.0105 0.0205
OS 0.0105 -0.0205
OS -0.0015 -0.0205
OS -0.0015 0.004519980315
OS -0.0105 0.004519980315
OE
SE

### symbols/sh041x021-r/features
#
#Num Features
#
F 1

#
#Units
#
U INCH

#
#Layer features
#
S P 0
OB 0.0225 0.0125 I
OS 0.0225 -0.0125
OS -0.0225 -0.0125
OS -0.0225 0.0035
OS 0.002519980315 0.0035
OS 0.002519980315 0.0125
OS 0.0225 0.0125
OE
SE

### symbols/sh052x046+1/features
#
#Num Features
#
F 1

#
#Units
#
U INCH

#
#Layer features
#
S P 0
OB 0.02618996063 0.02281003937 I
OS 0.02618996063 -0.02281003937
OS 0.01318996063 -0.02281003937
OS 0.01318996063 0.01295
OS -0.01318996063 0.01295
OS -0.01318996063 -0.02281003937
OS -0.02618996063 -0.02281003937
OS -0.02618996063 0.02281003937
OS 0.02618996063 0.02281003937
OE
SE

### symbols/sh052x046/features
#
#Num Features
#
F 1

#
#Units
#
U INCH

#
#Layer features
#
S P 0
OB 0.02818996063 0.02481003937 I
OS 0.02818996063 -0.02481003937
OS 0.01118996063 -0.02481003937
OS 0.01118996063 0.01095
OS -0.01118996063 0.01095
OS -0.01118996063 -0.02481003937
OS -0.02818996063 -0.02481003937
OS -0.02818996063 0.02481003937
OS 0.02818996063 0.02481003937
OE
SE

### misc/job_name
r4006-b0001-02_r01_odb

### misc/last_save
220225.181531

### misc/userattr
FORCE_LIB=NO

### symbols/024x051ob071x075p_l/attrlist
.out_break = no
.out_scale = no
.break_away = no
.comment = 
.fill_dx = 0.1
.fill_dy = 0.1
.image_dx = -1
.image_dy = -1

### symbols/024x051ob071x075p_r/attrlist
.out_break = no
.out_scale = no
.break_away = no
.comment = 
.fill_dx = 0.1
.fill_dy = 0.1
.image_dx = -1
.image_dy = -1

### symbols/024x063ob035x075p/attrlist
.out_break = no
.out_scale = no
.break_away = no
.comment = 
.fill_dx = 0.1
.fill_dy = 0.1
.image_dx = -1
.image_dy = -1

### symbols/sh041x021-l+1/attrlist
.out_break = no
.out_scale = no
.break_away = no
.comment = 
.fill_dx = 0.1
.fill_dy = 0.1
.image_dx = -1
.image_dy = -1

### symbols/sh041x021-l+2/attrlist
.out_break = no
.out_scale = no
.break_away = no
.comment = 
.fill_dx = 0.1
.fill_dy = 0.1
.image_dx = -1
.image_dy = -1

### symbols/sh041x021-l+3/attrlist
.out_break = no
.out_scale = no
.break_away = no
.comment = 
.fill_dx = 0.1
.fill_dy = 0.1
.image_dx = -1
.image_dy = -1

### symbols/sh041x021-l+4/attrlist
.out_break = no
.out_scale = no
.break_away = no
.comment = 
.fill_dx = 0.1
.fill_dy = 0.1
.image_dx = -1
.image_dy = -1

### symbols/sh041x021-l+5/attrlist
.out_break = no
.out_scale = no
.break_away = no
.comment = 
.fill_dx = 0.1
.fill_dy = 0.1
.image_dx = -1
.image_dy = -1

### symbols/sh041x021-l+6/attrlist
.out_break = no
.out_scale = no
.break_away = no
.comment = 
.fill_dx = 0.1
.fill_dy = 0.1
.image_dx = -1
.image_dy = -1

### symbols/sh041x021-l+7/attrlist
.out_break = no
.out_scale = no
.break_away = no
.comment = 
.fill_dx = 0.1
.fill_dy = 0.1
.image_dx = -1
.image_dy = -1

### symbols/sh041x021-l/attrlist
.out_break = no
.out_scale = no
.break_away = no
.comment = 
.fill_dx = 0.1
.fill_dy = 0.1
.image_dx = -1
.image_dy = -1

### symbols/sh041x021-r+1/attrlist
.out_break = no
.out_scale = no
.break_away = no
.comment = 
.fill_dx = 0.1
.fill_dy = 0.1
.image_dx = -1
.image_dy = -1

### symbols/sh041x021-r+2/attrlist
.out_break = no
.out_scale = no
.break_away = no
.comment = 
.fill_dx = 0.1
.fill_dy = 0.1
.image_dx = -1
.image_dy = -1

### symbols/sh041x021-r+3/attrlist
.out_break = no
.out_scale = no
.break_away = no
.comment = 
.fill_dx = 0.1
.fill_dy = 0.1
.image_dx = -1
.image_dy = -1

### symbols/sh041x021-r+4/attrlist
.out_break = no
.out_scale = no
.break_away = no
.comment = 
.fill_dx = 0.1
.fill_dy = 0.1
.image_dx = -1
.image_dy = -1

### symbols/sh041x021-r+5/attrlist
.out_break = no
.out_scale = no
.break_away = no
.comment = 
.fill_dx = 0.1
.fill_dy = 0.1
.image_dx = -1
.image_dy = -1

### symbols/sh041x021-r+6/attrlist
.out_break = no
.out_scale = no
.break_away = no
.comment = 
.fill_dx = 0.1
.fill_dy = 0.1
.image_dx = -1
.image_dy = -1

### symbols/sh041x021-r+7/attrlist
.out_break = no
.out_scale = no
.break_away = no
.comment = 
.fill_dx = 0.1
.fill_dy = 0.1
.image_dx = -1
.image_dy = -1

### symbols/sh041x021-r/attrlist
.out_break = no
.out_scale = no
.break_away = no
.comment = 
.fill_dx = 0.1
.fill_dy = 0.1
.image_dx = -1
.image_dy = -1

### symbols/sh052x046+1/attrlist
.out_break = no
.out_scale = no
.break_away = no
.comment = 
.fill_dx = 0.1
.fill_dy = 0.1
.image_dx = -1
.image_dy = -1

### symbols/sh052x046/attrlist
.out_break = no
.out_scale = no
.break_away = no
.comment = 
.fill_dx = 0.1
.fill_dy = 0.1
.image_dx = -1
.image_dy = -1
